(kicad_pcb
	(version 20260206)
	(generator "pcbnew")
	(generator_version "10.0")
	(general
		(thickness 1.6)
		(legacy_teardrops no)
	)
	(paper "A4")
	(layers
		(0 "F.Cu" signal "TOP")
		(4 "In1.Cu" signal "L2GND")
		(6 "In2.Cu" signal "L3")
		(8 "In3.Cu" signal "L4VCC")
		(10 "In4.Cu" signal "L5VCC")
		(12 "In5.Cu" signal "L6")
		(14 "In6.Cu" signal "L7GND")
		(2 "B.Cu" signal "BOTTOM")
		(9 "F.Adhes" user "F.Adhesive")
		(11 "B.Adhes" user "B.Adhesive")
		(13 "F.Paste" user "Package Geometry/Pastemask Top")
		(15 "B.Paste" user "Package Geometry/Pastemask Bottom")
		(5 "F.SilkS" user "Ref Des/Silkscreen Top")
		(7 "B.SilkS" user "Ref Des/Silkscreen Bottom")
		(1 "F.Mask" user "Board Geometry/Soldermask Top")
		(3 "B.Mask" user "Board Geometry/Soldermask Bottom")
		(17 "Dwgs.User" user "User.Drawings")
		(19 "Cmts.User" user "User.Comments")
		(21 "Eco1.User" user "User.Eco1")
		(23 "Eco2.User" user "User.Eco2")
		(25 "Edge.Cuts" user "Board Geometry/Outline")
		(27 "Margin" user)
		(31 "F.CrtYd" user "Package Geometry/Place Bound Top")
		(29 "B.CrtYd" user "Package Geometry/Place Bound Bottom")
		(35 "F.Fab" user "Ref Des/Assembly Top")
		(33 "B.Fab" user "Ref Des/Assembly Bottom")
	)
	(setup
		(pad_to_mask_clearance 0)
		(allow_soldermask_bridges_in_footprints no)
		(tenting
			(front yes)
			(back yes)
		)
		(covering
			(front no)
			(back no)
		)
		(plugging
			(front no)
			(back no)
		)
		(capping no)
		(filling no)
		(pcbplotparams
			(layerselection 0x00000000_00000000_55555555_5755f5ff)
			(plot_on_all_layers_selection 0x00000000_00000000_00000000_00000000)
			(disableapertmacros no)
			(usegerberextensions no)
			(usegerberattributes yes)
			(usegerberadvancedattributes yes)
			(creategerberjobfile yes)
			(dashed_line_dash_ratio 12)
			(dashed_line_gap_ratio 3)
			(svgprecision 4)
			(plotframeref no)
			(mode 1)
			(useauxorigin no)
			(pdf_front_fp_property_popups yes)
			(pdf_back_fp_property_popups yes)
			(pdf_metadata yes)
			(pdf_single_document no)
			(dxfpolygonmode yes)
			(dxfimperialunits yes)
			(dxfusepcbnewfont yes)
			(psnegative no)
			(psa4output no)
			(plot_black_and_white yes)
			(sketchpadsonfab no)
			(plotpadnumbers no)
			(hidednponfab no)
			(sketchdnponfab yes)
			(crossoutdnponfab yes)
			(subtractmaskfromsilk no)
			(outputformat 1)
			(mirror no)
			(drillshape 1)
			(scaleselection 1)
			(outputdirectory "")
		)
	)
	(footprint ""
		(layer "F.Cu")
		(at 58.70575 -123.205494)
		(property "Reference" "R510"
			(at 0 0 0)
			(layer "F.SilkS")
			(hide yes)
			(effects
				(font
					(size 1.27 1.27)
				)
			)
		)
		(property "Value" "0R5J-5-GP"
			(at 0 -8.9535 0)
			(unlocked yes)
			(layer "F.Fab")
			(hide yes)
			(effects
				(font
					(size 1.27 1.016)
					(thickness 0.1524)
				)
			)
		)
		(property "Device Type" "R805H24"
			(at 0 -10.6299 0)
			(unlocked yes)
			(layer "F.Fab")
			(hide yes)
			(effects
				(font
					(size 1.27 1.016)
					(thickness 0.1524)
				)
			)
		)
		(duplicate_pad_numbers_are_jumpers no)
		(fp_line
			(start -0.889 -1.7018)
			(end -0.889 0.2794)
			(stroke
				(width 0.1524)
				(type default)
			)
			(layer "F.SilkS")
		)
		(fp_line
			(start -0.889 0.0762)
			(end -0.889 1.7018)
			(stroke
				(width 0.1524)
				(type default)
			)
			(layer "F.SilkS")
		)
		(fp_line
			(start -0.889 1.7018)
			(end 0.889 1.7018)
			(stroke
				(width 0.1524)
				(type default)
			)
			(layer "F.SilkS")
		)
		(fp_line
			(start 0.889 -1.7018)
			(end -0.889 -1.7018)
			(stroke
				(width 0.1524)
				(type default)
			)
			(layer "F.SilkS")
		)
		(fp_line
			(start 0.889 -1.7018)
			(end 0.889 -0.381)
			(stroke
				(width 0.1524)
				(type default)
			)
			(layer "F.SilkS")
		)
		(fp_line
			(start 0.889 1.7018)
			(end 0.889 -0.508)
			(stroke
				(width 0.1524)
				(type default)
			)
			(layer "F.SilkS")
		)
		(fp_poly
			(pts
				(xy 0.9652 -1.778) (xy 0.9652 1.778) (xy -0.9652 1.778) (xy -0.9652 -1.778)
			)
			(stroke
				(width 0)
				(type default)
			)
			(fill no)
			(layer "F.CrtYd")
		)
		(fp_rect
			(start -0.9652 1.778)
			(end 0.9652 -1.778)
			(stroke
				(width 0)
				(type default)
			)
			(fill no)
			(layer "F.Fab")
		)
		(pad "1" smd rect
			(at 0 -0.9652)
			(size 1.397 1.143)
			(layers "F.Cu" "F.Mask" "F.Paste")
			(net "P3V3")
		)
		(pad "2" smd rect
			(at 0 0.9652)
			(size 1.397 1.143)
			(layers "F.Cu" "F.Mask" "F.Paste")
			(net "P3V3_OUT")
		)
	)
	(footprint ""
		(layer "F.Cu")
		(at 148.436838 -54.426104 102)
		(property "Reference" "C344"
			(at 0 0 102)
			(layer "F.SilkS")
			(hide yes)
			(effects
				(font
					(size 1.27 1.27)
				)
			)
		)
		(property "Value" "SCD01U16V1KX-GP"
			(at -2.832244 -1.740078 102)
			(unlocked yes)
			(layer "F.Fab")
			(hide yes)
			(effects
				(font
					(size 1.016 1.016)
					(thickness 0.1524)
				)
			)
		)
		(property "Device Type" "C0201H13"
			(at -2.832121 -3.264082 102)
			(unlocked yes)
			(layer "F.Fab")
			(hide yes)
			(effects
				(font
					(size 1.016 1.016)
					(thickness 0.1524)
				)
			)
		)
		(duplicate_pad_numbers_are_jumpers no)
		(fp_poly
			(pts
				(xy -0.279454 -0.647706) (xy 0.279346 -0.647706) (xy 0.279346 0.647694) (xy -0.279454 0.647694)
			)
			(stroke
				(width 0)
				(type default)
			)
			(fill no)
			(layer "F.CrtYd")
		)
		(fp_poly
			(pts
				(xy -0.279454 -0.647706) (xy 0.279346 -0.647706) (xy 0.279346 0.647694) (xy -0.279454 0.647694)
			)
			(stroke
				(width 0)
				(type default)
			)
			(fill no)
			(layer "F.Fab")
		)
		(pad "1" smd custom
			(at -0.000001 -0.2794 102)
			(size 0.0762 0.0762)
			(layers "F.Cu" "F.Mask" "F.Paste")
			(net "PHY_SCC_TO_IOC_47_DN")
			(options
				(clearance outline)
				(anchor circle)
			)
			(primitives
				(gr_poly
					(pts
						(arc
							(start 0.1524 -0.127)
							(mid 0.137521 -0.162921)
							(end 0.1016 -0.1778)
						)
						(arc
							(start -0.1016 -0.1778)
							(mid -0.137521 -0.162921)
							(end -0.1524 -0.127)
						)
						(arc
							(start -0.1524 0.127)
							(mid -0.137521 0.162921)
							(end -0.1016 0.1778)
						)
						(arc
							(start 0.1016 0.1778)
							(mid 0.137521 0.162921)
							(end 0.1524 0.127)
						)
					)
					(width 0)
					(fill yes)
				)
			)
		)
		(pad "2" smd custom
			(at 0.000001 0.2794 102)
			(size 0.0762 0.0762)
			(layers "F.Cu" "F.Mask" "F.Paste")
			(net "PHY_SCC_TO_IOC_C_47_DN")
			(options
				(clearance outline)
				(anchor circle)
			)
			(primitives
				(gr_poly
					(pts
						(arc
							(start 0.1524 -0.127)
							(mid 0.137521 -0.162921)
							(end 0.1016 -0.1778)
						)
						(arc
							(start -0.1016 -0.1778)
							(mid -0.137521 -0.162921)
							(end -0.1524 -0.127)
						)
						(arc
							(start -0.1524 0.127)
							(mid -0.137521 0.162921)
							(end -0.1016 0.1778)
						)
						(arc
							(start 0.1016 0.1778)
							(mid 0.137521 0.162921)
							(end 0.1524 0.127)
						)
					)
					(width 0)
					(fill yes)
				)
			)
		)
	)
	(footprint ""
		(layer "F.Cu")
		(at 165.4556 -90.0176 90)
		(property "Reference" "C657"
			(at 0 0 90)
			(layer "F.SilkS")
			(hide yes)
			(effects
				(font
					(size 1.27 1.27)
				)
			)
		)
		(property "Value" "SC10U16V5KX-7-GP-U"
			(at -0.0762 -6.1214 90)
			(unlocked yes)
			(layer "F.Fab")
			(hide yes)
			(effects
				(font
					(size 1.016 1.016)
					(thickness 0.1524)
				)
			)
		)
		(property "Device Type" "C805H58"
			(at -0.0762 -8.1534 90)
			(unlocked yes)
			(layer "F.Fab")
			(hide yes)
			(effects
				(font
					(size 1.016 1.016)
					(thickness 0.1524)
				)
			)
		)
		(duplicate_pad_numbers_are_jumpers no)
		(fp_line
			(start 0.635 0)
			(end -0.635 0)
			(stroke
				(width 0.508)
				(type default)
			)
			(layer "F.SilkS")
		)
		(fp_rect
			(start -0.9652 1.778)
			(end 0.9652 -1.778)
			(stroke
				(width 0)
				(type default)
			)
			(fill no)
			(layer "F.CrtYd")
		)
		(fp_poly
			(pts
				(xy -0.9652 -1.778) (xy 0.9652 -1.778) (xy 0.9652 1.778) (xy -0.9652 1.778)
			)
			(stroke
				(width 0)
				(type default)
			)
			(fill no)
			(layer "F.Fab")
		)
		(pad "1" smd rect
			(at 0 -0.9652 90)
			(size 1.397 1.143)
			(layers "F.Cu" "F.Mask" "F.Paste")
			(net "P12V_SYBY_VDD_U6")
		)
		(pad "2" smd rect
			(at 0 0.9652 90)
			(size 1.397 1.143)
			(layers "F.Cu" "F.Mask" "F.Paste")
			(net "GND")
		)
	)
	(footprint ""
		(layer "F.Cu")
		(at 143.891 -100.457)
		(property "Reference" "R134"
			(at 0 0 0)
			(layer "F.SilkS")
			(hide yes)
			(effects
				(font
					(size 1.27 1.27)
				)
			)
		)
		(property "Value" "D51R3F-2-GP"
			(at -0.0254 -2.5146 0)
			(unlocked yes)
			(layer "F.Fab")
			(hide yes)
			(effects
				(font
					(size 1.016 1.016)
					(thickness 0.1524)
				)
			)
		)
		(property "Device Type" "R603H22"
			(at -0.0254 -4.0386 0)
			(unlocked yes)
			(layer "F.Fab")
			(hide yes)
			(effects
				(font
					(size 1.016 1.016)
					(thickness 0.1524)
				)
			)
		)
		(duplicate_pad_numbers_are_jumpers no)
		(fp_line
			(start -0.4826 0)
			(end -0.2032 0)
			(stroke
				(width 0.2032)
				(type default)
			)
			(layer "F.SilkS")
		)
		(fp_line
			(start 0.2032 0)
			(end 0.4826 0)
			(stroke
				(width 0.2032)
				(type default)
			)
			(layer "F.SilkS")
		)
		(fp_rect
			(start -0.5842 1.3335)
			(end 0.5842 -1.3335)
			(stroke
				(width 0)
				(type default)
			)
			(fill no)
			(layer "F.CrtYd")
		)
		(fp_rect
			(start -0.5842 1.3335)
			(end 0.5842 -1.3335)
			(stroke
				(width 0)
				(type default)
			)
			(fill no)
			(layer "F.Fab")
		)
		(pad "1" smd custom
			(at 0 -0.762)
			(size 0.2159 0.2159)
			(layers "F.Cu" "F.Mask" "F.Paste")
			(net "P1V5_E")
			(options
				(clearance outline)
				(anchor circle)
			)
			(primitives
				(gr_poly
					(pts
						(arc
							(start -0.3302 -0.4318)
							(mid -0.402042 -0.402042)
							(end -0.4318 -0.3302)
						)
						(arc
							(start -0.4318 0.3302)
							(mid -0.402042 0.402042)
							(end -0.3302 0.4318)
						)
						(arc
							(start 0.3302 0.4318)
							(mid 0.402042 0.402042)
							(end 0.4318 0.3302)
						)
						(arc
							(start 0.4318 -0.3302)
							(mid 0.402042 -0.402042)
							(end 0.3302 -0.4318)
						)
					)
					(width 0)
					(fill yes)
				)
			)
		)
		(pad "2" smd custom
			(at 0 0.762)
			(size 0.2159 0.2159)
			(layers "F.Cu" "F.Mask" "F.Paste")
			(net "GB_VDDH")
			(options
				(clearance outline)
				(anchor circle)
			)
			(primitives
				(gr_poly
					(pts
						(arc
							(start -0.3302 -0.4318)
							(mid -0.402042 -0.402042)
							(end -0.4318 -0.3302)
						)
						(arc
							(start -0.4318 0.3302)
							(mid -0.402042 0.402042)
							(end -0.3302 0.4318)
						)
						(arc
							(start 0.3302 0.4318)
							(mid 0.402042 0.402042)
							(end 0.4318 0.3302)
						)
						(arc
							(start 0.4318 -0.3302)
							(mid 0.402042 -0.402042)
							(end 0.3302 -0.4318)
						)
					)
					(width 0)
					(fill yes)
				)
			)
		)
	)
	(footprint ""
		(layer "F.Cu")
		(at 192.791842 -24.74976)
		(property "Reference" "TP131"
			(at 0 0 0)
			(layer "F.SilkS")
			(hide yes)
			(effects
				(font
					(size 1.27 1.27)
				)
			)
		)
		(property "Value" "TPAD28-2-GP"
			(at -0.0127 -1.6637 0)
			(unlocked yes)
			(layer "F.Fab")
			(hide yes)
			(effects
				(font
					(size 1.016 1.016)
					(thickness 0.1524)
				)
			)
		)
		(property "Device Type" "TPAD28"
			(at -0.0127 -3.1877 0)
			(unlocked yes)
			(layer "F.Fab")
			(hide yes)
			(effects
				(font
					(size 1.016 1.016)
					(thickness 0.1524)
				)
			)
		)
		(duplicate_pad_numbers_are_jumpers no)
		(fp_poly
			(pts
				(arc
					(start 0.3556 0)
					(mid -0.3556 0)
					(end 0.3556 0)
				)
			)
			(stroke
				(width 0)
				(type default)
			)
			(fill no)
			(layer "F.CrtYd")
		)
		(fp_poly
			(pts
				(arc
					(start 0.6096 0)
					(mid -0.6096 0)
					(end 0.6096 0)
				)
			)
			(stroke
				(width 0)
				(type default)
			)
			(fill no)
			(layer "F.Fab")
		)
		(pad "1" smd circle
			(at 0 0)
			(size 0.7112 0.7112)
			(layers "F.Cu" "F.Mask" "F.Paste")
			(net "SYS_HALT1#")
		)
	)
	(footprint ""
		(layer "F.Cu")
		(at 142.57782 -59.940952 -90)
		(property "Reference" "C37"
			(at 0 0 270)
			(layer "F.SilkS")
			(hide yes)
			(effects
				(font
					(size 1.27 1.27)
				)
			)
		)
		(property "Value" "SCD01U16V1KX-GP"
			(at -2.8321 -1.7399 270)
			(unlocked yes)
			(layer "F.Fab")
			(hide yes)
			(effects
				(font
					(size 1.016 1.016)
					(thickness 0.1524)
				)
			)
		)
		(property "Device Type" "C0201H13"
			(at -2.8321 -3.2639 270)
			(unlocked yes)
			(layer "F.Fab")
			(hide yes)
			(effects
				(font
					(size 1.016 1.016)
					(thickness 0.1524)
				)
			)
		)
		(duplicate_pad_numbers_are_jumpers no)
		(fp_rect
			(start -0.2794 0.6477)
			(end 0.2794 -0.6477)
			(stroke
				(width 0)
				(type default)
			)
			(fill no)
			(layer "F.CrtYd")
		)
		(fp_rect
			(start -0.2794 0.6477)
			(end 0.2794 -0.6477)
			(stroke
				(width 0)
				(type default)
			)
			(fill no)
			(layer "F.Fab")
		)
		(pad "1" smd custom
			(at 0 -0.2794 270)
			(size 0.0762 0.0762)
			(layers "F.Cu" "F.Mask" "F.Paste")
			(net "PHY_IOC_TO_SCC_45_DP")
			(options
				(clearance outline)
				(anchor circle)
			)
			(primitives
				(gr_poly
					(pts
						(arc
							(start 0.1524 -0.127)
							(mid 0.137521 -0.162921)
							(end 0.1016 -0.1778)
						)
						(arc
							(start -0.1016 -0.1778)
							(mid -0.137521 -0.162921)
							(end -0.1524 -0.127)
						)
						(arc
							(start -0.1524 0.127)
							(mid -0.137521 0.162921)
							(end -0.1016 0.1778)
						)
						(arc
							(start 0.1016 0.1778)
							(mid 0.137521 0.162921)
							(end 0.1524 0.127)
						)
					)
					(width 0)
					(fill yes)
				)
			)
		)
		(pad "2" smd custom
			(at 0 0.2794 270)
			(size 0.0762 0.0762)
			(layers "F.Cu" "F.Mask" "F.Paste")
			(net "PHY_IOC_TO_SCC_C_45_DP")
			(options
				(clearance outline)
				(anchor circle)
			)
			(primitives
				(gr_poly
					(pts
						(arc
							(start 0.1524 -0.127)
							(mid 0.137521 -0.162921)
							(end 0.1016 -0.1778)
						)
						(arc
							(start -0.1016 -0.1778)
							(mid -0.137521 -0.162921)
							(end -0.1524 -0.127)
						)
						(arc
							(start -0.1524 0.127)
							(mid -0.137521 0.162921)
							(end -0.1016 0.1778)
						)
						(arc
							(start 0.1016 0.1778)
							(mid 0.137521 0.162921)
							(end 0.1524 0.127)
						)
					)
					(width 0)
					(fill yes)
				)
			)
		)
	)
	(footprint ""
		(layer "F.Cu")
		(at 166.31158 -100.67544)
		(property "Reference" "R374"
			(at 0 0 0)
			(layer "F.SilkS")
			(hide yes)
			(effects
				(font
					(size 1.27 1.27)
				)
			)
		)
		(property "Value" "4K7R2F-GP"
			(at 0.064008 -3.993896 0)
			(unlocked yes)
			(layer "F.Fab")
			(hide yes)
			(effects
				(font
					(size 1.016 1.016)
					(thickness 0.1524)
				)
			)
		)
		(property "Device Type" "R402H16"
			(at 0.064008 -5.517896 0)
			(unlocked yes)
			(layer "F.Fab")
			(hide yes)
			(effects
				(font
					(size 1.016 1.016)
					(thickness 0.1524)
				)
			)
		)
		(duplicate_pad_numbers_are_jumpers no)
		(fp_line
			(start -0.508 -0.9398)
			(end -0.508 0.9398)
			(stroke
				(width 0.1524)
				(type default)
			)
			(layer "F.SilkS")
		)
		(fp_line
			(start 0.508 -0.9398)
			(end -0.508 -0.9398)
			(stroke
				(width 0.1524)
				(type default)
			)
			(layer "F.SilkS")
		)
		(fp_rect
			(start -0.508 0.9398)
			(end 0.508 -0.9398)
			(stroke
				(width 0)
				(type default)
			)
			(fill no)
			(layer "F.CrtYd")
		)
		(fp_rect
			(start -0.508 0.9398)
			(end 0.508 -0.9398)
			(stroke
				(width 0)
				(type default)
			)
			(fill no)
			(layer "F.Fab")
		)
		(pad "1" smd custom
			(at 0 -0.4445)
			(size 0.1397 0.1397)
			(layers "F.Cu" "F.Mask" "F.Paste")
			(net "P3V3")
			(options
				(clearance outline)
				(anchor circle)
			)
			(primitives
				(gr_poly
					(pts
						(arc
							(start -0.1778 -0.2794)
							(mid -0.249642 -0.249642)
							(end -0.2794 -0.1778)
						)
						(arc
							(start -0.2794 0.1778)
							(mid -0.249642 0.249642)
							(end -0.1778 0.2794)
						)
						(arc
							(start 0.1778 0.2794)
							(mid 0.249642 0.249642)
							(end 0.2794 0.1778)
						)
						(arc
							(start 0.2794 -0.1778)
							(mid 0.249642 -0.249642)
							(end 0.1778 -0.2794)
						)
					)
					(width 0)
					(fill yes)
				)
			)
		)
		(pad "2" smd custom
			(at 0 0.4445)
			(size 0.1397 0.1397)
			(layers "F.Cu" "F.Mask" "F.Paste")
			(net "P0V975_STAT")
			(options
				(clearance outline)
				(anchor circle)
			)
			(primitives
				(gr_poly
					(pts
						(arc
							(start -0.1778 -0.2794)
							(mid -0.249642 -0.249642)
							(end -0.2794 -0.1778)
						)
						(arc
							(start -0.2794 0.1778)
							(mid -0.249642 0.249642)
							(end -0.1778 0.2794)
						)
						(arc
							(start 0.1778 0.2794)
							(mid 0.249642 0.249642)
							(end 0.2794 0.1778)
						)
						(arc
							(start 0.2794 -0.1778)
							(mid 0.249642 -0.249642)
							(end 0.1778 -0.2794)
						)
					)
					(width 0)
					(fill yes)
				)
			)
		)
	)
	(footprint ""
		(layer "F.Cu")
		(at 176.7078 -99.8347 180)
		(property "Reference" "C663"
			(at 0 0 180)
			(layer "F.SilkS")
			(hide yes)
			(effects
				(font
					(size 1.27 1.27)
				)
			)
		)
		(property "Value" "SCD1U50V3KX-GP"
			(at 0 -2.8194 180)
			(unlocked yes)
			(layer "F.Fab")
			(hide yes)
			(effects
				(font
					(size 1.016 1.016)
					(thickness 0.1524)
				)
			)
		)
		(property "Device Type" "C603H36"
			(at 0 -4.3434 180)
			(unlocked yes)
			(layer "F.Fab")
			(hide yes)
			(effects
				(font
					(size 1.016 1.016)
					(thickness 0.1524)
				)
			)
		)
		(duplicate_pad_numbers_are_jumpers no)
		(fp_line
			(start 0.508 0)
			(end -0.508 0)
			(stroke
				(width 0.2032)
				(type default)
			)
			(layer "F.SilkS")
		)
		(fp_rect
			(start -0.5842 1.3335)
			(end 0.5842 -1.3335)
			(stroke
				(width 0)
				(type default)
			)
			(fill no)
			(layer "F.CrtYd")
		)
		(fp_rect
			(start -0.5842 1.3335)
			(end 0.5842 -1.3335)
			(stroke
				(width 0)
				(type default)
			)
			(fill no)
			(layer "F.Fab")
		)
		(pad "1" smd custom
			(at 0 -0.762 180)
			(size 0.2159 0.2159)
			(layers "F.Cu" "F.Mask" "F.Paste")
			(net "VT235_VDES_RC")
			(options
				(clearance outline)
				(anchor circle)
			)
			(primitives
				(gr_poly
					(pts
						(arc
							(start -0.3302 -0.4318)
							(mid -0.402042 -0.402042)
							(end -0.4318 -0.3302)
						)
						(arc
							(start -0.4318 0.3302)
							(mid -0.402042 0.402042)
							(end -0.3302 0.4318)
						)
						(arc
							(start 0.3302 0.4318)
							(mid 0.402042 0.402042)
							(end 0.4318 0.3302)
						)
						(arc
							(start 0.4318 -0.3302)
							(mid 0.402042 -0.402042)
							(end 0.3302 -0.4318)
						)
					)
					(width 0)
					(fill yes)
				)
			)
		)
		(pad "2" smd custom
			(at 0 0.762 180)
			(size 0.2159 0.2159)
			(layers "F.Cu" "F.Mask" "F.Paste")
			(net "VT235_VDES_RCC")
			(options
				(clearance outline)
				(anchor circle)
			)
			(primitives
				(gr_poly
					(pts
						(arc
							(start -0.3302 -0.4318)
							(mid -0.402042 -0.402042)
							(end -0.4318 -0.3302)
						)
						(arc
							(start -0.4318 0.3302)
							(mid -0.402042 0.402042)
							(end -0.3302 0.4318)
						)
						(arc
							(start 0.3302 0.4318)
							(mid 0.402042 0.402042)
							(end 0.4318 0.3302)
						)
						(arc
							(start 0.4318 -0.3302)
							(mid 0.402042 -0.402042)
							(end 0.3302 -0.4318)
						)
					)
					(width 0)
					(fill yes)
				)
			)
		)
	)
	(footprint ""
		(layer "F.Cu")
		(at 19.2786 -74.0918 90)
		(property "Reference" "C530"
			(at 0 0 90)
			(layer "F.SilkS")
			(hide yes)
			(effects
				(font
					(size 1.27 1.27)
				)
			)
		)
		(property "Value" "SCD1U16V2KX-3GP"
			(at 1.1811 -2.7051 90)
			(unlocked yes)
			(layer "F.Fab")
			(hide yes)
			(effects
				(font
					(size 1.016 1.016)
					(thickness 0.1524)
				)
			)
		)
		(property "Device Type" "C402H22"
			(at 1.1811 -4.2291 90)
			(unlocked yes)
			(layer "F.Fab")
			(hide yes)
			(effects
				(font
					(size 1.016 1.016)
					(thickness 0.1524)
				)
			)
		)
		(duplicate_pad_numbers_are_jumpers no)
		(fp_rect
			(start -0.4318 0.9525)
			(end 0.4318 -0.9525)
			(stroke
				(width 0)
				(type default)
			)
			(fill no)
			(layer "F.CrtYd")
		)
		(fp_rect
			(start -0.4318 0.9525)
			(end 0.4318 -0.9525)
			(stroke
				(width 0)
				(type default)
			)
			(fill no)
			(layer "F.Fab")
		)
		(pad "1" smd custom
			(at 0 -0.4445 90)
			(size 0.1524 0.1524)
			(layers "F.Cu" "F.Mask" "F.Paste")
			(net "P3V3")
			(options
				(clearance outline)
				(anchor circle)
			)
			(primitives
				(gr_poly
					(pts
						(arc
							(start 0.3048 -0.2032)
							(mid 0.275042 -0.275042)
							(end 0.2032 -0.3048)
						)
						(arc
							(start -0.2032 -0.3048)
							(mid -0.275042 -0.275042)
							(end -0.3048 -0.2032)
						)
						(arc
							(start -0.3048 0.2032)
							(mid -0.275042 0.275042)
							(end -0.2032 0.3048)
						)
						(arc
							(start 0.2032 0.3048)
							(mid 0.275042 0.275042)
							(end 0.3048 0.2032)
						)
					)
					(width 0)
					(fill yes)
				)
			)
		)
		(pad "2" smd custom
			(at 0 0.4445 90)
			(size 0.1524 0.1524)
			(layers "F.Cu" "F.Mask" "F.Paste")
			(net "GND")
			(options
				(clearance outline)
				(anchor circle)
			)
			(primitives
				(gr_poly
					(pts
						(arc
							(start 0.3048 -0.2032)
							(mid 0.275042 -0.275042)
							(end 0.2032 -0.3048)
						)
						(arc
							(start -0.2032 -0.3048)
							(mid -0.275042 -0.275042)
							(end -0.3048 -0.2032)
						)
						(arc
							(start -0.3048 0.2032)
							(mid -0.275042 0.275042)
							(end -0.2032 0.3048)
						)
						(arc
							(start 0.2032 0.3048)
							(mid 0.275042 0.275042)
							(end 0.3048 0.2032)
						)
					)
					(width 0)
					(fill yes)
				)
			)
		)
	)
	(footprint ""
		(layer "F.Cu")
		(at 70.440804 -70.696582 -90)
		(property "Reference" "C559"
			(at 0 0 270)
			(layer "F.SilkS")
			(hide yes)
			(effects
				(font
					(size 1.27 1.27)
				)
			)
		)
		(property "Value" "SCD1U16V2KX-3GP"
			(at 1.1811 -2.7051 270)
			(unlocked yes)
			(layer "F.Fab")
			(hide yes)
			(effects
				(font
					(size 1.016 1.016)
					(thickness 0.1524)
				)
			)
		)
		(property "Device Type" "C402H22"
			(at 1.1811 -4.2291 270)
			(unlocked yes)
			(layer "F.Fab")
			(hide yes)
			(effects
				(font
					(size 1.016 1.016)
					(thickness 0.1524)
				)
			)
		)
		(duplicate_pad_numbers_are_jumpers no)
		(fp_rect
			(start -0.4318 0.9525)
			(end 0.4318 -0.9525)
			(stroke
				(width 0)
				(type default)
			)
			(fill no)
			(layer "F.CrtYd")
		)
		(fp_rect
			(start -0.4318 0.9525)
			(end 0.4318 -0.9525)
			(stroke
				(width 0)
				(type default)
			)
			(fill no)
			(layer "F.Fab")
		)
		(pad "1" smd custom
			(at 0 -0.4445 270)
			(size 0.1524 0.1524)
			(layers "F.Cu" "F.Mask" "F.Paste")
			(net "VREF6")
			(options
				(clearance outline)
				(anchor circle)
			)
			(primitives
				(gr_poly
					(pts
						(arc
							(start 0.3048 -0.2032)
							(mid 0.275042 -0.275042)
							(end 0.2032 -0.3048)
						)
						(arc
							(start -0.2032 -0.3048)
							(mid -0.275042 -0.275042)
							(end -0.3048 -0.2032)
						)
						(arc
							(start -0.3048 0.2032)
							(mid -0.275042 0.275042)
							(end -0.2032 0.3048)
						)
						(arc
							(start 0.2032 0.3048)
							(mid 0.275042 0.275042)
							(end 0.3048 0.2032)
						)
					)
					(width 0)
					(fill yes)
				)
			)
		)
		(pad "2" smd custom
			(at 0 0.4445 270)
			(size 0.1524 0.1524)
			(layers "F.Cu" "F.Mask" "F.Paste")
			(net "GND")
			(options
				(clearance outline)
				(anchor circle)
			)
			(primitives
				(gr_poly
					(pts
						(arc
							(start 0.3048 -0.2032)
							(mid 0.275042 -0.275042)
							(end 0.2032 -0.3048)
						)
						(arc
							(start -0.2032 -0.3048)
							(mid -0.275042 -0.275042)
							(end -0.3048 -0.2032)
						)
						(arc
							(start -0.3048 0.2032)
							(mid -0.275042 0.275042)
							(end -0.2032 0.3048)
						)
						(arc
							(start 0.2032 0.3048)
							(mid 0.275042 0.275042)
							(end 0.3048 0.2032)
						)
					)
					(width 0)
					(fill yes)
				)
			)
		)
	)
	(footprint ""
		(layer "F.Cu")
		(at 14.378178 -43.193208 180)
		(property "Reference" "R519"
			(at 0 0 180)
			(layer "F.SilkS")
			(hide yes)
			(effects
				(font
					(size 1.27 1.27)
				)
			)
		)
		(property "Value" "10R2F-L-GP"
			(at 0.064008 -3.993896 180)
			(unlocked yes)
			(layer "F.Fab")
			(hide yes)
			(effects
				(font
					(size 1.016 1.016)
					(thickness 0.1524)
				)
			)
		)
		(property "Device Type" "R402H14"
			(at 0.064008 -5.517896 180)
			(unlocked yes)
			(layer "F.Fab")
			(hide yes)
			(effects
				(font
					(size 1.016 1.016)
					(thickness 0.1524)
				)
			)
		)
		(duplicate_pad_numbers_are_jumpers no)
		(fp_line
			(start 0.508 -0.9398)
			(end -0.508 -0.9398)
			(stroke
				(width 0.1524)
				(type default)
			)
			(layer "F.SilkS")
		)
		(fp_line
			(start -0.508 -0.9398)
			(end -0.508 0.9398)
			(stroke
				(width 0.1524)
				(type default)
			)
			(layer "F.SilkS")
		)
		(fp_rect
			(start -0.508 0.9398)
			(end 0.508 -0.9398)
			(stroke
				(width 0)
				(type default)
			)
			(fill no)
			(layer "F.CrtYd")
		)
		(fp_rect
			(start -0.508 0.9398)
			(end 0.508 -0.9398)
			(stroke
				(width 0)
				(type default)
			)
			(fill no)
			(layer "F.Fab")
		)
		(pad "1" smd custom
			(at 0 -0.4445 180)
			(size 0.1397 0.1397)
			(layers "F.Cu" "F.Mask" "F.Paste")
			(net "MB0_CM_SENSE_R1_P")
			(options
				(clearance outline)
				(anchor circle)
			)
			(primitives
				(gr_poly
					(pts
						(arc
							(start -0.1778 -0.2794)
							(mid -0.249642 -0.249642)
							(end -0.2794 -0.1778)
						)
						(arc
							(start -0.2794 0.1778)
							(mid -0.249642 0.249642)
							(end -0.1778 0.2794)
						)
						(arc
							(start 0.1778 0.2794)
							(mid 0.249642 0.249642)
							(end 0.2794 0.1778)
						)
						(arc
							(start 0.2794 -0.1778)
							(mid 0.249642 -0.249642)
							(end 0.1778 -0.2794)
						)
					)
					(width 0)
					(fill yes)
				)
			)
		)
		(pad "2" smd custom
			(at 0 0.4445 180)
			(size 0.1397 0.1397)
			(layers "F.Cu" "F.Mask" "F.Paste")
			(net "MB0_CM_SENSE_P")
			(options
				(clearance outline)
				(anchor circle)
			)
			(primitives
				(gr_poly
					(pts
						(arc
							(start -0.1778 -0.2794)
							(mid -0.249642 -0.249642)
							(end -0.2794 -0.1778)
						)
						(arc
							(start -0.2794 0.1778)
							(mid -0.249642 0.249642)
							(end -0.1778 0.2794)
						)
						(arc
							(start 0.1778 0.2794)
							(mid 0.249642 0.249642)
							(end 0.2794 0.1778)
						)
						(arc
							(start 0.2794 -0.1778)
							(mid 0.249642 -0.249642)
							(end 0.1778 -0.2794)
						)
					)
					(width 0)
					(fill yes)
				)
			)
		)
	)
	(footprint ""
		(layer "F.Cu")
		(at 109.7788 -86.741)
		(property "Reference" "TP52"
			(at 0 0 0)
			(layer "F.SilkS")
			(hide yes)
			(effects
				(font
					(size 1.27 1.27)
				)
			)
		)
		(property "Value" "TPAD28-2-GP"
			(at -0.0127 -1.6637 0)
			(unlocked yes)
			(layer "F.Fab")
			(hide yes)
			(effects
				(font
					(size 1.016 1.016)
					(thickness 0.1524)
				)
			)
		)
		(property "Device Type" "TPAD28"
			(at -0.0127 -3.1877 0)
			(unlocked yes)
			(layer "F.Fab")
			(hide yes)
			(effects
				(font
					(size 1.016 1.016)
					(thickness 0.1524)
				)
			)
		)
		(duplicate_pad_numbers_are_jumpers no)
		(fp_poly
			(pts
				(arc
					(start 0.3556 0)
					(mid -0.3556 0)
					(end 0.3556 0)
				)
			)
			(stroke
				(width 0)
				(type default)
			)
			(fill no)
			(layer "F.CrtYd")
		)
		(fp_poly
			(pts
				(arc
					(start 0.6096 0)
					(mid -0.6096 0)
					(end 0.6096 0)
				)
			)
			(stroke
				(width 0)
				(type default)
			)
			(fill no)
			(layer "F.Fab")
		)
		(pad "1" smd circle
			(at 0 0)
			(size 0.7112 0.7112)
			(layers "F.Cu" "F.Mask" "F.Paste")
			(net "XM_WBE_0#_TP")
		)
	)
	(footprint ""
		(layer "F.Cu")
		(at 65.278 -22.86 -90)
		(property "Reference" "R574"
			(at 0 0 270)
			(layer "F.SilkS")
			(hide yes)
			(effects
				(font
					(size 1.27 1.27)
				)
			)
		)
		(property "Value" "0R2J-2-GP"
			(at 0.064008 -3.993896 270)
			(unlocked yes)
			(layer "F.Fab")
			(hide yes)
			(effects
				(font
					(size 1.016 1.016)
					(thickness 0.1524)
				)
			)
		)
		(property "Device Type" "R402H16"
			(at 0.064008 -5.517896 270)
			(unlocked yes)
			(layer "F.Fab")
			(hide yes)
			(effects
				(font
					(size 1.016 1.016)
					(thickness 0.1524)
				)
			)
		)
		(duplicate_pad_numbers_are_jumpers no)
		(fp_line
			(start -0.508 -0.9398)
			(end -0.508 0.9398)
			(stroke
				(width 0.1524)
				(type default)
			)
			(layer "F.SilkS")
		)
		(fp_line
			(start 0.508 -0.9398)
			(end -0.508 -0.9398)
			(stroke
				(width 0.1524)
				(type default)
			)
			(layer "F.SilkS")
		)
		(fp_rect
			(start -0.508 0.9398)
			(end 0.508 -0.9398)
			(stroke
				(width 0)
				(type default)
			)
			(fill no)
			(layer "F.CrtYd")
		)
		(fp_rect
			(start -0.508 0.9398)
			(end 0.508 -0.9398)
			(stroke
				(width 0)
				(type default)
			)
			(fill no)
			(layer "F.Fab")
		)
		(pad "1" smd custom
			(at 0 -0.4445 270)
			(size 0.1397 0.1397)
			(layers "F.Cu" "F.Mask" "F.Paste")
			(net "SCC_STBY_PGOOD_U49")
			(options
				(clearance outline)
				(anchor circle)
			)
			(primitives
				(gr_poly
					(pts
						(arc
							(start -0.1778 -0.2794)
							(mid -0.249642 -0.249642)
							(end -0.2794 -0.1778)
						)
						(arc
							(start -0.2794 0.1778)
							(mid -0.249642 0.249642)
							(end -0.1778 0.2794)
						)
						(arc
							(start 0.1778 0.2794)
							(mid 0.249642 0.249642)
							(end 0.2794 0.1778)
						)
						(arc
							(start 0.2794 -0.1778)
							(mid 0.249642 -0.249642)
							(end 0.1778 -0.2794)
						)
					)
					(width 0)
					(fill yes)
				)
			)
		)
		(pad "2" smd custom
			(at 0 0.4445 270)
			(size 0.1397 0.1397)
			(layers "F.Cu" "F.Mask" "F.Paste")
			(net "SCC_FULL_PWR_EN_U49")
			(options
				(clearance outline)
				(anchor circle)
			)
			(primitives
				(gr_poly
					(pts
						(arc
							(start -0.1778 -0.2794)
							(mid -0.249642 -0.249642)
							(end -0.2794 -0.1778)
						)
						(arc
							(start -0.2794 0.1778)
							(mid -0.249642 0.249642)
							(end -0.1778 0.2794)
						)
						(arc
							(start 0.1778 0.2794)
							(mid 0.249642 0.249642)
							(end 0.2794 0.1778)
						)
						(arc
							(start 0.2794 -0.1778)
							(mid 0.249642 -0.249642)
							(end 0.1778 -0.2794)
						)
					)
					(width 0)
					(fill yes)
				)
			)
		)
	)
	(footprint ""
		(layer "F.Cu")
		(at 15.0114 -102.4001 -90)
		(property "Reference" "R528"
			(at 0 0 270)
			(layer "F.SilkS")
			(hide yes)
			(effects
				(font
					(size 1.27 1.27)
				)
			)
		)
		(property "Value" "10KR2F-2-GP"
			(at 0.064008 -3.993896 270)
			(unlocked yes)
			(layer "F.Fab")
			(hide yes)
			(effects
				(font
					(size 1.016 1.016)
					(thickness 0.1524)
				)
			)
		)
		(property "Device Type" "R402H16"
			(at 0.064008 -5.517896 270)
			(unlocked yes)
			(layer "F.Fab")
			(hide yes)
			(effects
				(font
					(size 1.016 1.016)
					(thickness 0.1524)
				)
			)
		)
		(duplicate_pad_numbers_are_jumpers no)
		(fp_line
			(start -0.508 -0.9398)
			(end -0.508 0.9398)
			(stroke
				(width 0.1524)
				(type default)
			)
			(layer "F.SilkS")
		)
		(fp_line
			(start 0.508 -0.9398)
			(end -0.508 -0.9398)
			(stroke
				(width 0.1524)
				(type default)
			)
			(layer "F.SilkS")
		)
		(fp_rect
			(start -0.508 0.9398)
			(end 0.508 -0.9398)
			(stroke
				(width 0)
				(type default)
			)
			(fill no)
			(layer "F.CrtYd")
		)
		(fp_rect
			(start -0.508 0.9398)
			(end 0.508 -0.9398)
			(stroke
				(width 0)
				(type default)
			)
			(fill no)
			(layer "F.Fab")
		)
		(pad "1" smd custom
			(at 0 -0.4445 270)
			(size 0.1397 0.1397)
			(layers "F.Cu" "F.Mask" "F.Paste")
			(net "U119_EN")
			(options
				(clearance outline)
				(anchor circle)
			)
			(primitives
				(gr_poly
					(pts
						(arc
							(start -0.1778 -0.2794)
							(mid -0.249642 -0.249642)
							(end -0.2794 -0.1778)
						)
						(arc
							(start -0.2794 0.1778)
							(mid -0.249642 0.249642)
							(end -0.1778 0.2794)
						)
						(arc
							(start 0.1778 0.2794)
							(mid 0.249642 0.249642)
							(end 0.2794 0.1778)
						)
						(arc
							(start 0.2794 -0.1778)
							(mid 0.249642 -0.249642)
							(end 0.1778 -0.2794)
						)
					)
					(width 0)
					(fill yes)
				)
			)
		)
		(pad "2" smd custom
			(at 0 0.4445 270)
			(size 0.1397 0.1397)
			(layers "F.Cu" "F.Mask" "F.Paste")
			(net "P3V3")
			(options
				(clearance outline)
				(anchor circle)
			)
			(primitives
				(gr_poly
					(pts
						(arc
							(start -0.1778 -0.2794)
							(mid -0.249642 -0.249642)
							(end -0.2794 -0.1778)
						)
						(arc
							(start -0.2794 0.1778)
							(mid -0.249642 0.249642)
							(end -0.1778 0.2794)
						)
						(arc
							(start 0.1778 0.2794)
							(mid 0.249642 0.249642)
							(end 0.2794 0.1778)
						)
						(arc
							(start 0.2794 -0.1778)
							(mid 0.249642 -0.249642)
							(end 0.1778 -0.2794)
						)
					)
					(width 0)
					(fill yes)
				)
			)
		)
	)
	(footprint ""
		(layer "F.Cu")
		(at 94.615 -75.9968 90)
		(property "Reference" "R124"
			(at 0 0 90)
			(layer "F.SilkS")
			(hide yes)
			(effects
				(font
					(size 1.27 1.27)
				)
			)
		)
		(property "Value" "4K75R2F-1-GP"
			(at 0.064008 -3.993896 90)
			(unlocked yes)
			(layer "F.Fab")
			(hide yes)
			(effects
				(font
					(size 1.016 1.016)
					(thickness 0.1524)
				)
			)
		)
		(property "Device Type" "R402H16"
			(at 0.064008 -5.517896 90)
			(unlocked yes)
			(layer "F.Fab")
			(hide yes)
			(effects
				(font
					(size 1.016 1.016)
					(thickness 0.1524)
				)
			)
		)
		(duplicate_pad_numbers_are_jumpers no)
		(fp_line
			(start 0.508 -0.9398)
			(end -0.508 -0.9398)
			(stroke
				(width 0.1524)
				(type default)
			)
			(layer "F.SilkS")
		)
		(fp_line
			(start -0.508 -0.9398)
			(end -0.508 0.9398)
			(stroke
				(width 0.1524)
				(type default)
			)
			(layer "F.SilkS")
		)
		(fp_rect
			(start -0.508 0.9398)
			(end 0.508 -0.9398)
			(stroke
				(width 0)
				(type default)
			)
			(fill no)
			(layer "F.CrtYd")
		)
		(fp_rect
			(start -0.508 0.9398)
			(end 0.508 -0.9398)
			(stroke
				(width 0)
				(type default)
			)
			(fill no)
			(layer "F.Fab")
		)
		(pad "1" smd custom
			(at 0 -0.4445 90)
			(size 0.1397 0.1397)
			(layers "F.Cu" "F.Mask" "F.Paste")
			(net "EXP_CLK_SEL0")
			(options
				(clearance outline)
				(anchor circle)
			)
			(primitives
				(gr_poly
					(pts
						(arc
							(start -0.1778 -0.2794)
							(mid -0.249642 -0.249642)
							(end -0.2794 -0.1778)
						)
						(arc
							(start -0.2794 0.1778)
							(mid -0.249642 0.249642)
							(end -0.1778 0.2794)
						)
						(arc
							(start 0.1778 0.2794)
							(mid 0.249642 0.249642)
							(end 0.2794 0.1778)
						)
						(arc
							(start 0.2794 -0.1778)
							(mid 0.249642 -0.249642)
							(end 0.1778 -0.2794)
						)
					)
					(width 0)
					(fill yes)
				)
			)
		)
		(pad "2" smd custom
			(at 0 0.4445 90)
			(size 0.1397 0.1397)
			(layers "F.Cu" "F.Mask" "F.Paste")
			(net "GND")
			(options
				(clearance outline)
				(anchor circle)
			)
			(primitives
				(gr_poly
					(pts
						(arc
							(start -0.1778 -0.2794)
							(mid -0.249642 -0.249642)
							(end -0.2794 -0.1778)
						)
						(arc
							(start -0.2794 0.1778)
							(mid -0.249642 0.249642)
							(end -0.1778 0.2794)
						)
						(arc
							(start 0.1778 0.2794)
							(mid 0.249642 0.249642)
							(end 0.2794 0.1778)
						)
						(arc
							(start 0.2794 -0.1778)
							(mid 0.249642 -0.249642)
							(end 0.1778 -0.2794)
						)
					)
					(width 0)
					(fill yes)
				)
			)
		)
	)
	(footprint ""
		(layer "F.Cu")
		(at 132.588 -89.7001 180)
		(property "Reference" "R39"
			(at 0 0 180)
			(layer "F.SilkS")
			(hide yes)
			(effects
				(font
					(size 1.27 1.27)
				)
			)
		)
		(property "Value" "4K7R2F-GP"
			(at 0.064008 -3.993896 180)
			(unlocked yes)
			(layer "F.Fab")
			(hide yes)
			(effects
				(font
					(size 1.016 1.016)
					(thickness 0.1524)
				)
			)
		)
		(property "Device Type" "R402H16"
			(at 0.064008 -5.517896 180)
			(unlocked yes)
			(layer "F.Fab")
			(hide yes)
			(effects
				(font
					(size 1.016 1.016)
					(thickness 0.1524)
				)
			)
		)
		(duplicate_pad_numbers_are_jumpers no)
		(fp_line
			(start 0.508 -0.9398)
			(end -0.508 -0.9398)
			(stroke
				(width 0.1524)
				(type default)
			)
			(layer "F.SilkS")
		)
		(fp_line
			(start -0.508 -0.9398)
			(end -0.508 0.9398)
			(stroke
				(width 0.1524)
				(type default)
			)
			(layer "F.SilkS")
		)
		(fp_rect
			(start -0.508 0.9398)
			(end 0.508 -0.9398)
			(stroke
				(width 0)
				(type default)
			)
			(fill no)
			(layer "F.CrtYd")
		)
		(fp_rect
			(start -0.508 0.9398)
			(end 0.508 -0.9398)
			(stroke
				(width 0)
				(type default)
			)
			(fill no)
			(layer "F.Fab")
		)
		(pad "1" smd custom
			(at 0 -0.4445 180)
			(size 0.1397 0.1397)
			(layers "F.Cu" "F.Mask" "F.Paste")
			(net "EXP_SIO_D_IN")
			(options
				(clearance outline)
				(anchor circle)
			)
			(primitives
				(gr_poly
					(pts
						(arc
							(start -0.1778 -0.2794)
							(mid -0.249642 -0.249642)
							(end -0.2794 -0.1778)
						)
						(arc
							(start -0.2794 0.1778)
							(mid -0.249642 0.249642)
							(end -0.1778 0.2794)
						)
						(arc
							(start 0.1778 0.2794)
							(mid 0.249642 0.249642)
							(end 0.2794 0.1778)
						)
						(arc
							(start 0.2794 -0.1778)
							(mid 0.249642 -0.249642)
							(end 0.1778 -0.2794)
						)
					)
					(width 0)
					(fill yes)
				)
			)
		)
		(pad "2" smd custom
			(at 0 0.4445 180)
			(size 0.1397 0.1397)
			(layers "F.Cu" "F.Mask" "F.Paste")
			(net "P1V8_E")
			(options
				(clearance outline)
				(anchor circle)
			)
			(primitives
				(gr_poly
					(pts
						(arc
							(start -0.1778 -0.2794)
							(mid -0.249642 -0.249642)
							(end -0.2794 -0.1778)
						)
						(arc
							(start -0.2794 0.1778)
							(mid -0.249642 0.249642)
							(end -0.1778 0.2794)
						)
						(arc
							(start 0.1778 0.2794)
							(mid 0.249642 0.249642)
							(end 0.2794 0.1778)
						)
						(arc
							(start 0.2794 -0.1778)
							(mid 0.249642 -0.249642)
							(end 0.1778 -0.2794)
						)
					)
					(width 0)
					(fill yes)
				)
			)
		)
	)
	(footprint ""
		(layer "F.Cu")
		(at 88.543638 -53.68036)
		(property "Reference" "R121"
			(at 0 0 0)
			(layer "F.SilkS")
			(hide yes)
			(effects
				(font
					(size 1.27 1.27)
				)
			)
		)
		(property "Value" "0R2J-2-GP"
			(at 0.064008 -3.993896 0)
			(unlocked yes)
			(layer "F.Fab")
			(hide yes)
			(effects
				(font
					(size 1.016 1.016)
					(thickness 0.1524)
				)
			)
		)
		(property "Device Type" "R402H16"
			(at 0.064008 -5.517896 0)
			(unlocked yes)
			(layer "F.Fab")
			(hide yes)
			(effects
				(font
					(size 1.016 1.016)
					(thickness 0.1524)
				)
			)
		)
		(duplicate_pad_numbers_are_jumpers no)
		(fp_line
			(start -0.508 -0.9398)
			(end -0.508 0.9398)
			(stroke
				(width 0.1524)
				(type default)
			)
			(layer "F.SilkS")
		)
		(fp_line
			(start 0.508 -0.9398)
			(end -0.508 -0.9398)
			(stroke
				(width 0.1524)
				(type default)
			)
			(layer "F.SilkS")
		)
		(fp_rect
			(start -0.508 0.9398)
			(end 0.508 -0.9398)
			(stroke
				(width 0)
				(type default)
			)
			(fill no)
			(layer "F.CrtYd")
		)
		(fp_rect
			(start -0.508 0.9398)
			(end 0.508 -0.9398)
			(stroke
				(width 0)
				(type default)
			)
			(fill no)
			(layer "F.Fab")
		)
		(pad "1" smd custom
			(at 0 -0.4445)
			(size 0.1397 0.1397)
			(layers "F.Cu" "F.Mask" "F.Paste")
			(net "EXP_REF_CLK_N")
			(options
				(clearance outline)
				(anchor circle)
			)
			(primitives
				(gr_poly
					(pts
						(arc
							(start -0.1778 -0.2794)
							(mid -0.249642 -0.249642)
							(end -0.2794 -0.1778)
						)
						(arc
							(start -0.2794 0.1778)
							(mid -0.249642 0.249642)
							(end -0.1778 0.2794)
						)
						(arc
							(start 0.1778 0.2794)
							(mid 0.249642 0.249642)
							(end 0.2794 0.1778)
						)
						(arc
							(start 0.2794 -0.1778)
							(mid 0.249642 -0.249642)
							(end 0.1778 -0.2794)
						)
					)
					(width 0)
					(fill yes)
				)
			)
		)
		(pad "2" smd custom
			(at 0 0.4445)
			(size 0.1397 0.1397)
			(layers "F.Cu" "F.Mask" "F.Paste")
			(net "EXP_REF_CLK_R_N")
			(options
				(clearance outline)
				(anchor circle)
			)
			(primitives
				(gr_poly
					(pts
						(arc
							(start -0.1778 -0.2794)
							(mid -0.249642 -0.249642)
							(end -0.2794 -0.1778)
						)
						(arc
							(start -0.2794 0.1778)
							(mid -0.249642 0.249642)
							(end -0.1778 0.2794)
						)
						(arc
							(start 0.1778 0.2794)
							(mid 0.249642 0.249642)
							(end 0.2794 0.1778)
						)
						(arc
							(start 0.2794 -0.1778)
							(mid 0.249642 -0.249642)
							(end 0.1778 -0.2794)
						)
					)
					(width 0)
					(fill yes)
				)
			)
		)
	)
	(footprint ""
		(layer "F.Cu")
		(at 7.366 -80.899 -90)
		(property "Reference" "R344"
			(at 0 0 270)
			(layer "F.SilkS")
			(hide yes)
			(effects
				(font
					(size 1.27 1.27)
				)
			)
		)
		(property "Value" "4K7R2F-GP"
			(at 0.064008 -3.993896 270)
			(unlocked yes)
			(layer "F.Fab")
			(hide yes)
			(effects
				(font
					(size 1.016 1.016)
					(thickness 0.1524)
				)
			)
		)
		(property "Device Type" "R402H16"
			(at 0.064008 -5.517896 270)
			(unlocked yes)
			(layer "F.Fab")
			(hide yes)
			(effects
				(font
					(size 1.016 1.016)
					(thickness 0.1524)
				)
			)
		)
		(duplicate_pad_numbers_are_jumpers no)
		(fp_line
			(start -0.508 -0.9398)
			(end -0.508 0.9398)
			(stroke
				(width 0.1524)
				(type default)
			)
			(layer "F.SilkS")
		)
		(fp_line
			(start 0.508 -0.9398)
			(end -0.508 -0.9398)
			(stroke
				(width 0.1524)
				(type default)
			)
			(layer "F.SilkS")
		)
		(fp_rect
			(start -0.508 0.9398)
			(end 0.508 -0.9398)
			(stroke
				(width 0)
				(type default)
			)
			(fill no)
			(layer "F.CrtYd")
		)
		(fp_rect
			(start -0.508 0.9398)
			(end 0.508 -0.9398)
			(stroke
				(width 0)
				(type default)
			)
			(fill no)
			(layer "F.Fab")
		)
		(pad "1" smd custom
			(at 0 -0.4445 270)
			(size 0.1397 0.1397)
			(layers "F.Cu" "F.Mask" "F.Paste")
			(net "EXP_EEPROM_A0")
			(options
				(clearance outline)
				(anchor circle)
			)
			(primitives
				(gr_poly
					(pts
						(arc
							(start -0.1778 -0.2794)
							(mid -0.249642 -0.249642)
							(end -0.2794 -0.1778)
						)
						(arc
							(start -0.2794 0.1778)
							(mid -0.249642 0.249642)
							(end -0.1778 0.2794)
						)
						(arc
							(start 0.1778 0.2794)
							(mid 0.249642 0.249642)
							(end 0.2794 0.1778)
						)
						(arc
							(start 0.2794 -0.1778)
							(mid 0.249642 -0.249642)
							(end 0.1778 -0.2794)
						)
					)
					(width 0)
					(fill yes)
				)
			)
		)
		(pad "2" smd custom
			(at 0 0.4445 270)
			(size 0.1397 0.1397)
			(layers "F.Cu" "F.Mask" "F.Paste")
			(net "GND")
			(options
				(clearance outline)
				(anchor circle)
			)
			(primitives
				(gr_poly
					(pts
						(arc
							(start -0.1778 -0.2794)
							(mid -0.249642 -0.249642)
							(end -0.2794 -0.1778)
						)
						(arc
							(start -0.2794 0.1778)
							(mid -0.249642 0.249642)
							(end -0.1778 0.2794)
						)
						(arc
							(start 0.1778 0.2794)
							(mid 0.249642 0.249642)
							(end 0.2794 0.1778)
						)
						(arc
							(start 0.2794 -0.1778)
							(mid 0.249642 -0.249642)
							(end 0.1778 -0.2794)
						)
					)
					(width 0)
					(fill yes)
				)
			)
		)
	)
	(footprint ""
		(layer "F.Cu")
		(at 175.7934 -77.8002 90)
		(property "Reference" "C384"
			(at 0 0 90)
			(layer "F.SilkS")
			(hide yes)
			(effects
				(font
					(size 1.27 1.27)
				)
			)
		)
		(property "Value" "SC22U6D3V3MX-9-GP-U"
			(at 0 -2.8194 90)
			(unlocked yes)
			(layer "F.Fab")
			(hide yes)
			(effects
				(font
					(size 1.016 1.016)
					(thickness 0.1524)
				)
			)
		)
		(property "Device Type" "C603H40"
			(at 0 -4.3434 90)
			(unlocked yes)
			(layer "F.Fab")
			(hide yes)
			(effects
				(font
					(size 1.016 1.016)
					(thickness 0.1524)
				)
			)
		)
		(duplicate_pad_numbers_are_jumpers no)
		(fp_line
			(start 0.508 0)
			(end -0.508 0)
			(stroke
				(width 0.2032)
				(type default)
			)
			(layer "F.SilkS")
		)
		(fp_rect
			(start -0.5842 1.3335)
			(end 0.5842 -1.3335)
			(stroke
				(width 0)
				(type default)
			)
			(fill no)
			(layer "F.CrtYd")
		)
		(fp_rect
			(start -0.5842 1.3335)
			(end 0.5842 -1.3335)
			(stroke
				(width 0)
				(type default)
			)
			(fill no)
			(layer "F.Fab")
		)
		(pad "1" smd custom
			(at 0 -0.762 90)
			(size 0.2159 0.2159)
			(layers "F.Cu" "F.Mask" "F.Paste")
			(net "PCE_AVDD")
			(options
				(clearance outline)
				(anchor circle)
			)
			(primitives
				(gr_poly
					(pts
						(arc
							(start -0.3302 -0.4318)
							(mid -0.402042 -0.402042)
							(end -0.4318 -0.3302)
						)
						(arc
							(start -0.4318 0.3302)
							(mid -0.402042 0.402042)
							(end -0.3302 0.4318)
						)
						(arc
							(start 0.3302 0.4318)
							(mid 0.402042 0.402042)
							(end 0.4318 0.3302)
						)
						(arc
							(start 0.4318 -0.3302)
							(mid 0.402042 -0.402042)
							(end 0.3302 -0.4318)
						)
					)
					(width 0)
					(fill yes)
				)
			)
		)
		(pad "2" smd custom
			(at 0 0.762 90)
			(size 0.2159 0.2159)
			(layers "F.Cu" "F.Mask" "F.Paste")
			(net "GND")
			(options
				(clearance outline)
				(anchor circle)
			)
			(primitives
				(gr_poly
					(pts
						(arc
							(start -0.3302 -0.4318)
							(mid -0.402042 -0.402042)
							(end -0.4318 -0.3302)
						)
						(arc
							(start -0.4318 0.3302)
							(mid -0.402042 0.402042)
							(end -0.3302 0.4318)
						)
						(arc
							(start 0.3302 0.4318)
							(mid 0.402042 0.402042)
							(end 0.4318 0.3302)
						)
						(arc
							(start 0.4318 -0.3302)
							(mid 0.402042 -0.402042)
							(end 0.3302 -0.4318)
						)
					)
					(width 0)
					(fill yes)
				)
			)
		)
	)
	(footprint ""
		(layer "F.Cu")
		(at 18.797778 -100.43033 -90)
		(property "Reference" "U119"
			(at 0 0 270)
			(layer "F.SilkS")
			(hide yes)
			(effects
				(font
					(size 1.27 1.27)
				)
			)
		)
		(property "Value" "NX3L1G66GW-GP"
			(at -2.3368 -8.6868 270)
			(unlocked yes)
			(layer "F.Fab")
			(hide yes)
			(effects
				(font
					(size 1.016 1.016)
					(thickness 0.1524)
				)
			)
		)
		(property "Device Type" "SC70-5H44"
			(at -2.3114 -10.414 270)
			(unlocked yes)
			(layer "F.Fab")
			(hide yes)
			(effects
				(font
					(size 1.016 1.016)
					(thickness 0.1524)
				)
			)
		)
		(duplicate_pad_numbers_are_jumpers no)
		(fp_line
			(start -1.27 1.7018)
			(end -1.27 -1.7018)
			(stroke
				(width 0.1524)
				(type default)
			)
			(layer "F.SilkS")
		)
		(fp_line
			(start 1.27 1.7018)
			(end -1.27 1.7018)
			(stroke
				(width 0.1524)
				(type default)
			)
			(layer "F.SilkS")
		)
		(fp_line
			(start -1.27 -1.7018)
			(end 1.27 -1.7018)
			(stroke
				(width 0.1524)
				(type default)
			)
			(layer "F.SilkS")
		)
		(fp_line
			(start 1.27 -1.7018)
			(end 1.27 1.7018)
			(stroke
				(width 0.1524)
				(type default)
			)
			(layer "F.SilkS")
		)
		(fp_line
			(start 0.6604 -1.8034)
			(end 1.3843 -1.8034)
			(stroke
				(width 0.3302)
				(type default)
			)
			(layer "F.SilkS")
		)
		(fp_line
			(start 1.3843 -1.8034)
			(end 1.3843 -1.1176)
			(stroke
				(width 0.3302)
				(type default)
			)
			(layer "F.SilkS")
		)
		(fp_rect
			(start -1.524 1.9558)
			(end 1.524 -1.9558)
			(stroke
				(width 0)
				(type default)
			)
			(fill no)
			(layer "F.CrtYd")
		)
		(fp_poly
			(pts
				(xy -1.524 -1.9558) (xy 1.524 -1.9558) (xy 1.524 1.9558) (xy -1.524 1.9558)
			)
			(stroke
				(width 0)
				(type default)
			)
			(fill no)
			(layer "F.Fab")
		)
		(pad "1" smd rect
			(at 0.65024 -0.8255 270)
			(size 0.4064 1.2192)
			(layers "F.Cu" "F.Mask" "F.Paste")
			(net "SCC_STBY_PGOOD_BUF")
		)
		(pad "2" smd rect
			(at 0 -0.8255 270)
			(size 0.4064 1.2192)
			(layers "F.Cu" "F.Mask" "F.Paste")
			(net "SCC_STBY_PGOOD_R")
		)
		(pad "3" smd rect
			(at -0.65024 -0.8255 270)
			(size 0.4064 1.2192)
			(layers "F.Cu" "F.Mask" "F.Paste")
			(net "GND")
		)
		(pad "4" smd rect
			(at -0.65024 0.8255 270)
			(size 0.4064 1.2192)
			(layers "F.Cu" "F.Mask" "F.Paste")
			(net "U119_EN")
		)
		(pad "5" smd rect
			(at 0.65024 0.8255 270)
			(size 0.4064 1.2192)
			(layers "F.Cu" "F.Mask" "F.Paste")
			(net "P3V3")
		)
	)
	(footprint ""
		(layer "F.Cu")
		(at 194.801998 -71.411846 90)
		(property "Reference" "U22"
			(at 0 0 90)
			(layer "F.SilkS")
			(hide yes)
			(effects
				(font
					(size 1.27 1.27)
				)
			)
		)
		(property "Value" "TXS0102DCUR-1-GP"
			(at 0 -11.1252 90)
			(unlocked yes)
			(layer "F.Fab")
			(hide yes)
			(effects
				(font
					(size 1.016 1.016)
					(thickness 0.1524)
				)
			)
		)
		(property "Device Type" "SSOIC8-4H36"
			(at 0 -12.6492 90)
			(unlocked yes)
			(layer "F.Fab")
			(hide yes)
			(effects
				(font
					(size 1.016 1.016)
					(thickness 0.1524)
				)
			)
		)
		(duplicate_pad_numbers_are_jumpers no)
		(fp_line
			(start 1.2573 -2.1844)
			(end 1.2573 2.1844)
			(stroke
				(width 0.1524)
				(type default)
			)
			(layer "F.SilkS")
		)
		(fp_line
			(start -1.2573 -2.1844)
			(end 1.2573 -2.1844)
			(stroke
				(width 0.1524)
				(type default)
			)
			(layer "F.SilkS")
		)
		(fp_line
			(start -1.2192 -0.3556)
			(end -0.9017 -0.0381)
			(stroke
				(width 0.1524)
				(type default)
			)
			(layer "F.SilkS")
		)
		(fp_line
			(start -1.2573 -0.3556)
			(end -1.2192 -0.3556)
			(stroke
				(width 0.1524)
				(type default)
			)
			(layer "F.SilkS")
		)
		(fp_line
			(start -0.9017 -0.0381)
			(end -1.2065 0.2667)
			(stroke
				(width 0.1524)
				(type default)
			)
			(layer "F.SilkS")
		)
		(fp_line
			(start -1.2065 0.2667)
			(end -1.27 0.2667)
			(stroke
				(width 0.1524)
				(type default)
			)
			(layer "F.SilkS")
		)
		(fp_line
			(start -1.2954 0.4572)
			(end -1.2954 2.159)
			(stroke
				(width 0.4064)
				(type default)
			)
			(layer "F.SilkS")
		)
		(fp_line
			(start 1.2573 2.1844)
			(end -1.2573 2.1844)
			(stroke
				(width 0.1524)
				(type default)
			)
			(layer "F.SilkS")
		)
		(fp_line
			(start -1.2573 2.1844)
			(end -1.2573 -2.1844)
			(stroke
				(width 0.1524)
				(type default)
			)
			(layer "F.SilkS")
		)
		(fp_poly
			(pts
				(xy -1.5113 2.4384) (xy 1.5113 2.4384) (xy 1.5113 -2.4384) (xy -1.5113 -2.4384)
			)
			(stroke
				(width 0)
				(type default)
			)
			(fill no)
			(layer "F.CrtYd")
		)
		(fp_poly
			(pts
				(xy -1.5113 -2.4384) (xy 1.5113 -2.4384) (xy 1.5113 2.4384) (xy -1.5113 2.4384)
			)
			(stroke
				(width 0)
				(type default)
			)
			(fill no)
			(layer "F.Fab")
		)
		(pad "1" smd rect
			(at -0.75057 1.1684 90)
			(size 0.3048 1.524)
			(layers "F.Cu" "F.Mask" "F.Paste")
			(net "IOC_UART_R_RX")
		)
		(pad "2" smd rect
			(at -0.25019 1.1684 90)
			(size 0.3048 1.524)
			(layers "F.Cu" "F.Mask" "F.Paste")
			(net "GND")
		)
		(pad "3" smd rect
			(at 0.25019 1.1684 90)
			(size 0.3048 1.524)
			(layers "F.Cu" "F.Mask" "F.Paste")
			(net "P1V8_C")
		)
		(pad "4" smd rect
			(at 0.75057 1.1684 90)
			(size 0.3048 1.524)
			(layers "F.Cu" "F.Mask" "F.Paste")
			(net "IOC_UART_0_RX_R")
		)
		(pad "5" smd rect
			(at 0.75057 -1.1684 90)
			(size 0.3048 1.524)
			(layers "F.Cu" "F.Mask" "F.Paste")
			(net "IOC_UART_0_TX_R")
		)
		(pad "6" smd rect
			(at 0.25019 -1.1684 90)
			(size 0.3048 1.524)
			(layers "F.Cu" "F.Mask" "F.Paste")
			(net "PCIE_RST_N")
		)
		(pad "7" smd rect
			(at -0.25019 -1.1684 90)
			(size 0.3048 1.524)
			(layers "F.Cu" "F.Mask" "F.Paste")
			(net "P3V3")
		)
		(pad "8" smd rect
			(at -0.75057 -1.1684 90)
			(size 0.3048 1.524)
			(layers "F.Cu" "F.Mask" "F.Paste")
			(net "IOC_UART_R_TX")
		)
	)
	(footprint ""
		(layer "F.Cu")
		(at 7.7978 -70.4088)
		(property "Reference" "R362"
			(at 0 0 0)
			(layer "F.SilkS")
			(hide yes)
			(effects
				(font
					(size 1.27 1.27)
				)
			)
		)
		(property "Value" "4K7R2F-GP"
			(at 0.064008 -3.993896 0)
			(unlocked yes)
			(layer "F.Fab")
			(hide yes)
			(effects
				(font
					(size 1.016 1.016)
					(thickness 0.1524)
				)
			)
		)
		(property "Device Type" "R402H16"
			(at 0.064008 -5.517896 0)
			(unlocked yes)
			(layer "F.Fab")
			(hide yes)
			(effects
				(font
					(size 1.016 1.016)
					(thickness 0.1524)
				)
			)
		)
		(duplicate_pad_numbers_are_jumpers no)
		(fp_line
			(start -0.508 -0.9398)
			(end -0.508 0.9398)
			(stroke
				(width 0.1524)
				(type default)
			)
			(layer "F.SilkS")
		)
		(fp_line
			(start 0.508 -0.9398)
			(end -0.508 -0.9398)
			(stroke
				(width 0.1524)
				(type default)
			)
			(layer "F.SilkS")
		)
		(fp_rect
			(start -0.508 0.9398)
			(end 0.508 -0.9398)
			(stroke
				(width 0)
				(type default)
			)
			(fill no)
			(layer "F.CrtYd")
		)
		(fp_rect
			(start -0.508 0.9398)
			(end 0.508 -0.9398)
			(stroke
				(width 0)
				(type default)
			)
			(fill no)
			(layer "F.Fab")
		)
		(pad "1" smd custom
			(at 0 -0.4445)
			(size 0.1397 0.1397)
			(layers "F.Cu" "F.Mask" "F.Paste")
			(net "FRU_EEPROM_A2")
			(options
				(clearance outline)
				(anchor circle)
			)
			(primitives
				(gr_poly
					(pts
						(arc
							(start -0.1778 -0.2794)
							(mid -0.249642 -0.249642)
							(end -0.2794 -0.1778)
						)
						(arc
							(start -0.2794 0.1778)
							(mid -0.249642 0.249642)
							(end -0.1778 0.2794)
						)
						(arc
							(start 0.1778 0.2794)
							(mid 0.249642 0.249642)
							(end 0.2794 0.1778)
						)
						(arc
							(start 0.2794 -0.1778)
							(mid 0.249642 -0.249642)
							(end 0.1778 -0.2794)
						)
					)
					(width 0)
					(fill yes)
				)
			)
		)
		(pad "2" smd custom
			(at 0 0.4445)
			(size 0.1397 0.1397)
			(layers "F.Cu" "F.Mask" "F.Paste")
			(net "GND")
			(options
				(clearance outline)
				(anchor circle)
			)
			(primitives
				(gr_poly
					(pts
						(arc
							(start -0.1778 -0.2794)
							(mid -0.249642 -0.249642)
							(end -0.2794 -0.1778)
						)
						(arc
							(start -0.2794 0.1778)
							(mid -0.249642 0.249642)
							(end -0.1778 0.2794)
						)
						(arc
							(start 0.1778 0.2794)
							(mid 0.249642 0.249642)
							(end 0.2794 0.1778)
						)
						(arc
							(start 0.2794 -0.1778)
							(mid 0.249642 -0.249642)
							(end 0.1778 -0.2794)
						)
					)
					(width 0)
					(fill yes)
				)
			)
		)
	)
	(footprint ""
		(layer "F.Cu")
		(at 174.4726 -57.785)
		(property "Reference" "TP139"
			(at 0 0 0)
			(layer "F.SilkS")
			(hide yes)
			(effects
				(font
					(size 1.27 1.27)
				)
			)
		)
		(property "Value" "TPAD28-2-GP"
			(at -0.0127 -1.6637 0)
			(unlocked yes)
			(layer "F.Fab")
			(hide yes)
			(effects
				(font
					(size 1.016 1.016)
					(thickness 0.1524)
				)
			)
		)
		(property "Device Type" "TPAD28"
			(at -0.0127 -3.1877 0)
			(unlocked yes)
			(layer "F.Fab")
			(hide yes)
			(effects
				(font
					(size 1.016 1.016)
					(thickness 0.1524)
				)
			)
		)
		(duplicate_pad_numbers_are_jumpers no)
		(fp_poly
			(pts
				(arc
					(start 0.3556 0)
					(mid -0.3556 0)
					(end 0.3556 0)
				)
			)
			(stroke
				(width 0)
				(type default)
			)
			(fill no)
			(layer "F.CrtYd")
		)
		(fp_poly
			(pts
				(arc
					(start 0.6096 0)
					(mid -0.6096 0)
					(end 0.6096 0)
				)
			)
			(stroke
				(width 0)
				(type default)
			)
			(fill no)
			(layer "F.Fab")
		)
		(pad "1" smd circle
			(at 0 0)
			(size 0.7112 0.7112)
			(layers "F.Cu" "F.Mask" "F.Paste")
			(net "LSI_JTAG_EN_N")
		)
	)
	(footprint ""
		(layer "F.Cu")
		(at 156.0576 -104.42956)
		(property "Reference" "DEBUG1"
			(at 0 0 0)
			(layer "F.SilkS")
			(hide yes)
			(effects
				(font
					(size 1.27 1.27)
				)
			)
		)
		(property "Value" "AMP-CONN4D-2-GP"
			(at -6.35 -0.254 0)
			(unlocked yes)
			(layer "F.Fab")
			(hide yes)
			(effects
				(font
					(size 1.016 1.016)
					(thickness 0.1524)
				)
			)
		)
		(property "Device Type" "G800MR304010HR"
			(at -6.35 -1.778 0)
			(unlocked yes)
			(layer "F.Fab")
			(hide yes)
			(effects
				(font
					(size 1.016 1.016)
					(thickness 0.1524)
				)
			)
		)
		(duplicate_pad_numbers_are_jumpers no)
		(fp_line
			(start -5.334 -3.2512)
			(end -5.334 3.2512)
			(stroke
				(width 0.1524)
				(type default)
			)
			(layer "F.SilkS")
		)
		(fp_line
			(start -5.334 3.2512)
			(end 5.334 3.2512)
			(stroke
				(width 0.1524)
				(type default)
			)
			(layer "F.SilkS")
		)
		(fp_line
			(start -4.2672 -3.3401)
			(end -3.2512 -3.3401)
			(stroke
				(width 0.3302)
				(type default)
			)
			(layer "F.SilkS")
		)
		(fp_line
			(start 5.334 -3.2512)
			(end -5.334 -3.2512)
			(stroke
				(width 0.1524)
				(type default)
			)
			(layer "F.SilkS")
		)
		(fp_line
			(start 5.334 3.2512)
			(end 5.334 -3.2512)
			(stroke
				(width 0.1524)
				(type default)
			)
			(layer "F.SilkS")
		)
		(fp_poly
			(pts
				(xy -3.81 -3.3274) (xy -3.175 -3.9624) (xy -4.445 -3.9624)
			)
			(stroke
				(width 0)
				(type default)
			)
			(fill yes)
			(layer "F.SilkS")
		)
		(fp_rect
			(start -5.08 2.4892)
			(end 5.08 -2.4892)
			(stroke
				(width 0)
				(type default)
			)
			(fill no)
			(layer "F.CrtYd")
		)
		(fp_poly
			(pts
				(xy 5.588 -2.4892) (xy -5.08 -2.4892) (xy -5.08 2.4892) (xy 5.08 2.4892) (xy 5.08 -2.4765) (xy 5.588 -2.4765)
				(xy 5.588 3.5052) (xy -5.588 3.5052) (xy -5.588 -3.5052) (xy 5.588 -3.5052)
			)
			(stroke
				(width 0)
				(type default)
			)
			(fill no)
			(layer "F.CrtYd")
		)
		(fp_rect
			(start -5.588 3.5052)
			(end 5.588 -3.5052)
			(stroke
				(width 0)
				(type default)
			)
			(fill no)
			(layer "F.Fab")
		)
		(pad "1" smd rect
			(at -3.81 -1.500124)
			(size 0.9906 2.9972)
			(layers "F.Cu" "F.Mask" "F.Paste")
			(net "SDB_CONN_PWR_2")
		)
		(pad "2" smd rect
			(at -1.27 1.500124)
			(size 0.9906 2.9972)
			(layers "F.Cu" "F.Mask" "F.Paste")
			(net "UART_SDB_TX")
		)
		(pad "3" smd rect
			(at 1.27 -1.500124)
			(size 0.9906 2.9972)
			(layers "F.Cu" "F.Mask" "F.Paste")
			(net "UART_SDB_RX")
		)
		(pad "4" smd rect
			(at 3.81 1.500124)
			(size 0.9906 2.9972)
			(layers "F.Cu" "F.Mask" "F.Paste")
			(net "GND")
		)
	)
	(footprint ""
		(layer "F.Cu")
		(at 123.317 -109.93628)
		(property "Reference" "TP151"
			(at 0 0 0)
			(layer "F.SilkS")
			(hide yes)
			(effects
				(font
					(size 1.27 1.27)
				)
			)
		)
		(property "Value" "TPAD28-2-GP"
			(at -0.0127 -1.6637 0)
			(unlocked yes)
			(layer "F.Fab")
			(hide yes)
			(effects
				(font
					(size 1.016 1.016)
					(thickness 0.1524)
				)
			)
		)
		(property "Device Type" "TPAD28"
			(at -0.0127 -3.1877 0)
			(unlocked yes)
			(layer "F.Fab")
			(hide yes)
			(effects
				(font
					(size 1.016 1.016)
					(thickness 0.1524)
				)
			)
		)
		(duplicate_pad_numbers_are_jumpers no)
		(fp_poly
			(pts
				(arc
					(start 0.3556 0)
					(mid -0.3556 0)
					(end 0.3556 0)
				)
			)
			(stroke
				(width 0)
				(type default)
			)
			(fill no)
			(layer "F.CrtYd")
		)
		(fp_poly
			(pts
				(arc
					(start 0.6096 0)
					(mid -0.6096 0)
					(end 0.6096 0)
				)
			)
			(stroke
				(width 0)
				(type default)
			)
			(fill no)
			(layer "F.Fab")
		)
		(pad "1" smd circle
			(at 0 0)
			(size 0.7112 0.7112)
			(layers "F.Cu" "F.Mask" "F.Paste")
			(net "INT_C1_CONN1")
		)
	)
	(footprint ""
		(layer "F.Cu")
		(at 67.9704 -72.6948 180)
		(property "Reference" "R429"
			(at 0 0 180)
			(layer "F.SilkS")
			(hide yes)
			(effects
				(font
					(size 1.27 1.27)
				)
			)
		)
		(property "Value" "1KR2F-3-GP"
			(at 0.064008 -3.993896 180)
			(unlocked yes)
			(layer "F.Fab")
			(hide yes)
			(effects
				(font
					(size 1.016 1.016)
					(thickness 0.1524)
				)
			)
		)
		(property "Device Type" "R402H16"
			(at 0.064008 -5.517896 180)
			(unlocked yes)
			(layer "F.Fab")
			(hide yes)
			(effects
				(font
					(size 1.016 1.016)
					(thickness 0.1524)
				)
			)
		)
		(duplicate_pad_numbers_are_jumpers no)
		(fp_line
			(start 0.508 -0.9398)
			(end -0.508 -0.9398)
			(stroke
				(width 0.1524)
				(type default)
			)
			(layer "F.SilkS")
		)
		(fp_line
			(start -0.508 -0.9398)
			(end -0.508 0.9398)
			(stroke
				(width 0.1524)
				(type default)
			)
			(layer "F.SilkS")
		)
		(fp_rect
			(start -0.508 0.9398)
			(end 0.508 -0.9398)
			(stroke
				(width 0)
				(type default)
			)
			(fill no)
			(layer "F.CrtYd")
		)
		(fp_rect
			(start -0.508 0.9398)
			(end 0.508 -0.9398)
			(stroke
				(width 0)
				(type default)
			)
			(fill no)
			(layer "F.Fab")
		)
		(pad "1" smd custom
			(at 0 -0.4445 180)
			(size 0.1397 0.1397)
			(layers "F.Cu" "F.Mask" "F.Paste")
			(net "P3V3")
			(options
				(clearance outline)
				(anchor circle)
			)
			(primitives
				(gr_poly
					(pts
						(arc
							(start -0.1778 -0.2794)
							(mid -0.249642 -0.249642)
							(end -0.2794 -0.1778)
						)
						(arc
							(start -0.2794 0.1778)
							(mid -0.249642 0.249642)
							(end -0.1778 0.2794)
						)
						(arc
							(start 0.1778 0.2794)
							(mid 0.249642 0.249642)
							(end 0.2794 0.1778)
						)
						(arc
							(start 0.2794 -0.1778)
							(mid 0.249642 -0.249642)
							(end 0.1778 -0.2794)
						)
					)
					(width 0)
					(fill yes)
				)
			)
		)
		(pad "2" smd custom
			(at 0 0.4445 180)
			(size 0.1397 0.1397)
			(layers "F.Cu" "F.Mask" "F.Paste")
			(net "I2C_DRIVE_FLT_LED_SCL6")
			(options
				(clearance outline)
				(anchor circle)
			)
			(primitives
				(gr_poly
					(pts
						(arc
							(start -0.1778 -0.2794)
							(mid -0.249642 -0.249642)
							(end -0.2794 -0.1778)
						)
						(arc
							(start -0.2794 0.1778)
							(mid -0.249642 0.249642)
							(end -0.1778 0.2794)
						)
						(arc
							(start 0.1778 0.2794)
							(mid 0.249642 0.249642)
							(end 0.2794 0.1778)
						)
						(arc
							(start 0.2794 -0.1778)
							(mid 0.249642 -0.249642)
							(end 0.1778 -0.2794)
						)
					)
					(width 0)
					(fill yes)
				)
			)
		)
	)
	(footprint ""
		(layer "F.Cu")
		(at 152.253442 -89.593166 -90)
		(property "Reference" "R289"
			(at 0 0 270)
			(layer "F.SilkS")
			(hide yes)
			(effects
				(font
					(size 1.27 1.27)
				)
			)
		)
		(property "Value" "0R2J-2-GP"
			(at 0.064008 -3.993896 270)
			(unlocked yes)
			(layer "F.Fab")
			(hide yes)
			(effects
				(font
					(size 1.016 1.016)
					(thickness 0.1524)
				)
			)
		)
		(property "Device Type" "R402H16"
			(at 0.064008 -5.517896 270)
			(unlocked yes)
			(layer "F.Fab")
			(hide yes)
			(effects
				(font
					(size 1.016 1.016)
					(thickness 0.1524)
				)
			)
		)
		(duplicate_pad_numbers_are_jumpers no)
		(fp_line
			(start -0.508 -0.9398)
			(end -0.508 0.9398)
			(stroke
				(width 0.1524)
				(type default)
			)
			(layer "F.SilkS")
		)
		(fp_line
			(start 0.508 -0.9398)
			(end -0.508 -0.9398)
			(stroke
				(width 0.1524)
				(type default)
			)
			(layer "F.SilkS")
		)
		(fp_rect
			(start -0.508 0.9398)
			(end 0.508 -0.9398)
			(stroke
				(width 0)
				(type default)
			)
			(fill no)
			(layer "F.CrtYd")
		)
		(fp_rect
			(start -0.508 0.9398)
			(end 0.508 -0.9398)
			(stroke
				(width 0)
				(type default)
			)
			(fill no)
			(layer "F.Fab")
		)
		(pad "1" smd custom
			(at 0 -0.4445 270)
			(size 0.1397 0.1397)
			(layers "F.Cu" "F.Mask" "F.Paste")
			(net "SAS_SMART_R_TX")
			(options
				(clearance outline)
				(anchor circle)
			)
			(primitives
				(gr_poly
					(pts
						(arc
							(start -0.1778 -0.2794)
							(mid -0.249642 -0.249642)
							(end -0.2794 -0.1778)
						)
						(arc
							(start -0.2794 0.1778)
							(mid -0.249642 0.249642)
							(end -0.1778 0.2794)
						)
						(arc
							(start 0.1778 0.2794)
							(mid 0.249642 0.249642)
							(end 0.2794 0.1778)
						)
						(arc
							(start 0.2794 -0.1778)
							(mid 0.249642 -0.249642)
							(end 0.1778 -0.2794)
						)
					)
					(width 0)
					(fill yes)
				)
			)
		)
		(pad "2" smd custom
			(at 0 0.4445 270)
			(size 0.1397 0.1397)
			(layers "F.Cu" "F.Mask" "F.Paste")
			(net "SAS_SMART_TX")
			(options
				(clearance outline)
				(anchor circle)
			)
			(primitives
				(gr_poly
					(pts
						(arc
							(start -0.1778 -0.2794)
							(mid -0.249642 -0.249642)
							(end -0.2794 -0.1778)
						)
						(arc
							(start -0.2794 0.1778)
							(mid -0.249642 0.249642)
							(end -0.1778 0.2794)
						)
						(arc
							(start 0.1778 0.2794)
							(mid 0.249642 0.249642)
							(end 0.2794 0.1778)
						)
						(arc
							(start 0.2794 -0.1778)
							(mid 0.249642 -0.249642)
							(end 0.1778 -0.2794)
						)
					)
					(width 0)
					(fill yes)
				)
			)
		)
	)
	(footprint ""
		(layer "F.Cu")
		(at 84.7725 -68.622164 -90)
		(property "Reference" "U24"
			(at 0 0 270)
			(layer "F.SilkS")
			(hide yes)
			(effects
				(font
					(size 1.27 1.27)
				)
			)
		)
		(property "Value" "SNLVC8T245DGVR-GP"
			(at 0 -11.1252 270)
			(unlocked yes)
			(layer "F.Fab")
			(hide yes)
			(effects
				(font
					(size 1.016 1.016)
					(thickness 0.1524)
				)
			)
		)
		(property "Device Type" "TVSOP24H48"
			(at 0 -12.6492 270)
			(unlocked yes)
			(layer "F.Fab")
			(hide yes)
			(effects
				(font
					(size 1.016 1.016)
					(thickness 0.1524)
				)
			)
		)
		(duplicate_pad_numbers_are_jumpers no)
		(fp_line
			(start -2.9337 1.397)
			(end 2.2987 1.397)
			(stroke
				(width 0.1524)
				(type default)
			)
			(layer "F.SilkS")
		)
		(fp_line
			(start -2.7559 1.397)
			(end -2.7559 3.8354)
			(stroke
				(width 0.508)
				(type default)
			)
			(layer "F.SilkS")
		)
		(fp_line
			(start 2.2987 1.397)
			(end 2.2987 -1.397)
			(stroke
				(width 0.1524)
				(type default)
			)
			(layer "F.SilkS")
		)
		(fp_line
			(start -2.5654 0)
			(end -2.9337 0.3683)
			(stroke
				(width 0.1524)
				(type default)
			)
			(layer "F.SilkS")
		)
		(fp_line
			(start -2.9337 -0.3683)
			(end -2.5654 0)
			(stroke
				(width 0.1524)
				(type default)
			)
			(layer "F.SilkS")
		)
		(fp_line
			(start -2.9337 -1.397)
			(end -2.9337 1.397)
			(stroke
				(width 0.1524)
				(type default)
			)
			(layer "F.SilkS")
		)
		(fp_line
			(start 2.2987 -1.397)
			(end -2.9337 -1.397)
			(stroke
				(width 0.1524)
				(type default)
			)
			(layer "F.SilkS")
		)
		(fp_rect
			(start -3.0099 4.0894)
			(end 3.0099 -4.0894)
			(stroke
				(width 0)
				(type default)
			)
			(fill no)
			(layer "F.CrtYd")
		)
		(fp_poly
			(pts
				(xy -3.0099 -4.0894) (xy 3.0099 -4.0894) (xy 3.0099 4.0894) (xy -3.0099 4.0894)
			)
			(stroke
				(width 0)
				(type default)
			)
			(fill no)
			(layer "F.Fab")
		)
		(pad "1" smd rect
			(at -2.19964 2.8194 270)
			(size 0.2032 1.524)
			(layers "F.Cu" "F.Mask" "F.Paste")
			(net "P3V3")
		)
		(pad "2" smd rect
			(at -1.79959 2.8194 270)
			(size 0.2032 1.524)
			(layers "F.Cu" "F.Mask" "F.Paste")
			(net "GND")
		)
		(pad "3" smd rect
			(at -1.39954 2.8194 270)
			(size 0.2032 1.524)
			(layers "F.Cu" "F.Mask" "F.Paste")
			(net "DEBUG_LOW_HEX_0")
		)
		(pad "4" smd rect
			(at -0.99949 2.8194 270)
			(size 0.2032 1.524)
			(layers "F.Cu" "F.Mask" "F.Paste")
			(net "DEBUG_LOW_HEX_1")
		)
		(pad "5" smd rect
			(at -0.59944 2.8194 270)
			(size 0.2032 1.524)
			(layers "F.Cu" "F.Mask" "F.Paste")
			(net "DEBUG_LOW_HEX_2")
		)
		(pad "6" smd rect
			(at -0.19939 2.8194 270)
			(size 0.2032 1.524)
			(layers "F.Cu" "F.Mask" "F.Paste")
			(net "DEBUG_LOW_HEX_3")
		)
		(pad "7" smd rect
			(at 0.19939 2.8194 270)
			(size 0.2032 1.524)
			(layers "F.Cu" "F.Mask" "F.Paste")
			(net "DEBUG_HIGH_HEX_0")
		)
		(pad "8" smd rect
			(at 0.59944 2.8194 270)
			(size 0.2032 1.524)
			(layers "F.Cu" "F.Mask" "F.Paste")
			(net "DEBUG_HIGH_HEX_1")
		)
		(pad "9" smd rect
			(at 0.99949 2.8194 270)
			(size 0.2032 1.524)
			(layers "F.Cu" "F.Mask" "F.Paste")
			(net "DEBUG_HIGH_HEX_2")
		)
		(pad "10" smd rect
			(at 1.39954 2.8194 270)
			(size 0.2032 1.524)
			(layers "F.Cu" "F.Mask" "F.Paste")
			(net "DEBUG_HIGH_HEX_3")
		)
		(pad "11" smd rect
			(at 1.79959 2.8194 270)
			(size 0.2032 1.524)
			(layers "F.Cu" "F.Mask" "F.Paste")
			(net "GND")
		)
		(pad "12" smd rect
			(at 2.19964 2.8194 270)
			(size 0.2032 1.524)
			(layers "F.Cu" "F.Mask" "F.Paste")
			(net "GND")
		)
		(pad "13" smd rect
			(at 2.19964 -2.8194 270)
			(size 0.2032 1.524)
			(layers "F.Cu" "F.Mask" "F.Paste")
			(net "GND")
		)
		(pad "14" smd rect
			(at 1.79959 -2.8194 270)
			(size 0.2032 1.524)
			(layers "F.Cu" "F.Mask" "F.Paste")
			(net "LED47")
		)
		(pad "15" smd rect
			(at 1.39954 -2.8194 270)
			(size 0.2032 1.524)
			(layers "F.Cu" "F.Mask" "F.Paste")
			(net "LED46")
		)
		(pad "16" smd rect
			(at 0.99949 -2.8194 270)
			(size 0.2032 1.524)
			(layers "F.Cu" "F.Mask" "F.Paste")
			(net "LED45")
		)
		(pad "17" smd rect
			(at 0.59944 -2.8194 270)
			(size 0.2032 1.524)
			(layers "F.Cu" "F.Mask" "F.Paste")
			(net "LED44")
		)
		(pad "18" smd rect
			(at 0.19939 -2.8194 270)
			(size 0.2032 1.524)
			(layers "F.Cu" "F.Mask" "F.Paste")
			(net "LED43")
		)
		(pad "19" smd rect
			(at -0.19939 -2.8194 270)
			(size 0.2032 1.524)
			(layers "F.Cu" "F.Mask" "F.Paste")
			(net "LED42")
		)
		(pad "20" smd rect
			(at -0.59944 -2.8194 270)
			(size 0.2032 1.524)
			(layers "F.Cu" "F.Mask" "F.Paste")
			(net "LED41")
		)
		(pad "21" smd rect
			(at -0.99949 -2.8194 270)
			(size 0.2032 1.524)
			(layers "F.Cu" "F.Mask" "F.Paste")
			(net "LED40")
		)
		(pad "22" smd rect
			(at -1.39954 -2.8194 270)
			(size 0.2032 1.524)
			(layers "F.Cu" "F.Mask" "F.Paste")
			(net "LS_EN_U24")
		)
		(pad "23" smd rect
			(at -1.79959 -2.8194 270)
			(size 0.2032 1.524)
			(layers "F.Cu" "F.Mask" "F.Paste")
			(net "P1V8_E")
		)
		(pad "24" smd rect
			(at -2.19964 -2.8194 270)
			(size 0.2032 1.524)
			(layers "F.Cu" "F.Mask" "F.Paste")
			(net "P1V8_E")
		)
	)
	(footprint ""
		(layer "F.Cu")
		(at 21.7932 -51.9176 90)
		(property "Reference" "C714"
			(at 0 0 90)
			(layer "F.SilkS")
			(hide yes)
			(effects
				(font
					(size 1.27 1.27)
				)
			)
		)
		(property "Value" "SC1U16V3KX-5GP"
			(at 0 -2.8194 90)
			(unlocked yes)
			(layer "F.Fab")
			(hide yes)
			(effects
				(font
					(size 1.016 1.016)
					(thickness 0.1524)
				)
			)
		)
		(property "Device Type" "C603H36"
			(at 0 -4.3434 90)
			(unlocked yes)
			(layer "F.Fab")
			(hide yes)
			(effects
				(font
					(size 1.016 1.016)
					(thickness 0.1524)
				)
			)
		)
		(duplicate_pad_numbers_are_jumpers no)
		(fp_line
			(start 0.508 0)
			(end -0.508 0)
			(stroke
				(width 0.2032)
				(type default)
			)
			(layer "F.SilkS")
		)
		(fp_rect
			(start -0.5842 1.3335)
			(end 0.5842 -1.3335)
			(stroke
				(width 0)
				(type default)
			)
			(fill no)
			(layer "F.CrtYd")
		)
		(fp_rect
			(start -0.5842 1.3335)
			(end 0.5842 -1.3335)
			(stroke
				(width 0)
				(type default)
			)
			(fill no)
			(layer "F.Fab")
		)
		(pad "1" smd custom
			(at 0 -0.762 90)
			(size 0.2159 0.2159)
			(layers "F.Cu" "F.Mask" "F.Paste")
			(net "MB0_VCAP_R")
			(options
				(clearance outline)
				(anchor circle)
			)
			(primitives
				(gr_poly
					(pts
						(arc
							(start -0.3302 -0.4318)
							(mid -0.402042 -0.402042)
							(end -0.4318 -0.3302)
						)
						(arc
							(start -0.4318 0.3302)
							(mid -0.402042 0.402042)
							(end -0.3302 0.4318)
						)
						(arc
							(start 0.3302 0.4318)
							(mid 0.402042 0.402042)
							(end 0.4318 0.3302)
						)
						(arc
							(start 0.4318 -0.3302)
							(mid 0.402042 -0.402042)
							(end 0.3302 -0.4318)
						)
					)
					(width 0)
					(fill yes)
				)
			)
		)
		(pad "2" smd custom
			(at 0 0.762 90)
			(size 0.2159 0.2159)
			(layers "F.Cu" "F.Mask" "F.Paste")
			(net "AGND_CURRENT_MON")
			(options
				(clearance outline)
				(anchor circle)
			)
			(primitives
				(gr_poly
					(pts
						(arc
							(start -0.3302 -0.4318)
							(mid -0.402042 -0.402042)
							(end -0.4318 -0.3302)
						)
						(arc
							(start -0.4318 0.3302)
							(mid -0.402042 0.402042)
							(end -0.3302 0.4318)
						)
						(arc
							(start 0.3302 0.4318)
							(mid 0.402042 0.402042)
							(end 0.4318 0.3302)
						)
						(arc
							(start 0.4318 -0.3302)
							(mid 0.402042 -0.402042)
							(end 0.3302 -0.4318)
						)
					)
					(width 0)
					(fill yes)
				)
			)
		)
	)
	(footprint ""
		(layer "F.Cu")
		(at 199.78624 -82.91322)
		(property "Reference" "C577"
			(at 0 0 0)
			(layer "F.SilkS")
			(hide yes)
			(effects
				(font
					(size 1.27 1.27)
				)
			)
		)
		(property "Value" "SCD1U16V2KX-3GP"
			(at 1.1811 -2.7051 0)
			(unlocked yes)
			(layer "F.Fab")
			(hide yes)
			(effects
				(font
					(size 1.016 1.016)
					(thickness 0.1524)
				)
			)
		)
		(property "Device Type" "C402H22"
			(at 1.1811 -4.2291 0)
			(unlocked yes)
			(layer "F.Fab")
			(hide yes)
			(effects
				(font
					(size 1.016 1.016)
					(thickness 0.1524)
				)
			)
		)
		(duplicate_pad_numbers_are_jumpers no)
		(fp_rect
			(start -0.4318 0.9525)
			(end 0.4318 -0.9525)
			(stroke
				(width 0)
				(type default)
			)
			(fill no)
			(layer "F.CrtYd")
		)
		(fp_rect
			(start -0.4318 0.9525)
			(end 0.4318 -0.9525)
			(stroke
				(width 0)
				(type default)
			)
			(fill no)
			(layer "F.Fab")
		)
		(pad "1" smd custom
			(at 0 -0.4445)
			(size 0.1524 0.1524)
			(layers "F.Cu" "F.Mask" "F.Paste")
			(net "SDB_CONN_PWR_3")
			(options
				(clearance outline)
				(anchor circle)
			)
			(primitives
				(gr_poly
					(pts
						(arc
							(start 0.3048 -0.2032)
							(mid 0.275042 -0.275042)
							(end 0.2032 -0.3048)
						)
						(arc
							(start -0.2032 -0.3048)
							(mid -0.275042 -0.275042)
							(end -0.3048 -0.2032)
						)
						(arc
							(start -0.3048 0.2032)
							(mid -0.275042 0.275042)
							(end -0.2032 0.3048)
						)
						(arc
							(start 0.2032 0.3048)
							(mid 0.275042 0.275042)
							(end 0.3048 0.2032)
						)
					)
					(width 0)
					(fill yes)
				)
			)
		)
		(pad "2" smd custom
			(at 0 0.4445)
			(size 0.1524 0.1524)
			(layers "F.Cu" "F.Mask" "F.Paste")
			(net "GND")
			(options
				(clearance outline)
				(anchor circle)
			)
			(primitives
				(gr_poly
					(pts
						(arc
							(start 0.3048 -0.2032)
							(mid 0.275042 -0.275042)
							(end 0.2032 -0.3048)
						)
						(arc
							(start -0.2032 -0.3048)
							(mid -0.275042 -0.275042)
							(end -0.3048 -0.2032)
						)
						(arc
							(start -0.3048 0.2032)
							(mid -0.275042 0.275042)
							(end -0.2032 0.3048)
						)
						(arc
							(start 0.2032 0.3048)
							(mid 0.275042 0.275042)
							(end 0.3048 0.2032)
						)
					)
					(width 0)
					(fill yes)
				)
			)
		)
	)
	(footprint ""
		(layer "F.Cu")
		(at 13.335 -72.3138 -90)
		(property "Reference" "U29"
			(at 0 0 270)
			(layer "F.SilkS")
			(hide yes)
			(effects
				(font
					(size 1.27 1.27)
				)
			)
		)
		(property "Value" "24LC64-I-SN-1-GP"
			(at -3.707384 -1.5367 270)
			(unlocked yes)
			(layer "F.Fab")
			(hide yes)
			(effects
				(font
					(size 1.016 1.016)
					(thickness 0.1524)
				)
			)
		)
		(property "Device Type" "SOIC8H69"
			(at -3.707384 -3.0607 270)
			(unlocked yes)
			(layer "F.Fab")
			(hide yes)
			(effects
				(font
					(size 1.016 1.016)
					(thickness 0.1524)
				)
			)
		)
		(duplicate_pad_numbers_are_jumpers no)
		(fp_line
			(start -2.6289 3.4417)
			(end -2.6289 1.4732)
			(stroke
				(width 0.381)
				(type default)
			)
			(layer "F.SilkS")
		)
		(fp_line
			(start -2.7432 1.4224)
			(end -2.6416 1.4224)
			(stroke
				(width 0.1524)
				(type default)
			)
			(layer "F.SilkS")
		)
		(fp_line
			(start -2.7432 1.4224)
			(end 2.1336 1.4224)
			(stroke
				(width 0.1524)
				(type default)
			)
			(layer "F.SilkS")
		)
		(fp_line
			(start 2.1336 1.4224)
			(end 2.1336 -1.4224)
			(stroke
				(width 0.1524)
				(type default)
			)
			(layer "F.SilkS")
		)
		(fp_line
			(start -2.1844 -0.0508)
			(end -2.7178 0.508)
			(stroke
				(width 0.1524)
				(type default)
			)
			(layer "F.SilkS")
		)
		(fp_line
			(start -2.7178 -0.508)
			(end -2.1844 -0.0508)
			(stroke
				(width 0.1524)
				(type default)
			)
			(layer "F.SilkS")
		)
		(fp_line
			(start -2.7432 -1.4224)
			(end -2.7432 1.4224)
			(stroke
				(width 0.1524)
				(type default)
			)
			(layer "F.SilkS")
		)
		(fp_line
			(start 2.1336 -1.4224)
			(end -2.7432 -1.4224)
			(stroke
				(width 0.1524)
				(type default)
			)
			(layer "F.SilkS")
		)
		(fp_poly
			(pts
				(xy -2.2098 -1.4224) (xy -2.2098 1.4224) (xy 2.2098 1.4224) (xy 2.2098 -1.4224)
			)
			(stroke
				(width 0)
				(type default)
			)
			(fill yes)
			(layer "F.SilkS")
		)
		(fp_rect
			(start -2.450084 2.999994)
			(end 2.450084 -2.999994)
			(stroke
				(width 0)
				(type default)
			)
			(fill no)
			(layer "F.CrtYd")
		)
		(fp_poly
			(pts
				(xy -2.8194 3.6322) (xy -2.8194 -3.6322) (xy 2.8194 -3.6322) (xy 2.8194 1.18364) (xy 2.450084 1.18364)
				(xy 2.450084 -2.999994) (xy -2.450084 -2.999994) (xy -2.450084 2.999994) (xy 2.450084 2.999994)
				(xy 2.450084 1.18618) (xy 2.8194 1.18618) (xy 2.8194 3.6322)
			)
			(stroke
				(width 0)
				(type default)
			)
			(fill no)
			(layer "F.CrtYd")
		)
		(fp_rect
			(start -2.8194 3.6322)
			(end 2.8194 -3.6322)
			(stroke
				(width 0)
				(type default)
			)
			(fill no)
			(layer "F.Fab")
		)
		(pad "1" smd rect
			(at -1.905 2.54 270)
			(size 0.635 1.651)
			(layers "F.Cu" "F.Mask" "F.Paste")
			(net "FRU_EEPROM_A0")
		)
		(pad "2" smd rect
			(at -0.635 2.54 270)
			(size 0.635 1.651)
			(layers "F.Cu" "F.Mask" "F.Paste")
			(net "FRU_EEPROM_A1")
		)
		(pad "3" smd rect
			(at 0.635 2.54 270)
			(size 0.635 1.651)
			(layers "F.Cu" "F.Mask" "F.Paste")
			(net "FRU_EEPROM_A2")
		)
		(pad "4" smd rect
			(at 1.905 2.54 270)
			(size 0.635 1.651)
			(layers "F.Cu" "F.Mask" "F.Paste")
			(net "GND")
		)
		(pad "5" smd rect
			(at 1.905 -2.54 270)
			(size 0.635 1.651)
			(layers "F.Cu" "F.Mask" "F.Paste")
			(net "EEPROM_SDA")
		)
		(pad "6" smd rect
			(at 0.635 -2.54 270)
			(size 0.635 1.651)
			(layers "F.Cu" "F.Mask" "F.Paste")
			(net "EEPROM_SCL")
		)
		(pad "7" smd rect
			(at -0.635 -2.54 270)
			(size 0.635 1.651)
			(layers "F.Cu" "F.Mask" "F.Paste")
			(net "EEPROM_WP")
		)
		(pad "8" smd rect
			(at -1.905 -2.54 270)
			(size 0.635 1.651)
			(layers "F.Cu" "F.Mask" "F.Paste")
			(net "P3V3")
		)
	)
	(footprint ""
		(layer "F.Cu")
		(at 155.8417 -80.007714 -90)
		(property "Reference" "R334"
			(at 0 0 270)
			(layer "F.SilkS")
			(hide yes)
			(effects
				(font
					(size 1.27 1.27)
				)
			)
		)
		(property "Value" "4K7R2F-GP"
			(at 0.064008 -3.993896 270)
			(unlocked yes)
			(layer "F.Fab")
			(hide yes)
			(effects
				(font
					(size 1.016 1.016)
					(thickness 0.1524)
				)
			)
		)
		(property "Device Type" "R402H16"
			(at 0.064008 -5.517896 270)
			(unlocked yes)
			(layer "F.Fab")
			(hide yes)
			(effects
				(font
					(size 1.016 1.016)
					(thickness 0.1524)
				)
			)
		)
		(duplicate_pad_numbers_are_jumpers no)
		(fp_line
			(start -0.508 -0.9398)
			(end -0.508 0.9398)
			(stroke
				(width 0.1524)
				(type default)
			)
			(layer "F.SilkS")
		)
		(fp_line
			(start 0.508 -0.9398)
			(end -0.508 -0.9398)
			(stroke
				(width 0.1524)
				(type default)
			)
			(layer "F.SilkS")
		)
		(fp_rect
			(start -0.508 0.9398)
			(end 0.508 -0.9398)
			(stroke
				(width 0)
				(type default)
			)
			(fill no)
			(layer "F.CrtYd")
		)
		(fp_rect
			(start -0.508 0.9398)
			(end 0.508 -0.9398)
			(stroke
				(width 0)
				(type default)
			)
			(fill no)
			(layer "F.Fab")
		)
		(pad "1" smd custom
			(at 0 -0.4445 270)
			(size 0.1397 0.1397)
			(layers "F.Cu" "F.Mask" "F.Paste")
			(net "VOL_SEN2_ADDR")
			(options
				(clearance outline)
				(anchor circle)
			)
			(primitives
				(gr_poly
					(pts
						(arc
							(start -0.1778 -0.2794)
							(mid -0.249642 -0.249642)
							(end -0.2794 -0.1778)
						)
						(arc
							(start -0.2794 0.1778)
							(mid -0.249642 0.249642)
							(end -0.1778 0.2794)
						)
						(arc
							(start 0.1778 0.2794)
							(mid 0.249642 0.249642)
							(end 0.2794 0.1778)
						)
						(arc
							(start 0.2794 -0.1778)
							(mid 0.249642 -0.249642)
							(end 0.1778 -0.2794)
						)
					)
					(width 0)
					(fill yes)
				)
			)
		)
		(pad "2" smd custom
			(at 0 0.4445 270)
			(size 0.1397 0.1397)
			(layers "F.Cu" "F.Mask" "F.Paste")
			(net "GND")
			(options
				(clearance outline)
				(anchor circle)
			)
			(primitives
				(gr_poly
					(pts
						(arc
							(start -0.1778 -0.2794)
							(mid -0.249642 -0.249642)
							(end -0.2794 -0.1778)
						)
						(arc
							(start -0.2794 0.1778)
							(mid -0.249642 0.249642)
							(end -0.1778 0.2794)
						)
						(arc
							(start 0.1778 0.2794)
							(mid 0.249642 0.249642)
							(end 0.2794 0.1778)
						)
						(arc
							(start 0.2794 -0.1778)
							(mid 0.249642 -0.249642)
							(end 0.1778 -0.2794)
						)
					)
					(width 0)
					(fill yes)
				)
			)
		)
	)
	(footprint ""
		(layer "F.Cu")
		(at 187.3758 -21.8948 -90)
		(property "Reference" "R272"
			(at 0 0 270)
			(layer "F.SilkS")
			(hide yes)
			(effects
				(font
					(size 1.27 1.27)
				)
			)
		)
		(property "Value" "10KR2F-2-GP"
			(at 0.064008 -3.993896 270)
			(unlocked yes)
			(layer "F.Fab")
			(hide yes)
			(effects
				(font
					(size 1.016 1.016)
					(thickness 0.1524)
				)
			)
		)
		(property "Device Type" "R402H16"
			(at 0.064008 -5.517896 270)
			(unlocked yes)
			(layer "F.Fab")
			(hide yes)
			(effects
				(font
					(size 1.016 1.016)
					(thickness 0.1524)
				)
			)
		)
		(duplicate_pad_numbers_are_jumpers no)
		(fp_line
			(start -0.508 -0.9398)
			(end -0.508 0.9398)
			(stroke
				(width 0.1524)
				(type default)
			)
			(layer "F.SilkS")
		)
		(fp_line
			(start 0.508 -0.9398)
			(end -0.508 -0.9398)
			(stroke
				(width 0.1524)
				(type default)
			)
			(layer "F.SilkS")
		)
		(fp_rect
			(start -0.508 0.9398)
			(end 0.508 -0.9398)
			(stroke
				(width 0)
				(type default)
			)
			(fill no)
			(layer "F.CrtYd")
		)
		(fp_rect
			(start -0.508 0.9398)
			(end 0.508 -0.9398)
			(stroke
				(width 0)
				(type default)
			)
			(fill no)
			(layer "F.Fab")
		)
		(pad "1" smd custom
			(at 0 -0.4445 270)
			(size 0.1397 0.1397)
			(layers "F.Cu" "F.Mask" "F.Paste")
			(net "SYS_DBMODE1")
			(options
				(clearance outline)
				(anchor circle)
			)
			(primitives
				(gr_poly
					(pts
						(arc
							(start -0.1778 -0.2794)
							(mid -0.249642 -0.249642)
							(end -0.2794 -0.1778)
						)
						(arc
							(start -0.2794 0.1778)
							(mid -0.249642 0.249642)
							(end -0.1778 0.2794)
						)
						(arc
							(start 0.1778 0.2794)
							(mid 0.249642 0.249642)
							(end 0.2794 0.1778)
						)
						(arc
							(start 0.2794 -0.1778)
							(mid 0.249642 -0.249642)
							(end 0.1778 -0.2794)
						)
					)
					(width 0)
					(fill yes)
				)
			)
		)
		(pad "2" smd custom
			(at 0 0.4445 270)
			(size 0.1397 0.1397)
			(layers "F.Cu" "F.Mask" "F.Paste")
			(net "GND")
			(options
				(clearance outline)
				(anchor circle)
			)
			(primitives
				(gr_poly
					(pts
						(arc
							(start -0.1778 -0.2794)
							(mid -0.249642 -0.249642)
							(end -0.2794 -0.1778)
						)
						(arc
							(start -0.2794 0.1778)
							(mid -0.249642 0.249642)
							(end -0.1778 0.2794)
						)
						(arc
							(start 0.1778 0.2794)
							(mid 0.249642 0.249642)
							(end 0.2794 0.1778)
						)
						(arc
							(start 0.2794 -0.1778)
							(mid 0.249642 -0.249642)
							(end 0.1778 -0.2794)
						)
					)
					(width 0)
					(fill yes)
				)
			)
		)
	)
	(footprint ""
		(layer "F.Cu")
		(at 193.0908 -34.3916 -90)
		(property "Reference" "R181"
			(at 0 0 270)
			(layer "F.SilkS")
			(hide yes)
			(effects
				(font
					(size 1.27 1.27)
				)
			)
		)
		(property "Value" "2K2R2F-GP"
			(at 0.064008 -3.993896 270)
			(unlocked yes)
			(layer "F.Fab")
			(hide yes)
			(effects
				(font
					(size 1.016 1.016)
					(thickness 0.1524)
				)
			)
		)
		(property "Device Type" "R402H16"
			(at 0.064008 -5.517896 270)
			(unlocked yes)
			(layer "F.Fab")
			(hide yes)
			(effects
				(font
					(size 1.016 1.016)
					(thickness 0.1524)
				)
			)
		)
		(duplicate_pad_numbers_are_jumpers no)
		(fp_line
			(start -0.508 -0.9398)
			(end -0.508 0.9398)
			(stroke
				(width 0.1524)
				(type default)
			)
			(layer "F.SilkS")
		)
		(fp_line
			(start 0.508 -0.9398)
			(end -0.508 -0.9398)
			(stroke
				(width 0.1524)
				(type default)
			)
			(layer "F.SilkS")
		)
		(fp_rect
			(start -0.508 0.9398)
			(end 0.508 -0.9398)
			(stroke
				(width 0)
				(type default)
			)
			(fill no)
			(layer "F.CrtYd")
		)
		(fp_rect
			(start -0.508 0.9398)
			(end 0.508 -0.9398)
			(stroke
				(width 0)
				(type default)
			)
			(fill no)
			(layer "F.Fab")
		)
		(pad "1" smd custom
			(at 0 -0.4445 270)
			(size 0.1397 0.1397)
			(layers "F.Cu" "F.Mask" "F.Paste")
			(net "P1V8_C")
			(options
				(clearance outline)
				(anchor circle)
			)
			(primitives
				(gr_poly
					(pts
						(arc
							(start -0.1778 -0.2794)
							(mid -0.249642 -0.249642)
							(end -0.2794 -0.1778)
						)
						(arc
							(start -0.2794 0.1778)
							(mid -0.249642 0.249642)
							(end -0.1778 0.2794)
						)
						(arc
							(start 0.1778 0.2794)
							(mid 0.249642 0.249642)
							(end 0.2794 0.1778)
						)
						(arc
							(start 0.2794 -0.1778)
							(mid 0.249642 -0.249642)
							(end 0.1778 -0.2794)
						)
					)
					(width 0)
					(fill yes)
				)
			)
		)
		(pad "2" smd custom
			(at 0 0.4445 270)
			(size 0.1397 0.1397)
			(layers "F.Cu" "F.Mask" "F.Paste")
			(net "I2C_IOC_0_SCL")
			(options
				(clearance outline)
				(anchor circle)
			)
			(primitives
				(gr_poly
					(pts
						(arc
							(start -0.1778 -0.2794)
							(mid -0.249642 -0.249642)
							(end -0.2794 -0.1778)
						)
						(arc
							(start -0.2794 0.1778)
							(mid -0.249642 0.249642)
							(end -0.1778 0.2794)
						)
						(arc
							(start 0.1778 0.2794)
							(mid 0.249642 0.249642)
							(end 0.2794 0.1778)
						)
						(arc
							(start 0.2794 -0.1778)
							(mid 0.249642 -0.249642)
							(end 0.1778 -0.2794)
						)
					)
					(width 0)
					(fill yes)
				)
			)
		)
	)
	(footprint ""
		(layer "F.Cu")
		(at 7.2898 -71.9328 90)
		(property "Reference" "R357"
			(at 0 0 90)
			(layer "F.SilkS")
			(hide yes)
			(effects
				(font
					(size 1.27 1.27)
				)
			)
		)
		(property "Value" "4K7R2F-GP"
			(at 0.064008 -3.993896 90)
			(unlocked yes)
			(layer "F.Fab")
			(hide yes)
			(effects
				(font
					(size 1.016 1.016)
					(thickness 0.1524)
				)
			)
		)
		(property "Device Type" "R402H16"
			(at 0.064008 -5.517896 90)
			(unlocked yes)
			(layer "F.Fab")
			(hide yes)
			(effects
				(font
					(size 1.016 1.016)
					(thickness 0.1524)
				)
			)
		)
		(duplicate_pad_numbers_are_jumpers no)
		(fp_line
			(start 0.508 -0.9398)
			(end -0.508 -0.9398)
			(stroke
				(width 0.1524)
				(type default)
			)
			(layer "F.SilkS")
		)
		(fp_line
			(start -0.508 -0.9398)
			(end -0.508 0.9398)
			(stroke
				(width 0.1524)
				(type default)
			)
			(layer "F.SilkS")
		)
		(fp_rect
			(start -0.508 0.9398)
			(end 0.508 -0.9398)
			(stroke
				(width 0)
				(type default)
			)
			(fill no)
			(layer "F.CrtYd")
		)
		(fp_rect
			(start -0.508 0.9398)
			(end 0.508 -0.9398)
			(stroke
				(width 0)
				(type default)
			)
			(fill no)
			(layer "F.Fab")
		)
		(pad "1" smd custom
			(at 0 -0.4445 90)
			(size 0.1397 0.1397)
			(layers "F.Cu" "F.Mask" "F.Paste")
			(net "P3V3")
			(options
				(clearance outline)
				(anchor circle)
			)
			(primitives
				(gr_poly
					(pts
						(arc
							(start -0.1778 -0.2794)
							(mid -0.249642 -0.249642)
							(end -0.2794 -0.1778)
						)
						(arc
							(start -0.2794 0.1778)
							(mid -0.249642 0.249642)
							(end -0.1778 0.2794)
						)
						(arc
							(start 0.1778 0.2794)
							(mid 0.249642 0.249642)
							(end 0.2794 0.1778)
						)
						(arc
							(start 0.2794 -0.1778)
							(mid 0.249642 -0.249642)
							(end 0.1778 -0.2794)
						)
					)
					(width 0)
					(fill yes)
				)
			)
		)
		(pad "2" smd custom
			(at 0 0.4445 90)
			(size 0.1397 0.1397)
			(layers "F.Cu" "F.Mask" "F.Paste")
			(net "FRU_EEPROM_A1")
			(options
				(clearance outline)
				(anchor circle)
			)
			(primitives
				(gr_poly
					(pts
						(arc
							(start -0.1778 -0.2794)
							(mid -0.249642 -0.249642)
							(end -0.2794 -0.1778)
						)
						(arc
							(start -0.2794 0.1778)
							(mid -0.249642 0.249642)
							(end -0.1778 0.2794)
						)
						(arc
							(start 0.1778 0.2794)
							(mid 0.249642 0.249642)
							(end 0.2794 0.1778)
						)
						(arc
							(start 0.2794 -0.1778)
							(mid 0.249642 -0.249642)
							(end 0.1778 -0.2794)
						)
					)
					(width 0)
					(fill yes)
				)
			)
		)
	)
	(footprint ""
		(layer "F.Cu")
		(at 126.110746 -44.74718 180)
		(property "Reference" "C48"
			(at 0 0 180)
			(layer "F.SilkS")
			(hide yes)
			(effects
				(font
					(size 1.27 1.27)
				)
			)
		)
		(property "Value" "SCD01U16V1KX-GP"
			(at -2.8321 -1.7399 180)
			(unlocked yes)
			(layer "F.Fab")
			(hide yes)
			(effects
				(font
					(size 1.016 1.016)
					(thickness 0.1524)
				)
			)
		)
		(property "Device Type" "C0201H13"
			(at -2.8321 -3.2639 180)
			(unlocked yes)
			(layer "F.Fab")
			(hide yes)
			(effects
				(font
					(size 1.016 1.016)
					(thickness 0.1524)
				)
			)
		)
		(duplicate_pad_numbers_are_jumpers no)
		(fp_rect
			(start -0.2794 0.6477)
			(end 0.2794 -0.6477)
			(stroke
				(width 0)
				(type default)
			)
			(fill no)
			(layer "F.CrtYd")
		)
		(fp_rect
			(start -0.2794 0.6477)
			(end 0.2794 -0.6477)
			(stroke
				(width 0)
				(type default)
			)
			(fill no)
			(layer "F.Fab")
		)
		(pad "1" smd custom
			(at 0 -0.2794 180)
			(size 0.0762 0.0762)
			(layers "F.Cu" "F.Mask" "F.Paste")
			(net "PHY_IOC_TO_SCC_40_DN")
			(options
				(clearance outline)
				(anchor circle)
			)
			(primitives
				(gr_poly
					(pts
						(arc
							(start 0.1524 -0.127)
							(mid 0.137521 -0.162921)
							(end 0.1016 -0.1778)
						)
						(arc
							(start -0.1016 -0.1778)
							(mid -0.137521 -0.162921)
							(end -0.1524 -0.127)
						)
						(arc
							(start -0.1524 0.127)
							(mid -0.137521 0.162921)
							(end -0.1016 0.1778)
						)
						(arc
							(start 0.1016 0.1778)
							(mid 0.137521 0.162921)
							(end 0.1524 0.127)
						)
					)
					(width 0)
					(fill yes)
				)
			)
		)
		(pad "2" smd custom
			(at 0 0.2794 180)
			(size 0.0762 0.0762)
			(layers "F.Cu" "F.Mask" "F.Paste")
			(net "PHY_IOC_TO_SCC_C_40_DN")
			(options
				(clearance outline)
				(anchor circle)
			)
			(primitives
				(gr_poly
					(pts
						(arc
							(start 0.1524 -0.127)
							(mid 0.137521 -0.162921)
							(end 0.1016 -0.1778)
						)
						(arc
							(start -0.1016 -0.1778)
							(mid -0.137521 -0.162921)
							(end -0.1524 -0.127)
						)
						(arc
							(start -0.1524 0.127)
							(mid -0.137521 0.162921)
							(end -0.1016 0.1778)
						)
						(arc
							(start 0.1016 0.1778)
							(mid 0.137521 0.162921)
							(end 0.1524 0.127)
						)
					)
					(width 0)
					(fill yes)
				)
			)
		)
	)
	(footprint ""
		(layer "F.Cu")
		(at 111.125 -86.995 180)
		(property "Reference" "R136"
			(at 0 0 180)
			(layer "F.SilkS")
			(hide yes)
			(effects
				(font
					(size 1.27 1.27)
				)
			)
		)
		(property "Value" "4K75R2F-1-GP"
			(at 0.064008 -3.993896 180)
			(unlocked yes)
			(layer "F.Fab")
			(hide yes)
			(effects
				(font
					(size 1.016 1.016)
					(thickness 0.1524)
				)
			)
		)
		(property "Device Type" "R402H16"
			(at 0.064008 -5.517896 180)
			(unlocked yes)
			(layer "F.Fab")
			(hide yes)
			(effects
				(font
					(size 1.016 1.016)
					(thickness 0.1524)
				)
			)
		)
		(duplicate_pad_numbers_are_jumpers no)
		(fp_line
			(start 0.508 -0.9398)
			(end -0.508 -0.9398)
			(stroke
				(width 0.1524)
				(type default)
			)
			(layer "F.SilkS")
		)
		(fp_line
			(start -0.508 -0.9398)
			(end -0.508 0.9398)
			(stroke
				(width 0.1524)
				(type default)
			)
			(layer "F.SilkS")
		)
		(fp_rect
			(start -0.508 0.9398)
			(end 0.508 -0.9398)
			(stroke
				(width 0)
				(type default)
			)
			(fill no)
			(layer "F.CrtYd")
		)
		(fp_rect
			(start -0.508 0.9398)
			(end 0.508 -0.9398)
			(stroke
				(width 0)
				(type default)
			)
			(fill no)
			(layer "F.Fab")
		)
		(pad "1" smd custom
			(at 0 -0.4445 180)
			(size 0.1397 0.1397)
			(layers "F.Cu" "F.Mask" "F.Paste")
			(net "EXP_XM_OE_N")
			(options
				(clearance outline)
				(anchor circle)
			)
			(primitives
				(gr_poly
					(pts
						(arc
							(start -0.1778 -0.2794)
							(mid -0.249642 -0.249642)
							(end -0.2794 -0.1778)
						)
						(arc
							(start -0.2794 0.1778)
							(mid -0.249642 0.249642)
							(end -0.1778 0.2794)
						)
						(arc
							(start 0.1778 0.2794)
							(mid 0.249642 0.249642)
							(end 0.2794 0.1778)
						)
						(arc
							(start 0.2794 -0.1778)
							(mid 0.249642 -0.249642)
							(end 0.1778 -0.2794)
						)
					)
					(width 0)
					(fill yes)
				)
			)
		)
		(pad "2" smd custom
			(at 0 0.4445 180)
			(size 0.1397 0.1397)
			(layers "F.Cu" "F.Mask" "F.Paste")
			(net "P1V8_E")
			(options
				(clearance outline)
				(anchor circle)
			)
			(primitives
				(gr_poly
					(pts
						(arc
							(start -0.1778 -0.2794)
							(mid -0.249642 -0.249642)
							(end -0.2794 -0.1778)
						)
						(arc
							(start -0.2794 0.1778)
							(mid -0.249642 0.249642)
							(end -0.1778 0.2794)
						)
						(arc
							(start 0.1778 0.2794)
							(mid 0.249642 0.249642)
							(end 0.2794 0.1778)
						)
						(arc
							(start 0.2794 -0.1778)
							(mid 0.249642 -0.249642)
							(end 0.1778 -0.2794)
						)
					)
					(width 0)
					(fill yes)
				)
			)
		)
	)
	(footprint ""
		(layer "F.Cu")
		(at 171.323 -103.505 -90)
		(property "Reference" "R605"
			(at 0 0 270)
			(layer "F.SilkS")
			(hide yes)
			(effects
				(font
					(size 1.27 1.27)
				)
			)
		)
		(property "Value" "4K7R2F-GP"
			(at 0.064008 -3.993896 270)
			(unlocked yes)
			(layer "F.Fab")
			(hide yes)
			(effects
				(font
					(size 1.016 1.016)
					(thickness 0.1524)
				)
			)
		)
		(property "Device Type" "R402H16"
			(at 0.064008 -5.517896 270)
			(unlocked yes)
			(layer "F.Fab")
			(hide yes)
			(effects
				(font
					(size 1.016 1.016)
					(thickness 0.1524)
				)
			)
		)
		(duplicate_pad_numbers_are_jumpers no)
		(fp_line
			(start -0.508 -0.9398)
			(end -0.508 0.9398)
			(stroke
				(width 0.1524)
				(type default)
			)
			(layer "F.SilkS")
		)
		(fp_line
			(start 0.508 -0.9398)
			(end -0.508 -0.9398)
			(stroke
				(width 0.1524)
				(type default)
			)
			(layer "F.SilkS")
		)
		(fp_rect
			(start -0.508 0.9398)
			(end 0.508 -0.9398)
			(stroke
				(width 0)
				(type default)
			)
			(fill no)
			(layer "F.CrtYd")
		)
		(fp_rect
			(start -0.508 0.9398)
			(end 0.508 -0.9398)
			(stroke
				(width 0)
				(type default)
			)
			(fill no)
			(layer "F.Fab")
		)
		(pad "1" smd custom
			(at 0 -0.4445 270)
			(size 0.1397 0.1397)
			(layers "F.Cu" "F.Mask" "F.Paste")
			(net "P1V8_C_G")
			(options
				(clearance outline)
				(anchor circle)
			)
			(primitives
				(gr_poly
					(pts
						(arc
							(start -0.1778 -0.2794)
							(mid -0.249642 -0.249642)
							(end -0.2794 -0.1778)
						)
						(arc
							(start -0.2794 0.1778)
							(mid -0.249642 0.249642)
							(end -0.1778 0.2794)
						)
						(arc
							(start 0.1778 0.2794)
							(mid 0.249642 0.249642)
							(end 0.2794 0.1778)
						)
						(arc
							(start 0.2794 -0.1778)
							(mid 0.249642 -0.249642)
							(end 0.1778 -0.2794)
						)
					)
					(width 0)
					(fill yes)
				)
			)
		)
		(pad "2" smd custom
			(at 0 0.4445 270)
			(size 0.1397 0.1397)
			(layers "F.Cu" "F.Mask" "F.Paste")
			(net "P1V8_C")
			(options
				(clearance outline)
				(anchor circle)
			)
			(primitives
				(gr_poly
					(pts
						(arc
							(start -0.1778 -0.2794)
							(mid -0.249642 -0.249642)
							(end -0.2794 -0.1778)
						)
						(arc
							(start -0.2794 0.1778)
							(mid -0.249642 0.249642)
							(end -0.1778 0.2794)
						)
						(arc
							(start 0.1778 0.2794)
							(mid 0.249642 0.249642)
							(end 0.2794 0.1778)
						)
						(arc
							(start 0.2794 -0.1778)
							(mid 0.249642 -0.249642)
							(end 0.1778 -0.2794)
						)
					)
					(width 0)
					(fill yes)
				)
			)
		)
	)
	(footprint ""
		(layer "F.Cu")
		(at 156.718 -120.523)
		(property "Reference" "R311"
			(at 0 0 0)
			(layer "F.SilkS")
			(hide yes)
			(effects
				(font
					(size 1.27 1.27)
				)
			)
		)
		(property "Value" "619KR2F-GP"
			(at 0.064008 -3.993896 0)
			(unlocked yes)
			(layer "F.Fab")
			(hide yes)
			(effects
				(font
					(size 1.016 1.016)
					(thickness 0.1524)
				)
			)
		)
		(property "Device Type" "R402H16"
			(at 0.064008 -5.517896 0)
			(unlocked yes)
			(layer "F.Fab")
			(hide yes)
			(effects
				(font
					(size 1.016 1.016)
					(thickness 0.1524)
				)
			)
		)
		(duplicate_pad_numbers_are_jumpers no)
		(fp_line
			(start -0.508 -0.9398)
			(end -0.508 0.9398)
			(stroke
				(width 0.1524)
				(type default)
			)
			(layer "F.SilkS")
		)
		(fp_line
			(start 0.508 -0.9398)
			(end -0.508 -0.9398)
			(stroke
				(width 0.1524)
				(type default)
			)
			(layer "F.SilkS")
		)
		(fp_rect
			(start -0.508 0.9398)
			(end 0.508 -0.9398)
			(stroke
				(width 0)
				(type default)
			)
			(fill no)
			(layer "F.CrtYd")
		)
		(fp_rect
			(start -0.508 0.9398)
			(end 0.508 -0.9398)
			(stroke
				(width 0)
				(type default)
			)
			(fill no)
			(layer "F.Fab")
		)
		(pad "1" smd custom
			(at 0 -0.4445)
			(size 0.1397 0.1397)
			(layers "F.Cu" "F.Mask" "F.Paste")
			(net "AGND_P1V5_E")
			(options
				(clearance outline)
				(anchor circle)
			)
			(primitives
				(gr_poly
					(pts
						(arc
							(start -0.1778 -0.2794)
							(mid -0.249642 -0.249642)
							(end -0.2794 -0.1778)
						)
						(arc
							(start -0.2794 0.1778)
							(mid -0.249642 0.249642)
							(end -0.1778 0.2794)
						)
						(arc
							(start 0.1778 0.2794)
							(mid 0.249642 0.249642)
							(end 0.2794 0.1778)
						)
						(arc
							(start 0.2794 -0.1778)
							(mid 0.249642 -0.249642)
							(end 0.1778 -0.2794)
						)
					)
					(width 0)
					(fill yes)
				)
			)
		)
		(pad "2" smd custom
			(at 0 0.4445)
			(size 0.1397 0.1397)
			(layers "F.Cu" "F.Mask" "F.Paste")
			(net "P1V5_E_RF")
			(options
				(clearance outline)
				(anchor circle)
			)
			(primitives
				(gr_poly
					(pts
						(arc
							(start -0.1778 -0.2794)
							(mid -0.249642 -0.249642)
							(end -0.2794 -0.1778)
						)
						(arc
							(start -0.2794 0.1778)
							(mid -0.249642 0.249642)
							(end -0.1778 0.2794)
						)
						(arc
							(start 0.1778 0.2794)
							(mid 0.249642 0.249642)
							(end 0.2794 0.1778)
						)
						(arc
							(start 0.2794 -0.1778)
							(mid 0.249642 -0.249642)
							(end 0.1778 -0.2794)
						)
					)
					(width 0)
					(fill yes)
				)
			)
		)
	)
	(footprint ""
		(layer "F.Cu")
		(at 65.072514 -94.444058 90)
		(property "Reference" "R503"
			(at 0 0 90)
			(layer "F.SilkS")
			(hide yes)
			(effects
				(font
					(size 1.27 1.27)
				)
			)
		)
		(property "Value" "866KR2F-GP"
			(at 0.064008 -3.993896 90)
			(unlocked yes)
			(layer "F.Fab")
			(hide yes)
			(effects
				(font
					(size 1.016 1.016)
					(thickness 0.1524)
				)
			)
		)
		(property "Device Type" "R402H16"
			(at 0.064008 -5.517896 90)
			(unlocked yes)
			(layer "F.Fab")
			(hide yes)
			(effects
				(font
					(size 1.016 1.016)
					(thickness 0.1524)
				)
			)
		)
		(duplicate_pad_numbers_are_jumpers no)
		(fp_line
			(start 0.508 -0.9398)
			(end -0.508 -0.9398)
			(stroke
				(width 0.1524)
				(type default)
			)
			(layer "F.SilkS")
		)
		(fp_line
			(start -0.508 -0.9398)
			(end -0.508 0.9398)
			(stroke
				(width 0.1524)
				(type default)
			)
			(layer "F.SilkS")
		)
		(fp_rect
			(start -0.508 0.9398)
			(end 0.508 -0.9398)
			(stroke
				(width 0)
				(type default)
			)
			(fill no)
			(layer "F.CrtYd")
		)
		(fp_rect
			(start -0.508 0.9398)
			(end 0.508 -0.9398)
			(stroke
				(width 0)
				(type default)
			)
			(fill no)
			(layer "F.Fab")
		)
		(pad "1" smd custom
			(at 0 -0.4445 90)
			(size 0.1397 0.1397)
			(layers "F.Cu" "F.Mask" "F.Paste")
			(net "P3V3_VREG")
			(options
				(clearance outline)
				(anchor circle)
			)
			(primitives
				(gr_poly
					(pts
						(arc
							(start -0.1778 -0.2794)
							(mid -0.249642 -0.249642)
							(end -0.2794 -0.1778)
						)
						(arc
							(start -0.2794 0.1778)
							(mid -0.249642 0.249642)
							(end -0.1778 0.2794)
						)
						(arc
							(start 0.1778 0.2794)
							(mid 0.249642 0.249642)
							(end 0.2794 0.1778)
						)
						(arc
							(start 0.2794 -0.1778)
							(mid 0.249642 -0.249642)
							(end 0.1778 -0.2794)
						)
					)
					(width 0)
					(fill yes)
				)
			)
		)
		(pad "2" smd custom
			(at 0 0.4445 90)
			(size 0.1397 0.1397)
			(layers "F.Cu" "F.Mask" "F.Paste")
			(net "P3V3_RF")
			(options
				(clearance outline)
				(anchor circle)
			)
			(primitives
				(gr_poly
					(pts
						(arc
							(start -0.1778 -0.2794)
							(mid -0.249642 -0.249642)
							(end -0.2794 -0.1778)
						)
						(arc
							(start -0.2794 0.1778)
							(mid -0.249642 0.249642)
							(end -0.1778 0.2794)
						)
						(arc
							(start 0.1778 0.2794)
							(mid 0.249642 0.249642)
							(end 0.2794 0.1778)
						)
						(arc
							(start 0.2794 -0.1778)
							(mid 0.249642 -0.249642)
							(end 0.1778 -0.2794)
						)
					)
					(width 0)
					(fill yes)
				)
			)
		)
	)
	(footprint ""
		(layer "F.Cu")
		(at 134.99973 -134.999984)
		(property "Reference" ""
			(at 0 0 0)
			(layer "F.SilkS")
			(hide yes)
			(effects
				(font
					(size 1.27 1.27)
				)
			)
		)
		(property "Value" "*"
			(at -6.38175 0.19685 0)
			(unlocked yes)
			(layer "F.Fab")
			(hide yes)
			(effects
				(font
					(size 1.016 1.016)
					(thickness 0.1524)
				)
			)
		)
		(duplicate_pad_numbers_are_jumpers no)
		(fp_poly
			(pts
				(arc
					(start 5.0673 0)
					(mid -5.0673 0)
					(end 5.0673 0)
				)
			)
			(stroke
				(width 0)
				(type default)
			)
			(fill no)
			(layer "B.CrtYd")
		)
		(fp_poly
			(pts
				(arc
					(start 5.0673 0)
					(mid -5.0673 0)
					(end 5.0673 0)
				)
			)
			(stroke
				(width 0)
				(type default)
			)
			(fill no)
			(layer "F.CrtYd")
		)
		(fp_poly
			(pts
				(arc
					(start 5.0673 0)
					(mid -5.0673 0)
					(end 5.0673 0)
				)
			)
			(stroke
				(width 0)
				(type default)
			)
			(fill no)
			(layer "B.Fab")
		)
		(fp_poly
			(pts
				(arc
					(start 5.0673 0)
					(mid -5.0673 0)
					(end 5.0673 0)
				)
			)
			(stroke
				(width 0)
				(type default)
			)
			(fill no)
			(layer "F.Fab")
		)
		(pad "1" thru_hole circle
			(at 0 0)
			(size 9.525 9.525)
			(drill 3.5052)
			(layers "*.Cu" "*.Mask")
			(remove_unused_layers no)
			(net "Net_6")
			(clearance -2.5019)
			(thermal_gap 0.3048)
			(padstack
				(mode front_inner_back)
				(layer "Inner"
					(shape circle)
					(size 3.9116 3.9116)
					(clearance 0.3048)
				)
				(layer "B.Cu"
					(shape circle)
					(size 9.525 9.525)
					(clearance -2.5019)
				)
			)
		)
	)
	(footprint ""
		(layer "F.Cu")
		(at 191.85382 -52.3748 -90)
		(property "Reference" "R215"
			(at 0 0 270)
			(layer "F.SilkS")
			(hide yes)
			(effects
				(font
					(size 1.27 1.27)
				)
			)
		)
		(property "Value" "10KR2F-2-GP"
			(at 0.064008 -3.993896 270)
			(unlocked yes)
			(layer "F.Fab")
			(hide yes)
			(effects
				(font
					(size 1.016 1.016)
					(thickness 0.1524)
				)
			)
		)
		(property "Device Type" "R402H16"
			(at 0.064008 -5.517896 270)
			(unlocked yes)
			(layer "F.Fab")
			(hide yes)
			(effects
				(font
					(size 1.016 1.016)
					(thickness 0.1524)
				)
			)
		)
		(duplicate_pad_numbers_are_jumpers no)
		(fp_line
			(start -0.508 -0.9398)
			(end -0.508 0.9398)
			(stroke
				(width 0.1524)
				(type default)
			)
			(layer "F.SilkS")
		)
		(fp_line
			(start 0.508 -0.9398)
			(end -0.508 -0.9398)
			(stroke
				(width 0.1524)
				(type default)
			)
			(layer "F.SilkS")
		)
		(fp_rect
			(start -0.508 0.9398)
			(end 0.508 -0.9398)
			(stroke
				(width 0)
				(type default)
			)
			(fill no)
			(layer "F.CrtYd")
		)
		(fp_rect
			(start -0.508 0.9398)
			(end 0.508 -0.9398)
			(stroke
				(width 0)
				(type default)
			)
			(fill no)
			(layer "F.Fab")
		)
		(pad "1" smd custom
			(at 0 -0.4445 270)
			(size 0.1397 0.1397)
			(layers "F.Cu" "F.Mask" "F.Paste")
			(net "P1V8_C")
			(options
				(clearance outline)
				(anchor circle)
			)
			(primitives
				(gr_poly
					(pts
						(arc
							(start -0.1778 -0.2794)
							(mid -0.249642 -0.249642)
							(end -0.2794 -0.1778)
						)
						(arc
							(start -0.2794 0.1778)
							(mid -0.249642 0.249642)
							(end -0.1778 0.2794)
						)
						(arc
							(start 0.1778 0.2794)
							(mid 0.249642 0.249642)
							(end 0.2794 0.1778)
						)
						(arc
							(start 0.2794 -0.1778)
							(mid 0.249642 -0.249642)
							(end 0.1778 -0.2794)
						)
					)
					(width 0)
					(fill yes)
				)
			)
		)
		(pad "2" smd custom
			(at 0 0.4445 270)
			(size 0.1397 0.1397)
			(layers "F.Cu" "F.Mask" "F.Paste")
			(net "XM_ADDR_7")
			(options
				(clearance outline)
				(anchor circle)
			)
			(primitives
				(gr_poly
					(pts
						(arc
							(start -0.1778 -0.2794)
							(mid -0.249642 -0.249642)
							(end -0.2794 -0.1778)
						)
						(arc
							(start -0.2794 0.1778)
							(mid -0.249642 0.249642)
							(end -0.1778 0.2794)
						)
						(arc
							(start 0.1778 0.2794)
							(mid 0.249642 0.249642)
							(end 0.2794 0.1778)
						)
						(arc
							(start 0.2794 -0.1778)
							(mid 0.249642 -0.249642)
							(end 0.1778 -0.2794)
						)
					)
					(width 0)
					(fill yes)
				)
			)
		)
	)
	(footprint ""
		(layer "F.Cu")
		(at 62.76975 -123.205494)
		(property "Reference" "R511"
			(at 0 0 0)
			(layer "F.SilkS")
			(hide yes)
			(effects
				(font
					(size 1.27 1.27)
				)
			)
		)
		(property "Value" "0R5J-5-GP"
			(at 0 -8.9535 0)
			(unlocked yes)
			(layer "F.Fab")
			(hide yes)
			(effects
				(font
					(size 1.27 1.016)
					(thickness 0.1524)
				)
			)
		)
		(property "Device Type" "R805H24"
			(at 0 -10.6299 0)
			(unlocked yes)
			(layer "F.Fab")
			(hide yes)
			(effects
				(font
					(size 1.27 1.016)
					(thickness 0.1524)
				)
			)
		)
		(duplicate_pad_numbers_are_jumpers no)
		(fp_line
			(start -0.889 -1.7018)
			(end -0.889 0.2794)
			(stroke
				(width 0.1524)
				(type default)
			)
			(layer "F.SilkS")
		)
		(fp_line
			(start -0.889 0.0762)
			(end -0.889 1.7018)
			(stroke
				(width 0.1524)
				(type default)
			)
			(layer "F.SilkS")
		)
		(fp_line
			(start -0.889 1.7018)
			(end 0.889 1.7018)
			(stroke
				(width 0.1524)
				(type default)
			)
			(layer "F.SilkS")
		)
		(fp_line
			(start 0.889 -1.7018)
			(end -0.889 -1.7018)
			(stroke
				(width 0.1524)
				(type default)
			)
			(layer "F.SilkS")
		)
		(fp_line
			(start 0.889 -1.7018)
			(end 0.889 -0.381)
			(stroke
				(width 0.1524)
				(type default)
			)
			(layer "F.SilkS")
		)
		(fp_line
			(start 0.889 1.7018)
			(end 0.889 -0.508)
			(stroke
				(width 0.1524)
				(type default)
			)
			(layer "F.SilkS")
		)
		(fp_poly
			(pts
				(xy 0.9652 -1.778) (xy 0.9652 1.778) (xy -0.9652 1.778) (xy -0.9652 -1.778)
			)
			(stroke
				(width 0)
				(type default)
			)
			(fill no)
			(layer "F.CrtYd")
		)
		(fp_rect
			(start -0.9652 1.778)
			(end 0.9652 -1.778)
			(stroke
				(width 0)
				(type default)
			)
			(fill no)
			(layer "F.Fab")
		)
		(pad "1" smd rect
			(at 0 -0.9652)
			(size 1.397 1.143)
			(layers "F.Cu" "F.Mask" "F.Paste")
			(net "P3V3")
		)
		(pad "2" smd rect
			(at 0 0.9652)
			(size 1.397 1.143)
			(layers "F.Cu" "F.Mask" "F.Paste")
			(net "P3V3_OUT")
		)
	)
	(footprint ""
		(layer "F.Cu")
		(at 19.2278 -78.613 90)
		(property "Reference" "R347"
			(at 0 0 90)
			(layer "F.SilkS")
			(hide yes)
			(effects
				(font
					(size 1.27 1.27)
				)
			)
		)
		(property "Value" "0R2J-2-GP"
			(at 0.064008 -3.993896 90)
			(unlocked yes)
			(layer "F.Fab")
			(hide yes)
			(effects
				(font
					(size 1.016 1.016)
					(thickness 0.1524)
				)
			)
		)
		(property "Device Type" "R402H16"
			(at 0.064008 -5.517896 90)
			(unlocked yes)
			(layer "F.Fab")
			(hide yes)
			(effects
				(font
					(size 1.016 1.016)
					(thickness 0.1524)
				)
			)
		)
		(duplicate_pad_numbers_are_jumpers no)
		(fp_line
			(start 0.508 -0.9398)
			(end -0.508 -0.9398)
			(stroke
				(width 0.1524)
				(type default)
			)
			(layer "F.SilkS")
		)
		(fp_line
			(start -0.508 -0.9398)
			(end -0.508 0.9398)
			(stroke
				(width 0.1524)
				(type default)
			)
			(layer "F.SilkS")
		)
		(fp_rect
			(start -0.508 0.9398)
			(end 0.508 -0.9398)
			(stroke
				(width 0)
				(type default)
			)
			(fill no)
			(layer "F.CrtYd")
		)
		(fp_rect
			(start -0.508 0.9398)
			(end 0.508 -0.9398)
			(stroke
				(width 0)
				(type default)
			)
			(fill no)
			(layer "F.Fab")
		)
		(pad "1" smd custom
			(at 0 -0.4445 90)
			(size 0.1397 0.1397)
			(layers "F.Cu" "F.Mask" "F.Paste")
			(net "EXP_EEPROM_SCL")
			(options
				(clearance outline)
				(anchor circle)
			)
			(primitives
				(gr_poly
					(pts
						(arc
							(start -0.1778 -0.2794)
							(mid -0.249642 -0.249642)
							(end -0.2794 -0.1778)
						)
						(arc
							(start -0.2794 0.1778)
							(mid -0.249642 0.249642)
							(end -0.1778 0.2794)
						)
						(arc
							(start 0.1778 0.2794)
							(mid 0.249642 0.249642)
							(end 0.2794 0.1778)
						)
						(arc
							(start 0.2794 -0.1778)
							(mid 0.249642 -0.249642)
							(end 0.1778 -0.2794)
						)
					)
					(width 0)
					(fill yes)
				)
			)
		)
		(pad "2" smd custom
			(at 0 0.4445 90)
			(size 0.1397 0.1397)
			(layers "F.Cu" "F.Mask" "F.Paste")
			(net "I2C_SCC_SCL2")
			(options
				(clearance outline)
				(anchor circle)
			)
			(primitives
				(gr_poly
					(pts
						(arc
							(start -0.1778 -0.2794)
							(mid -0.249642 -0.249642)
							(end -0.2794 -0.1778)
						)
						(arc
							(start -0.2794 0.1778)
							(mid -0.249642 0.249642)
							(end -0.1778 0.2794)
						)
						(arc
							(start 0.1778 0.2794)
							(mid 0.249642 0.249642)
							(end 0.2794 0.1778)
						)
						(arc
							(start 0.2794 -0.1778)
							(mid 0.249642 -0.249642)
							(end 0.1778 -0.2794)
						)
					)
					(width 0)
					(fill yes)
				)
			)
		)
	)
	(footprint ""
		(layer "F.Cu")
		(at 159.2326 -111.0996)
		(property "Reference" "C698"
			(at 0 0 0)
			(layer "F.SilkS")
			(hide yes)
			(effects
				(font
					(size 1.27 1.27)
				)
			)
		)
		(property "Value" "SC10U16V5KX-7-GP-U"
			(at -0.0762 -6.1214 0)
			(unlocked yes)
			(layer "F.Fab")
			(hide yes)
			(effects
				(font
					(size 1.016 1.016)
					(thickness 0.1524)
				)
			)
		)
		(property "Device Type" "C805H58"
			(at -0.0762 -8.1534 0)
			(unlocked yes)
			(layer "F.Fab")
			(hide yes)
			(effects
				(font
					(size 1.016 1.016)
					(thickness 0.1524)
				)
			)
		)
		(duplicate_pad_numbers_are_jumpers no)
		(fp_line
			(start 0.635 0)
			(end -0.635 0)
			(stroke
				(width 0.508)
				(type default)
			)
			(layer "F.SilkS")
		)
		(fp_rect
			(start -0.9652 1.778)
			(end 0.9652 -1.778)
			(stroke
				(width 0)
				(type default)
			)
			(fill no)
			(layer "F.CrtYd")
		)
		(fp_poly
			(pts
				(xy -0.9652 -1.778) (xy 0.9652 -1.778) (xy 0.9652 1.778) (xy -0.9652 1.778)
			)
			(stroke
				(width 0)
				(type default)
			)
			(fill no)
			(layer "F.Fab")
		)
		(pad "1" smd rect
			(at 0 -0.9652)
			(size 1.397 1.143)
			(layers "F.Cu" "F.Mask" "F.Paste")
			(net "P12V_STBY_VIN_U11")
		)
		(pad "2" smd rect
			(at 0 0.9652)
			(size 1.397 1.143)
			(layers "F.Cu" "F.Mask" "F.Paste")
			(net "GND")
		)
	)
	(footprint ""
		(layer "F.Cu")
		(at 131.572 -89.7001)
		(property "Reference" "R119"
			(at 0 0 0)
			(layer "F.SilkS")
			(hide yes)
			(effects
				(font
					(size 1.27 1.27)
				)
			)
		)
		(property "Value" "4K75R2F-1-GP"
			(at 0.064008 -3.993896 0)
			(unlocked yes)
			(layer "F.Fab")
			(hide yes)
			(effects
				(font
					(size 1.016 1.016)
					(thickness 0.1524)
				)
			)
		)
		(property "Device Type" "R402H16"
			(at 0.064008 -5.517896 0)
			(unlocked yes)
			(layer "F.Fab")
			(hide yes)
			(effects
				(font
					(size 1.016 1.016)
					(thickness 0.1524)
				)
			)
		)
		(duplicate_pad_numbers_are_jumpers no)
		(fp_line
			(start -0.508 -0.9398)
			(end -0.508 0.9398)
			(stroke
				(width 0.1524)
				(type default)
			)
			(layer "F.SilkS")
		)
		(fp_line
			(start 0.508 -0.9398)
			(end -0.508 -0.9398)
			(stroke
				(width 0.1524)
				(type default)
			)
			(layer "F.SilkS")
		)
		(fp_rect
			(start -0.508 0.9398)
			(end 0.508 -0.9398)
			(stroke
				(width 0)
				(type default)
			)
			(fill no)
			(layer "F.CrtYd")
		)
		(fp_rect
			(start -0.508 0.9398)
			(end 0.508 -0.9398)
			(stroke
				(width 0)
				(type default)
			)
			(fill no)
			(layer "F.Fab")
		)
		(pad "1" smd custom
			(at 0 -0.4445)
			(size 0.1397 0.1397)
			(layers "F.Cu" "F.Mask" "F.Paste")
			(net "P1V8_E")
			(options
				(clearance outline)
				(anchor circle)
			)
			(primitives
				(gr_poly
					(pts
						(arc
							(start -0.1778 -0.2794)
							(mid -0.249642 -0.249642)
							(end -0.2794 -0.1778)
						)
						(arc
							(start -0.2794 0.1778)
							(mid -0.249642 0.249642)
							(end -0.1778 0.2794)
						)
						(arc
							(start 0.1778 0.2794)
							(mid 0.249642 0.249642)
							(end 0.2794 0.1778)
						)
						(arc
							(start 0.2794 -0.1778)
							(mid 0.249642 -0.249642)
							(end 0.1778 -0.2794)
						)
					)
					(width 0)
					(fill yes)
				)
			)
		)
		(pad "2" smd custom
			(at 0 0.4445)
			(size 0.1397 0.1397)
			(layers "F.Cu" "F.Mask" "F.Paste")
			(net "UART_CTS")
			(options
				(clearance outline)
				(anchor circle)
			)
			(primitives
				(gr_poly
					(pts
						(arc
							(start -0.1778 -0.2794)
							(mid -0.249642 -0.249642)
							(end -0.2794 -0.1778)
						)
						(arc
							(start -0.2794 0.1778)
							(mid -0.249642 0.249642)
							(end -0.1778 0.2794)
						)
						(arc
							(start 0.1778 0.2794)
							(mid 0.249642 0.249642)
							(end 0.2794 0.1778)
						)
						(arc
							(start 0.2794 -0.1778)
							(mid 0.249642 -0.249642)
							(end 0.1778 -0.2794)
						)
					)
					(width 0)
					(fill yes)
				)
			)
		)
	)
	(footprint ""
		(layer "F.Cu")
		(at 70.485 -50.292 90)
		(property "Reference" "L13"
			(at 0 0 90)
			(layer "F.SilkS")
			(hide yes)
			(effects
				(font
					(size 1.27 1.27)
				)
			)
		)
		(property "Value" "MPZ2012S300AT-GP"
			(at 0 -4.2418 90)
			(unlocked yes)
			(layer "F.Fab")
			(hide yes)
			(effects
				(font
					(size 1.016 1.016)
					(thickness 0.1524)
				)
			)
		)
		(property "Device Type" "L805H42"
			(at 0 -5.7912 90)
			(unlocked yes)
			(layer "F.Fab")
			(hide yes)
			(effects
				(font
					(size 1.016 1.016)
					(thickness 0.1524)
				)
			)
		)
		(duplicate_pad_numbers_are_jumpers no)
		(fp_line
			(start 0.889 -1.7018)
			(end 0.889 1.7018)
			(stroke
				(width 0.1524)
				(type default)
			)
			(layer "F.SilkS")
		)
		(fp_line
			(start -0.889 -1.7018)
			(end 0.889 -1.7018)
			(stroke
				(width 0.1524)
				(type default)
			)
			(layer "F.SilkS")
		)
		(fp_line
			(start 0.889 1.7018)
			(end -0.889 1.7018)
			(stroke
				(width 0.1524)
				(type default)
			)
			(layer "F.SilkS")
		)
		(fp_line
			(start -0.889 1.7018)
			(end -0.889 -1.7018)
			(stroke
				(width 0.1524)
				(type default)
			)
			(layer "F.SilkS")
		)
		(fp_rect
			(start -0.9652 1.778)
			(end 0.9652 -1.778)
			(stroke
				(width 0)
				(type default)
			)
			(fill no)
			(layer "F.CrtYd")
		)
		(fp_rect
			(start -0.9652 1.778)
			(end 0.9652 -1.778)
			(stroke
				(width 0)
				(type default)
			)
			(fill no)
			(layer "F.Fab")
		)
		(pad "1" smd rect
			(at 0 -0.9652 90)
			(size 1.397 1.143)
			(layers "F.Cu" "F.Mask" "F.Paste")
			(net "P0V9")
		)
		(pad "2" smd rect
			(at 0 0.9652 90)
			(size 1.397 1.143)
			(layers "F.Cu" "F.Mask" "F.Paste")
			(net "GB_VDDA")
		)
	)
	(footprint ""
		(layer "F.Cu")
		(at 61.654182 -17.401794)
		(property "Reference" "C743"
			(at 0 0 0)
			(layer "F.SilkS")
			(hide yes)
			(effects
				(font
					(size 1.27 1.27)
				)
			)
		)
		(property "Value" "SCD1U16V2KX-3GP"
			(at 1.1811 -2.7051 0)
			(unlocked yes)
			(layer "F.Fab")
			(hide yes)
			(effects
				(font
					(size 1.016 1.016)
					(thickness 0.1524)
				)
			)
		)
		(property "Device Type" "C402H22"
			(at 1.1811 -4.2291 0)
			(unlocked yes)
			(layer "F.Fab")
			(hide yes)
			(effects
				(font
					(size 1.016 1.016)
					(thickness 0.1524)
				)
			)
		)
		(duplicate_pad_numbers_are_jumpers no)
		(fp_rect
			(start -0.4318 0.9525)
			(end 0.4318 -0.9525)
			(stroke
				(width 0)
				(type default)
			)
			(fill no)
			(layer "F.CrtYd")
		)
		(fp_rect
			(start -0.4318 0.9525)
			(end 0.4318 -0.9525)
			(stroke
				(width 0)
				(type default)
			)
			(fill no)
			(layer "F.Fab")
		)
		(pad "1" smd custom
			(at 0 -0.4445)
			(size 0.1524 0.1524)
			(layers "F.Cu" "F.Mask" "F.Paste")
			(net "U49_OE")
			(options
				(clearance outline)
				(anchor circle)
			)
			(primitives
				(gr_poly
					(pts
						(arc
							(start 0.3048 -0.2032)
							(mid 0.275042 -0.275042)
							(end 0.2032 -0.3048)
						)
						(arc
							(start -0.2032 -0.3048)
							(mid -0.275042 -0.275042)
							(end -0.3048 -0.2032)
						)
						(arc
							(start -0.3048 0.2032)
							(mid -0.275042 0.275042)
							(end -0.2032 0.3048)
						)
						(arc
							(start 0.2032 0.3048)
							(mid 0.275042 0.275042)
							(end 0.3048 0.2032)
						)
					)
					(width 0)
					(fill yes)
				)
			)
		)
		(pad "2" smd custom
			(at 0 0.4445)
			(size 0.1524 0.1524)
			(layers "F.Cu" "F.Mask" "F.Paste")
			(net "GND")
			(options
				(clearance outline)
				(anchor circle)
			)
			(primitives
				(gr_poly
					(pts
						(arc
							(start 0.3048 -0.2032)
							(mid 0.275042 -0.275042)
							(end 0.2032 -0.3048)
						)
						(arc
							(start -0.2032 -0.3048)
							(mid -0.275042 -0.275042)
							(end -0.3048 -0.2032)
						)
						(arc
							(start -0.3048 0.2032)
							(mid -0.275042 0.275042)
							(end -0.2032 0.3048)
						)
						(arc
							(start 0.2032 0.3048)
							(mid 0.275042 0.275042)
							(end 0.3048 0.2032)
						)
					)
					(width 0)
					(fill yes)
				)
			)
		)
	)
	(footprint ""
		(layer "F.Cu")
		(at 194.1322 -41.7068 90)
		(property "Reference" "R171"
			(at 0 0 90)
			(layer "F.SilkS")
			(hide yes)
			(effects
				(font
					(size 1.27 1.27)
				)
			)
		)
		(property "Value" "10KR2F-2-GP"
			(at 0.064008 -3.993896 90)
			(unlocked yes)
			(layer "F.Fab")
			(hide yes)
			(effects
				(font
					(size 1.016 1.016)
					(thickness 0.1524)
				)
			)
		)
		(property "Device Type" "R402H16"
			(at 0.064008 -5.517896 90)
			(unlocked yes)
			(layer "F.Fab")
			(hide yes)
			(effects
				(font
					(size 1.016 1.016)
					(thickness 0.1524)
				)
			)
		)
		(duplicate_pad_numbers_are_jumpers no)
		(fp_line
			(start 0.508 -0.9398)
			(end -0.508 -0.9398)
			(stroke
				(width 0.1524)
				(type default)
			)
			(layer "F.SilkS")
		)
		(fp_line
			(start -0.508 -0.9398)
			(end -0.508 0.9398)
			(stroke
				(width 0.1524)
				(type default)
			)
			(layer "F.SilkS")
		)
		(fp_rect
			(start -0.508 0.9398)
			(end 0.508 -0.9398)
			(stroke
				(width 0)
				(type default)
			)
			(fill no)
			(layer "F.CrtYd")
		)
		(fp_rect
			(start -0.508 0.9398)
			(end 0.508 -0.9398)
			(stroke
				(width 0)
				(type default)
			)
			(fill no)
			(layer "F.Fab")
		)
		(pad "1" smd custom
			(at 0 -0.4445 90)
			(size 0.1397 0.1397)
			(layers "F.Cu" "F.Mask" "F.Paste")
			(net "IOC_CLK_SEL0")
			(options
				(clearance outline)
				(anchor circle)
			)
			(primitives
				(gr_poly
					(pts
						(arc
							(start -0.1778 -0.2794)
							(mid -0.249642 -0.249642)
							(end -0.2794 -0.1778)
						)
						(arc
							(start -0.2794 0.1778)
							(mid -0.249642 0.249642)
							(end -0.1778 0.2794)
						)
						(arc
							(start 0.1778 0.2794)
							(mid 0.249642 0.249642)
							(end 0.2794 0.1778)
						)
						(arc
							(start 0.2794 -0.1778)
							(mid 0.249642 -0.249642)
							(end 0.1778 -0.2794)
						)
					)
					(width 0)
					(fill yes)
				)
			)
		)
		(pad "2" smd custom
			(at 0 0.4445 90)
			(size 0.1397 0.1397)
			(layers "F.Cu" "F.Mask" "F.Paste")
			(net "P1V8_C")
			(options
				(clearance outline)
				(anchor circle)
			)
			(primitives
				(gr_poly
					(pts
						(arc
							(start -0.1778 -0.2794)
							(mid -0.249642 -0.249642)
							(end -0.2794 -0.1778)
						)
						(arc
							(start -0.2794 0.1778)
							(mid -0.249642 0.249642)
							(end -0.1778 0.2794)
						)
						(arc
							(start 0.1778 0.2794)
							(mid 0.249642 0.249642)
							(end 0.2794 0.1778)
						)
						(arc
							(start 0.2794 -0.1778)
							(mid 0.249642 -0.249642)
							(end 0.1778 -0.2794)
						)
					)
					(width 0)
					(fill yes)
				)
			)
		)
	)
	(footprint ""
		(layer "F.Cu")
		(at 124.6632 -109.93628)
		(property "Reference" "TP152"
			(at 0 0 0)
			(layer "F.SilkS")
			(hide yes)
			(effects
				(font
					(size 1.27 1.27)
				)
			)
		)
		(property "Value" "TPAD28-2-GP"
			(at -0.0127 -1.6637 0)
			(unlocked yes)
			(layer "F.Fab")
			(hide yes)
			(effects
				(font
					(size 1.016 1.016)
					(thickness 0.1524)
				)
			)
		)
		(property "Device Type" "TPAD28"
			(at -0.0127 -3.1877 0)
			(unlocked yes)
			(layer "F.Fab")
			(hide yes)
			(effects
				(font
					(size 1.016 1.016)
					(thickness 0.1524)
				)
			)
		)
		(duplicate_pad_numbers_are_jumpers no)
		(fp_poly
			(pts
				(arc
					(start 0.3556 0)
					(mid -0.3556 0)
					(end 0.3556 0)
				)
			)
			(stroke
				(width 0)
				(type default)
			)
			(fill no)
			(layer "F.CrtYd")
		)
		(fp_poly
			(pts
				(arc
					(start 0.6096 0)
					(mid -0.6096 0)
					(end 0.6096 0)
				)
			)
			(stroke
				(width 0)
				(type default)
			)
			(fill no)
			(layer "F.Fab")
		)
		(pad "1" smd circle
			(at 0 0)
			(size 0.7112 0.7112)
			(layers "F.Cu" "F.Mask" "F.Paste")
			(net "INT_C2_CONN1")
		)
	)
	(footprint ""
		(layer "F.Cu")
		(at 160.274 -83.224116 90)
		(property "Reference" "C526"
			(at 0 0 90)
			(layer "F.SilkS")
			(hide yes)
			(effects
				(font
					(size 1.27 1.27)
				)
			)
		)
		(property "Value" "SCD1U16V2KX-3GP"
			(at 1.1811 -2.7051 90)
			(unlocked yes)
			(layer "F.Fab")
			(hide yes)
			(effects
				(font
					(size 1.016 1.016)
					(thickness 0.1524)
				)
			)
		)
		(property "Device Type" "C402H22"
			(at 1.1811 -4.2291 90)
			(unlocked yes)
			(layer "F.Fab")
			(hide yes)
			(effects
				(font
					(size 1.016 1.016)
					(thickness 0.1524)
				)
			)
		)
		(duplicate_pad_numbers_are_jumpers no)
		(fp_rect
			(start -0.4318 0.9525)
			(end 0.4318 -0.9525)
			(stroke
				(width 0)
				(type default)
			)
			(fill no)
			(layer "F.CrtYd")
		)
		(fp_rect
			(start -0.4318 0.9525)
			(end 0.4318 -0.9525)
			(stroke
				(width 0)
				(type default)
			)
			(fill no)
			(layer "F.Fab")
		)
		(pad "1" smd custom
			(at 0 -0.4445 90)
			(size 0.1524 0.1524)
			(layers "F.Cu" "F.Mask" "F.Paste")
			(net "P0V9_SENSE")
			(options
				(clearance outline)
				(anchor circle)
			)
			(primitives
				(gr_poly
					(pts
						(arc
							(start 0.3048 -0.2032)
							(mid 0.275042 -0.275042)
							(end 0.2032 -0.3048)
						)
						(arc
							(start -0.2032 -0.3048)
							(mid -0.275042 -0.275042)
							(end -0.3048 -0.2032)
						)
						(arc
							(start -0.3048 0.2032)
							(mid -0.275042 0.275042)
							(end -0.2032 0.3048)
						)
						(arc
							(start 0.2032 0.3048)
							(mid 0.275042 0.275042)
							(end 0.3048 0.2032)
						)
					)
					(width 0)
					(fill yes)
				)
			)
		)
		(pad "2" smd custom
			(at 0 0.4445 90)
			(size 0.1524 0.1524)
			(layers "F.Cu" "F.Mask" "F.Paste")
			(net "GND")
			(options
				(clearance outline)
				(anchor circle)
			)
			(primitives
				(gr_poly
					(pts
						(arc
							(start 0.3048 -0.2032)
							(mid 0.275042 -0.275042)
							(end 0.2032 -0.3048)
						)
						(arc
							(start -0.2032 -0.3048)
							(mid -0.275042 -0.275042)
							(end -0.3048 -0.2032)
						)
						(arc
							(start -0.3048 0.2032)
							(mid -0.275042 0.275042)
							(end -0.2032 0.3048)
						)
						(arc
							(start 0.2032 0.3048)
							(mid 0.275042 0.275042)
							(end 0.3048 0.2032)
						)
					)
					(width 0)
					(fill yes)
				)
			)
		)
	)
	(footprint ""
		(layer "F.Cu")
		(at 165.461442 -82.200496 90)
		(property "Reference" "C635"
			(at 0 0 90)
			(layer "F.SilkS")
			(hide yes)
			(effects
				(font
					(size 1.27 1.27)
				)
			)
		)
		(property "Value" "SC10U16V5KX-7-GP-U"
			(at -0.0762 -6.1214 90)
			(unlocked yes)
			(layer "F.Fab")
			(hide yes)
			(effects
				(font
					(size 1.016 1.016)
					(thickness 0.1524)
				)
			)
		)
		(property "Device Type" "C805H58"
			(at -0.0762 -8.1534 90)
			(unlocked yes)
			(layer "F.Fab")
			(hide yes)
			(effects
				(font
					(size 1.016 1.016)
					(thickness 0.1524)
				)
			)
		)
		(duplicate_pad_numbers_are_jumpers no)
		(fp_line
			(start 0.635 0)
			(end -0.635 0)
			(stroke
				(width 0.508)
				(type default)
			)
			(layer "F.SilkS")
		)
		(fp_rect
			(start -0.9652 1.778)
			(end 0.9652 -1.778)
			(stroke
				(width 0)
				(type default)
			)
			(fill no)
			(layer "F.CrtYd")
		)
		(fp_poly
			(pts
				(xy -0.9652 -1.778) (xy 0.9652 -1.778) (xy 0.9652 1.778) (xy -0.9652 1.778)
			)
			(stroke
				(width 0)
				(type default)
			)
			(fill no)
			(layer "F.Fab")
		)
		(pad "1" smd rect
			(at 0 -0.9652 90)
			(size 1.397 1.143)
			(layers "F.Cu" "F.Mask" "F.Paste")
			(net "P12V_SYBY_VDD_U6")
		)
		(pad "2" smd rect
			(at 0 0.9652 90)
			(size 1.397 1.143)
			(layers "F.Cu" "F.Mask" "F.Paste")
			(net "GND")
		)
	)
	(footprint ""
		(layer "F.Cu")
		(at 151.257 -84.9249 -90)
		(property "Reference" "C524"
			(at 0 0 270)
			(layer "F.SilkS")
			(hide yes)
			(effects
				(font
					(size 1.27 1.27)
				)
			)
		)
		(property "Value" "SCD1U16V2KX-3GP"
			(at 1.1811 -2.7051 270)
			(unlocked yes)
			(layer "F.Fab")
			(hide yes)
			(effects
				(font
					(size 1.016 1.016)
					(thickness 0.1524)
				)
			)
		)
		(property "Device Type" "C402H22"
			(at 1.1811 -4.2291 270)
			(unlocked yes)
			(layer "F.Fab")
			(hide yes)
			(effects
				(font
					(size 1.016 1.016)
					(thickness 0.1524)
				)
			)
		)
		(duplicate_pad_numbers_are_jumpers no)
		(fp_rect
			(start -0.4318 0.9525)
			(end 0.4318 -0.9525)
			(stroke
				(width 0)
				(type default)
			)
			(fill no)
			(layer "F.CrtYd")
		)
		(fp_rect
			(start -0.4318 0.9525)
			(end 0.4318 -0.9525)
			(stroke
				(width 0)
				(type default)
			)
			(fill no)
			(layer "F.Fab")
		)
		(pad "1" smd custom
			(at 0 -0.4445 270)
			(size 0.1524 0.1524)
			(layers "F.Cu" "F.Mask" "F.Paste")
			(net "P1V8_E_SENSE")
			(options
				(clearance outline)
				(anchor circle)
			)
			(primitives
				(gr_poly
					(pts
						(arc
							(start 0.3048 -0.2032)
							(mid 0.275042 -0.275042)
							(end 0.2032 -0.3048)
						)
						(arc
							(start -0.2032 -0.3048)
							(mid -0.275042 -0.275042)
							(end -0.3048 -0.2032)
						)
						(arc
							(start -0.3048 0.2032)
							(mid -0.275042 0.275042)
							(end -0.2032 0.3048)
						)
						(arc
							(start 0.2032 0.3048)
							(mid 0.275042 0.275042)
							(end 0.3048 0.2032)
						)
					)
					(width 0)
					(fill yes)
				)
			)
		)
		(pad "2" smd custom
			(at 0 0.4445 270)
			(size 0.1524 0.1524)
			(layers "F.Cu" "F.Mask" "F.Paste")
			(net "GND")
			(options
				(clearance outline)
				(anchor circle)
			)
			(primitives
				(gr_poly
					(pts
						(arc
							(start 0.3048 -0.2032)
							(mid 0.275042 -0.275042)
							(end 0.2032 -0.3048)
						)
						(arc
							(start -0.2032 -0.3048)
							(mid -0.275042 -0.275042)
							(end -0.3048 -0.2032)
						)
						(arc
							(start -0.3048 0.2032)
							(mid -0.275042 0.275042)
							(end -0.2032 0.3048)
						)
						(arc
							(start 0.2032 0.3048)
							(mid 0.275042 0.275042)
							(end 0.3048 0.2032)
						)
					)
					(width 0)
					(fill yes)
				)
			)
		)
	)
	(footprint ""
		(layer "F.Cu")
		(at 18.6944 -81.7118 -90)
		(property "Reference" "C529"
			(at 0 0 270)
			(layer "F.SilkS")
			(hide yes)
			(effects
				(font
					(size 1.27 1.27)
				)
			)
		)
		(property "Value" "SCD01U25V2KX-3GP"
			(at 1.1811 -2.7051 270)
			(unlocked yes)
			(layer "F.Fab")
			(hide yes)
			(effects
				(font
					(size 1.016 1.016)
					(thickness 0.1524)
				)
			)
		)
		(property "Device Type" "C402H22"
			(at 1.1811 -4.2291 270)
			(unlocked yes)
			(layer "F.Fab")
			(hide yes)
			(effects
				(font
					(size 1.016 1.016)
					(thickness 0.1524)
				)
			)
		)
		(duplicate_pad_numbers_are_jumpers no)
		(fp_rect
			(start -0.4318 0.9525)
			(end 0.4318 -0.9525)
			(stroke
				(width 0)
				(type default)
			)
			(fill no)
			(layer "F.CrtYd")
		)
		(fp_rect
			(start -0.4318 0.9525)
			(end 0.4318 -0.9525)
			(stroke
				(width 0)
				(type default)
			)
			(fill no)
			(layer "F.Fab")
		)
		(pad "1" smd custom
			(at 0 -0.4445 270)
			(size 0.1524 0.1524)
			(layers "F.Cu" "F.Mask" "F.Paste")
			(net "GND")
			(options
				(clearance outline)
				(anchor circle)
			)
			(primitives
				(gr_poly
					(pts
						(arc
							(start 0.3048 -0.2032)
							(mid 0.275042 -0.275042)
							(end 0.2032 -0.3048)
						)
						(arc
							(start -0.2032 -0.3048)
							(mid -0.275042 -0.275042)
							(end -0.3048 -0.2032)
						)
						(arc
							(start -0.3048 0.2032)
							(mid -0.275042 0.275042)
							(end -0.2032 0.3048)
						)
						(arc
							(start 0.2032 0.3048)
							(mid 0.275042 0.275042)
							(end 0.3048 0.2032)
						)
					)
					(width 0)
					(fill yes)
				)
			)
		)
		(pad "2" smd custom
			(at 0 0.4445 270)
			(size 0.1524 0.1524)
			(layers "F.Cu" "F.Mask" "F.Paste")
			(net "P3V3")
			(options
				(clearance outline)
				(anchor circle)
			)
			(primitives
				(gr_poly
					(pts
						(arc
							(start 0.3048 -0.2032)
							(mid 0.275042 -0.275042)
							(end 0.2032 -0.3048)
						)
						(arc
							(start -0.2032 -0.3048)
							(mid -0.275042 -0.275042)
							(end -0.3048 -0.2032)
						)
						(arc
							(start -0.3048 0.2032)
							(mid -0.275042 0.275042)
							(end -0.2032 0.3048)
						)
						(arc
							(start 0.2032 0.3048)
							(mid 0.275042 0.275042)
							(end 0.3048 0.2032)
						)
					)
					(width 0)
					(fill yes)
				)
			)
		)
	)
	(footprint ""
		(layer "F.Cu")
		(at 53.467 -51.4604 180)
		(property "Reference" "R479"
			(at 0 0 180)
			(layer "F.SilkS")
			(hide yes)
			(effects
				(font
					(size 1.27 1.27)
				)
			)
		)
		(property "Value" "1R5F-1-GP"
			(at 0 -8.9535 180)
			(unlocked yes)
			(layer "F.Fab")
			(hide yes)
			(effects
				(font
					(size 1.27 1.016)
					(thickness 0.1524)
				)
			)
		)
		(property "Device Type" "R805H24"
			(at 0 -10.6299 180)
			(unlocked yes)
			(layer "F.Fab")
			(hide yes)
			(effects
				(font
					(size 1.27 1.016)
					(thickness 0.1524)
				)
			)
		)
		(duplicate_pad_numbers_are_jumpers no)
		(fp_line
			(start 0.889 1.7018)
			(end 0.889 -0.508)
			(stroke
				(width 0.1524)
				(type default)
			)
			(layer "F.SilkS")
		)
		(fp_line
			(start 0.889 -1.7018)
			(end 0.889 -0.381)
			(stroke
				(width 0.1524)
				(type default)
			)
			(layer "F.SilkS")
		)
		(fp_line
			(start 0.889 -1.7018)
			(end -0.889 -1.7018)
			(stroke
				(width 0.1524)
				(type default)
			)
			(layer "F.SilkS")
		)
		(fp_line
			(start -0.889 1.7018)
			(end 0.889 1.7018)
			(stroke
				(width 0.1524)
				(type default)
			)
			(layer "F.SilkS")
		)
		(fp_line
			(start -0.889 0.0762)
			(end -0.889 1.7018)
			(stroke
				(width 0.1524)
				(type default)
			)
			(layer "F.SilkS")
		)
		(fp_line
			(start -0.889 -1.7018)
			(end -0.889 0.2794)
			(stroke
				(width 0.1524)
				(type default)
			)
			(layer "F.SilkS")
		)
		(fp_poly
			(pts
				(xy 0.9652 -1.778) (xy 0.9652 1.778) (xy -0.9652 1.778) (xy -0.9652 -1.778)
			)
			(stroke
				(width 0)
				(type default)
			)
			(fill no)
			(layer "F.CrtYd")
		)
		(fp_rect
			(start -0.9652 1.778)
			(end 0.9652 -1.778)
			(stroke
				(width 0)
				(type default)
			)
			(fill no)
			(layer "F.Fab")
		)
		(pad "1" smd rect
			(at 0 -0.9652 180)
			(size 1.397 1.143)
			(layers "F.Cu" "F.Mask" "F.Paste")
			(net "P0V9_VSW")
		)
		(pad "2" smd rect
			(at 0 0.9652 180)
			(size 1.397 1.143)
			(layers "F.Cu" "F.Mask" "F.Paste")
			(net "P0V9_SNB")
		)
	)
	(footprint ""
		(layer "F.Cu")
		(at 194.5132 -31.9532 -90)
		(property "Reference" "TP101"
			(at 0 0 270)
			(layer "F.SilkS")
			(hide yes)
			(effects
				(font
					(size 1.27 1.27)
				)
			)
		)
		(property "Value" "TPAD28-2-GP"
			(at -0.0127 -1.6637 270)
			(unlocked yes)
			(layer "F.Fab")
			(hide yes)
			(effects
				(font
					(size 1.016 1.016)
					(thickness 0.1524)
				)
			)
		)
		(property "Device Type" "TPAD28"
			(at -0.0127 -3.1877 270)
			(unlocked yes)
			(layer "F.Fab")
			(hide yes)
			(effects
				(font
					(size 1.016 1.016)
					(thickness 0.1524)
				)
			)
		)
		(duplicate_pad_numbers_are_jumpers no)
		(fp_poly
			(pts
				(arc
					(start 0 -0.3556)
					(mid 0 0.3556)
					(end 0 -0.3556)
				)
			)
			(stroke
				(width 0)
				(type default)
			)
			(fill no)
			(layer "F.CrtYd")
		)
		(fp_poly
			(pts
				(arc
					(start 0 -0.6096)
					(mid 0 0.6096)
					(end 0 -0.6096)
				)
			)
			(stroke
				(width 0)
				(type default)
			)
			(fill no)
			(layer "F.Fab")
		)
		(pad "1" smd circle
			(at 0 0 270)
			(size 0.7112 0.7112)
			(layers "F.Cu" "F.Mask" "F.Paste")
			(net "IOC_GPIO_39")
		)
	)
	(footprint ""
		(layer "F.Cu")
		(at 152.980898 -82.970624 -90)
		(property "Reference" "R327"
			(at 0 0 270)
			(layer "F.SilkS")
			(hide yes)
			(effects
				(font
					(size 1.27 1.27)
				)
			)
		)
		(property "Value" "0R2J-2-GP"
			(at 0.064008 -3.993896 270)
			(unlocked yes)
			(layer "F.Fab")
			(hide yes)
			(effects
				(font
					(size 1.016 1.016)
					(thickness 0.1524)
				)
			)
		)
		(property "Device Type" "R402H16"
			(at 0.064008 -5.517896 270)
			(unlocked yes)
			(layer "F.Fab")
			(hide yes)
			(effects
				(font
					(size 1.016 1.016)
					(thickness 0.1524)
				)
			)
		)
		(duplicate_pad_numbers_are_jumpers no)
		(fp_line
			(start -0.508 -0.9398)
			(end -0.508 0.9398)
			(stroke
				(width 0.1524)
				(type default)
			)
			(layer "F.SilkS")
		)
		(fp_line
			(start 0.508 -0.9398)
			(end -0.508 -0.9398)
			(stroke
				(width 0.1524)
				(type default)
			)
			(layer "F.SilkS")
		)
		(fp_rect
			(start -0.508 0.9398)
			(end 0.508 -0.9398)
			(stroke
				(width 0)
				(type default)
			)
			(fill no)
			(layer "F.CrtYd")
		)
		(fp_rect
			(start -0.508 0.9398)
			(end 0.508 -0.9398)
			(stroke
				(width 0)
				(type default)
			)
			(fill no)
			(layer "F.Fab")
		)
		(pad "1" smd custom
			(at 0 -0.4445 270)
			(size 0.1397 0.1397)
			(layers "F.Cu" "F.Mask" "F.Paste")
			(net "VOL_SEN1_SCL")
			(options
				(clearance outline)
				(anchor circle)
			)
			(primitives
				(gr_poly
					(pts
						(arc
							(start -0.1778 -0.2794)
							(mid -0.249642 -0.249642)
							(end -0.2794 -0.1778)
						)
						(arc
							(start -0.2794 0.1778)
							(mid -0.249642 0.249642)
							(end -0.1778 0.2794)
						)
						(arc
							(start 0.1778 0.2794)
							(mid 0.249642 0.249642)
							(end 0.2794 0.1778)
						)
						(arc
							(start 0.2794 -0.1778)
							(mid 0.249642 -0.249642)
							(end 0.1778 -0.2794)
						)
					)
					(width 0)
					(fill yes)
				)
			)
		)
		(pad "2" smd custom
			(at 0 0.4445 270)
			(size 0.1397 0.1397)
			(layers "F.Cu" "F.Mask" "F.Paste")
			(net "I2C_SCC_SCL2")
			(options
				(clearance outline)
				(anchor circle)
			)
			(primitives
				(gr_poly
					(pts
						(arc
							(start -0.1778 -0.2794)
							(mid -0.249642 -0.249642)
							(end -0.2794 -0.1778)
						)
						(arc
							(start -0.2794 0.1778)
							(mid -0.249642 0.249642)
							(end -0.1778 0.2794)
						)
						(arc
							(start 0.1778 0.2794)
							(mid 0.249642 0.249642)
							(end 0.2794 0.1778)
						)
						(arc
							(start 0.2794 -0.1778)
							(mid 0.249642 -0.249642)
							(end 0.1778 -0.2794)
						)
					)
					(width 0)
					(fill yes)
				)
			)
		)
	)
	(footprint ""
		(layer "F.Cu")
		(at 187.651644 -58.476642)
		(property "Reference" "R214"
			(at 0 0 0)
			(layer "F.SilkS")
			(hide yes)
			(effects
				(font
					(size 1.27 1.27)
				)
			)
		)
		(property "Value" "10KR2F-2-GP"
			(at 0.064008 -3.993896 0)
			(unlocked yes)
			(layer "F.Fab")
			(hide yes)
			(effects
				(font
					(size 1.016 1.016)
					(thickness 0.1524)
				)
			)
		)
		(property "Device Type" "R402H16"
			(at 0.064008 -5.517896 0)
			(unlocked yes)
			(layer "F.Fab")
			(hide yes)
			(effects
				(font
					(size 1.016 1.016)
					(thickness 0.1524)
				)
			)
		)
		(duplicate_pad_numbers_are_jumpers no)
		(fp_line
			(start -0.508 -0.9398)
			(end -0.508 0.9398)
			(stroke
				(width 0.1524)
				(type default)
			)
			(layer "F.SilkS")
		)
		(fp_line
			(start 0.508 -0.9398)
			(end -0.508 -0.9398)
			(stroke
				(width 0.1524)
				(type default)
			)
			(layer "F.SilkS")
		)
		(fp_rect
			(start -0.508 0.9398)
			(end 0.508 -0.9398)
			(stroke
				(width 0)
				(type default)
			)
			(fill no)
			(layer "F.CrtYd")
		)
		(fp_rect
			(start -0.508 0.9398)
			(end 0.508 -0.9398)
			(stroke
				(width 0)
				(type default)
			)
			(fill no)
			(layer "F.Fab")
		)
		(pad "1" smd custom
			(at 0 -0.4445)
			(size 0.1397 0.1397)
			(layers "F.Cu" "F.Mask" "F.Paste")
			(net "P1V8_C")
			(options
				(clearance outline)
				(anchor circle)
			)
			(primitives
				(gr_poly
					(pts
						(arc
							(start -0.1778 -0.2794)
							(mid -0.249642 -0.249642)
							(end -0.2794 -0.1778)
						)
						(arc
							(start -0.2794 0.1778)
							(mid -0.249642 0.249642)
							(end -0.1778 0.2794)
						)
						(arc
							(start 0.1778 0.2794)
							(mid 0.249642 0.249642)
							(end 0.2794 0.1778)
						)
						(arc
							(start 0.2794 -0.1778)
							(mid 0.249642 -0.249642)
							(end 0.1778 -0.2794)
						)
					)
					(width 0)
					(fill yes)
				)
			)
		)
		(pad "2" smd custom
			(at 0 0.4445)
			(size 0.1397 0.1397)
			(layers "F.Cu" "F.Mask" "F.Paste")
			(net "XM_ADDR_4")
			(options
				(clearance outline)
				(anchor circle)
			)
			(primitives
				(gr_poly
					(pts
						(arc
							(start -0.1778 -0.2794)
							(mid -0.249642 -0.249642)
							(end -0.2794 -0.1778)
						)
						(arc
							(start -0.2794 0.1778)
							(mid -0.249642 0.249642)
							(end -0.1778 0.2794)
						)
						(arc
							(start 0.1778 0.2794)
							(mid 0.249642 0.249642)
							(end 0.2794 0.1778)
						)
						(arc
							(start 0.2794 -0.1778)
							(mid 0.249642 -0.249642)
							(end 0.1778 -0.2794)
						)
					)
					(width 0)
					(fill yes)
				)
			)
		)
	)
	(footprint ""
		(layer "F.Cu")
		(at 115.7986 -86.6394)
		(property "Reference" "TP45"
			(at 0 0 0)
			(layer "F.SilkS")
			(hide yes)
			(effects
				(font
					(size 1.27 1.27)
				)
			)
		)
		(property "Value" "TPAD28-2-GP"
			(at -0.0127 -1.6637 0)
			(unlocked yes)
			(layer "F.Fab")
			(hide yes)
			(effects
				(font
					(size 1.016 1.016)
					(thickness 0.1524)
				)
			)
		)
		(property "Device Type" "TPAD28"
			(at -0.0127 -3.1877 0)
			(unlocked yes)
			(layer "F.Fab")
			(hide yes)
			(effects
				(font
					(size 1.016 1.016)
					(thickness 0.1524)
				)
			)
		)
		(duplicate_pad_numbers_are_jumpers no)
		(fp_poly
			(pts
				(arc
					(start 0.3556 0)
					(mid -0.3556 0)
					(end 0.3556 0)
				)
			)
			(stroke
				(width 0)
				(type default)
			)
			(fill no)
			(layer "F.CrtYd")
		)
		(fp_poly
			(pts
				(arc
					(start 0.6096 0)
					(mid -0.6096 0)
					(end 0.6096 0)
				)
			)
			(stroke
				(width 0)
				(type default)
			)
			(fill no)
			(layer "F.Fab")
		)
		(pad "1" smd circle
			(at 0 0)
			(size 0.7112 0.7112)
			(layers "F.Cu" "F.Mask" "F.Paste")
			(net "EXP_XM_ADDR_25")
		)
	)
	(footprint ""
		(layer "F.Cu")
		(at 159.512 -42.291 90)
		(property "Reference" "C334"
			(at 0 0 90)
			(layer "F.SilkS")
			(hide yes)
			(effects
				(font
					(size 1.27 1.27)
				)
			)
		)
		(property "Value" "SC15P50V2JN-2-GP"
			(at 1.1811 -2.7051 90)
			(unlocked yes)
			(layer "F.Fab")
			(hide yes)
			(effects
				(font
					(size 1.016 1.016)
					(thickness 0.1524)
				)
			)
		)
		(property "Device Type" "C402H22"
			(at 1.1811 -4.2291 90)
			(unlocked yes)
			(layer "F.Fab")
			(hide yes)
			(effects
				(font
					(size 1.016 1.016)
					(thickness 0.1524)
				)
			)
		)
		(duplicate_pad_numbers_are_jumpers no)
		(fp_rect
			(start -0.4318 0.9525)
			(end 0.4318 -0.9525)
			(stroke
				(width 0)
				(type default)
			)
			(fill no)
			(layer "F.CrtYd")
		)
		(fp_rect
			(start -0.4318 0.9525)
			(end 0.4318 -0.9525)
			(stroke
				(width 0)
				(type default)
			)
			(fill no)
			(layer "F.Fab")
		)
		(pad "1" smd custom
			(at 0 -0.4445 90)
			(size 0.1524 0.1524)
			(layers "F.Cu" "F.Mask" "F.Paste")
			(net "IOC_REF_CLK_P")
			(options
				(clearance outline)
				(anchor circle)
			)
			(primitives
				(gr_poly
					(pts
						(arc
							(start 0.3048 -0.2032)
							(mid 0.275042 -0.275042)
							(end 0.2032 -0.3048)
						)
						(arc
							(start -0.2032 -0.3048)
							(mid -0.275042 -0.275042)
							(end -0.3048 -0.2032)
						)
						(arc
							(start -0.3048 0.2032)
							(mid -0.275042 0.275042)
							(end -0.2032 0.3048)
						)
						(arc
							(start 0.2032 0.3048)
							(mid 0.275042 0.275042)
							(end 0.3048 0.2032)
						)
					)
					(width 0)
					(fill yes)
				)
			)
		)
		(pad "2" smd custom
			(at 0 0.4445 90)
			(size 0.1524 0.1524)
			(layers "F.Cu" "F.Mask" "F.Paste")
			(net "GND")
			(options
				(clearance outline)
				(anchor circle)
			)
			(primitives
				(gr_poly
					(pts
						(arc
							(start 0.3048 -0.2032)
							(mid 0.275042 -0.275042)
							(end 0.2032 -0.3048)
						)
						(arc
							(start -0.2032 -0.3048)
							(mid -0.275042 -0.275042)
							(end -0.3048 -0.2032)
						)
						(arc
							(start -0.3048 0.2032)
							(mid -0.275042 0.275042)
							(end -0.2032 0.3048)
						)
						(arc
							(start 0.2032 0.3048)
							(mid 0.275042 0.275042)
							(end 0.3048 0.2032)
						)
					)
					(width 0)
					(fill yes)
				)
			)
		)
	)
	(footprint ""
		(layer "F.Cu")
		(at 60.73775 -123.205494)
		(property "Reference" "R509"
			(at 0 0 0)
			(layer "F.SilkS")
			(hide yes)
			(effects
				(font
					(size 1.27 1.27)
				)
			)
		)
		(property "Value" "0R5J-5-GP"
			(at 0 -8.9535 0)
			(unlocked yes)
			(layer "F.Fab")
			(hide yes)
			(effects
				(font
					(size 1.27 1.016)
					(thickness 0.1524)
				)
			)
		)
		(property "Device Type" "R805H24"
			(at 0 -10.6299 0)
			(unlocked yes)
			(layer "F.Fab")
			(hide yes)
			(effects
				(font
					(size 1.27 1.016)
					(thickness 0.1524)
				)
			)
		)
		(duplicate_pad_numbers_are_jumpers no)
		(fp_line
			(start -0.889 -1.7018)
			(end -0.889 0.2794)
			(stroke
				(width 0.1524)
				(type default)
			)
			(layer "F.SilkS")
		)
		(fp_line
			(start -0.889 0.0762)
			(end -0.889 1.7018)
			(stroke
				(width 0.1524)
				(type default)
			)
			(layer "F.SilkS")
		)
		(fp_line
			(start -0.889 1.7018)
			(end 0.889 1.7018)
			(stroke
				(width 0.1524)
				(type default)
			)
			(layer "F.SilkS")
		)
		(fp_line
			(start 0.889 -1.7018)
			(end -0.889 -1.7018)
			(stroke
				(width 0.1524)
				(type default)
			)
			(layer "F.SilkS")
		)
		(fp_line
			(start 0.889 -1.7018)
			(end 0.889 -0.381)
			(stroke
				(width 0.1524)
				(type default)
			)
			(layer "F.SilkS")
		)
		(fp_line
			(start 0.889 1.7018)
			(end 0.889 -0.508)
			(stroke
				(width 0.1524)
				(type default)
			)
			(layer "F.SilkS")
		)
		(fp_poly
			(pts
				(xy 0.9652 -1.778) (xy 0.9652 1.778) (xy -0.9652 1.778) (xy -0.9652 -1.778)
			)
			(stroke
				(width 0)
				(type default)
			)
			(fill no)
			(layer "F.CrtYd")
		)
		(fp_rect
			(start -0.9652 1.778)
			(end 0.9652 -1.778)
			(stroke
				(width 0)
				(type default)
			)
			(fill no)
			(layer "F.Fab")
		)
		(pad "1" smd rect
			(at 0 -0.9652)
			(size 1.397 1.143)
			(layers "F.Cu" "F.Mask" "F.Paste")
			(net "P3V3")
		)
		(pad "2" smd rect
			(at 0 0.9652)
			(size 1.397 1.143)
			(layers "F.Cu" "F.Mask" "F.Paste")
			(net "P3V3_OUT")
		)
	)
	(footprint ""
		(layer "F.Cu")
		(at 192.8241 -35.433 -90)
		(property "Reference" "R184"
			(at 0 0 270)
			(layer "F.SilkS")
			(hide yes)
			(effects
				(font
					(size 1.27 1.27)
				)
			)
		)
		(property "Value" "2K2R2F-GP"
			(at 0.064008 -3.993896 270)
			(unlocked yes)
			(layer "F.Fab")
			(hide yes)
			(effects
				(font
					(size 1.016 1.016)
					(thickness 0.1524)
				)
			)
		)
		(property "Device Type" "R402H16"
			(at 0.064008 -5.517896 270)
			(unlocked yes)
			(layer "F.Fab")
			(hide yes)
			(effects
				(font
					(size 1.016 1.016)
					(thickness 0.1524)
				)
			)
		)
		(duplicate_pad_numbers_are_jumpers no)
		(fp_line
			(start -0.508 -0.9398)
			(end -0.508 0.9398)
			(stroke
				(width 0.1524)
				(type default)
			)
			(layer "F.SilkS")
		)
		(fp_line
			(start 0.508 -0.9398)
			(end -0.508 -0.9398)
			(stroke
				(width 0.1524)
				(type default)
			)
			(layer "F.SilkS")
		)
		(fp_rect
			(start -0.508 0.9398)
			(end 0.508 -0.9398)
			(stroke
				(width 0)
				(type default)
			)
			(fill no)
			(layer "F.CrtYd")
		)
		(fp_rect
			(start -0.508 0.9398)
			(end 0.508 -0.9398)
			(stroke
				(width 0)
				(type default)
			)
			(fill no)
			(layer "F.Fab")
		)
		(pad "1" smd custom
			(at 0 -0.4445 270)
			(size 0.1397 0.1397)
			(layers "F.Cu" "F.Mask" "F.Paste")
			(net "P1V8_C")
			(options
				(clearance outline)
				(anchor circle)
			)
			(primitives
				(gr_poly
					(pts
						(arc
							(start -0.1778 -0.2794)
							(mid -0.249642 -0.249642)
							(end -0.2794 -0.1778)
						)
						(arc
							(start -0.2794 0.1778)
							(mid -0.249642 0.249642)
							(end -0.1778 0.2794)
						)
						(arc
							(start 0.1778 0.2794)
							(mid 0.249642 0.249642)
							(end 0.2794 0.1778)
						)
						(arc
							(start 0.2794 -0.1778)
							(mid 0.249642 -0.249642)
							(end 0.1778 -0.2794)
						)
					)
					(width 0)
					(fill yes)
				)
			)
		)
		(pad "2" smd custom
			(at 0 0.4445 270)
			(size 0.1397 0.1397)
			(layers "F.Cu" "F.Mask" "F.Paste")
			(net "I2C_IOC_1_SDA")
			(options
				(clearance outline)
				(anchor circle)
			)
			(primitives
				(gr_poly
					(pts
						(arc
							(start -0.1778 -0.2794)
							(mid -0.249642 -0.249642)
							(end -0.2794 -0.1778)
						)
						(arc
							(start -0.2794 0.1778)
							(mid -0.249642 0.249642)
							(end -0.1778 0.2794)
						)
						(arc
							(start 0.1778 0.2794)
							(mid 0.249642 0.249642)
							(end 0.2794 0.1778)
						)
						(arc
							(start 0.2794 -0.1778)
							(mid 0.249642 -0.249642)
							(end 0.1778 -0.2794)
						)
					)
					(width 0)
					(fill yes)
				)
			)
		)
	)
	(footprint ""
		(layer "F.Cu")
		(at 16.637 -94.9452 180)
		(property "Reference" "R411"
			(at 0 0 180)
			(layer "F.SilkS")
			(hide yes)
			(effects
				(font
					(size 1.27 1.27)
				)
			)
		)
		(property "Value" "200KR2F-L-GP"
			(at 0.064008 -3.993896 180)
			(unlocked yes)
			(layer "F.Fab")
			(hide yes)
			(effects
				(font
					(size 1.016 1.016)
					(thickness 0.1524)
				)
			)
		)
		(property "Device Type" "R402H16"
			(at 0.064008 -5.517896 180)
			(unlocked yes)
			(layer "F.Fab")
			(hide yes)
			(effects
				(font
					(size 1.016 1.016)
					(thickness 0.1524)
				)
			)
		)
		(duplicate_pad_numbers_are_jumpers no)
		(fp_line
			(start 0.508 -0.9398)
			(end -0.508 -0.9398)
			(stroke
				(width 0.1524)
				(type default)
			)
			(layer "F.SilkS")
		)
		(fp_line
			(start -0.508 -0.9398)
			(end -0.508 0.9398)
			(stroke
				(width 0.1524)
				(type default)
			)
			(layer "F.SilkS")
		)
		(fp_rect
			(start -0.508 0.9398)
			(end 0.508 -0.9398)
			(stroke
				(width 0)
				(type default)
			)
			(fill no)
			(layer "F.CrtYd")
		)
		(fp_rect
			(start -0.508 0.9398)
			(end 0.508 -0.9398)
			(stroke
				(width 0)
				(type default)
			)
			(fill no)
			(layer "F.Fab")
		)
		(pad "1" smd custom
			(at 0 -0.4445 180)
			(size 0.1397 0.1397)
			(layers "F.Cu" "F.Mask" "F.Paste")
			(net "LS_EN_U35")
			(options
				(clearance outline)
				(anchor circle)
			)
			(primitives
				(gr_poly
					(pts
						(arc
							(start -0.1778 -0.2794)
							(mid -0.249642 -0.249642)
							(end -0.2794 -0.1778)
						)
						(arc
							(start -0.2794 0.1778)
							(mid -0.249642 0.249642)
							(end -0.1778 0.2794)
						)
						(arc
							(start 0.1778 0.2794)
							(mid 0.249642 0.249642)
							(end 0.2794 0.1778)
						)
						(arc
							(start 0.2794 -0.1778)
							(mid 0.249642 -0.249642)
							(end 0.1778 -0.2794)
						)
					)
					(width 0)
					(fill yes)
				)
			)
		)
		(pad "2" smd custom
			(at 0 0.4445 180)
			(size 0.1397 0.1397)
			(layers "F.Cu" "F.Mask" "F.Paste")
			(net "P0V9_PG")
			(options
				(clearance outline)
				(anchor circle)
			)
			(primitives
				(gr_poly
					(pts
						(arc
							(start -0.1778 -0.2794)
							(mid -0.249642 -0.249642)
							(end -0.2794 -0.1778)
						)
						(arc
							(start -0.2794 0.1778)
							(mid -0.249642 0.249642)
							(end -0.1778 0.2794)
						)
						(arc
							(start 0.1778 0.2794)
							(mid 0.249642 0.249642)
							(end 0.2794 0.1778)
						)
						(arc
							(start 0.2794 -0.1778)
							(mid 0.249642 -0.249642)
							(end 0.1778 -0.2794)
						)
					)
					(width 0)
					(fill yes)
				)
			)
		)
	)
	(footprint ""
		(layer "F.Cu")
		(at 115.000024 -67.00012)
		(property "Reference" "U1"
			(at 0 0 0)
			(layer "F.SilkS")
			(hide yes)
			(effects
				(font
					(size 1.27 1.27)
				)
			)
		)
		(property "Value" "LSISAS3X48-GP"
			(at -24.358092 -5.0292 0)
			(unlocked yes)
			(layer "F.Fab")
			(hide yes)
			(effects
				(font
					(size 1.016 1.016)
					(thickness 0.1524)
				)
			)
		)
		(property "Device Type" "BGA1020C33H83"
			(at -24.358092 -6.5532 0)
			(unlocked yes)
			(layer "F.Fab")
			(hide yes)
			(effects
				(font
					(size 1.016 1.016)
					(thickness 0.1524)
				)
			)
		)
		(duplicate_pad_numbers_are_jumpers no)
		(fp_line
			(start -16.500094 -16.030194)
			(end -16.500094 -14.469872)
			(stroke
				(width 0.1524)
				(type default)
			)
			(layer "F.SilkS")
		)
		(fp_line
			(start -16.500094 -13.530072)
			(end -16.500094 13.530072)
			(stroke
				(width 0.1524)
				(type default)
			)
			(layer "F.SilkS")
		)
		(fp_line
			(start -16.500094 16.030194)
			(end -16.500094 14.469872)
			(stroke
				(width 0.1524)
				(type default)
			)
			(layer "F.SilkS")
		)
		(fp_line
			(start -16.030194 -16.500094)
			(end -14.469872 -16.500094)
			(stroke
				(width 0.1524)
				(type default)
			)
			(layer "F.SilkS")
		)
		(fp_line
			(start -16.030194 16.500094)
			(end -14.469872 16.500094)
			(stroke
				(width 0.1524)
				(type default)
			)
			(layer "F.SilkS")
		)
		(fp_line
			(start 13.530072 -16.500094)
			(end -13.530072 -16.500094)
			(stroke
				(width 0.1524)
				(type default)
			)
			(layer "F.SilkS")
		)
		(fp_line
			(start 13.530072 16.500094)
			(end -13.530072 16.500094)
			(stroke
				(width 0.1524)
				(type default)
			)
			(layer "F.SilkS")
		)
		(fp_line
			(start 16.030194 -16.500094)
			(end 14.469872 -16.500094)
			(stroke
				(width 0.1524)
				(type default)
			)
			(layer "F.SilkS")
		)
		(fp_line
			(start 16.030194 16.500094)
			(end 14.469872 16.500094)
			(stroke
				(width 0.1524)
				(type default)
			)
			(layer "F.SilkS")
		)
		(fp_line
			(start 16.500094 -16.030194)
			(end 16.500094 -14.469872)
			(stroke
				(width 0.1524)
				(type default)
			)
			(layer "F.SilkS")
		)
		(fp_line
			(start 16.500094 -13.530072)
			(end 16.500094 13.530072)
			(stroke
				(width 0.1524)
				(type default)
			)
			(layer "F.SilkS")
		)
		(fp_line
			(start 16.500094 16.030194)
			(end 16.500094 14.469872)
			(stroke
				(width 0.1524)
				(type default)
			)
			(layer "F.SilkS")
		)
		(fp_circle
			(center -16.500094 -16.500094)
			(end -16.030194 -16.500094)
			(stroke
				(width 0.1524)
				(type default)
			)
			(fill no)
			(layer "F.SilkS")
		)
		(fp_circle
			(center -16.500094 -13.999972)
			(end -16.030194 -13.999972)
			(stroke
				(width 0.1524)
				(type default)
			)
			(fill no)
			(layer "F.SilkS")
		)
		(fp_circle
			(center -16.500094 13.999972)
			(end -16.030194 13.999972)
			(stroke
				(width 0.1524)
				(type default)
			)
			(fill no)
			(layer "F.SilkS")
		)
		(fp_circle
			(center -16.500094 16.500094)
			(end -16.030194 16.500094)
			(stroke
				(width 0.1524)
				(type default)
			)
			(fill no)
			(layer "F.SilkS")
		)
		(fp_circle
			(center -13.999972 -16.500094)
			(end -13.530072 -16.500094)
			(stroke
				(width 0.1524)
				(type default)
			)
			(fill no)
			(layer "F.SilkS")
		)
		(fp_circle
			(center -13.999972 16.500094)
			(end -13.530072 16.500094)
			(stroke
				(width 0.1524)
				(type default)
			)
			(fill no)
			(layer "F.SilkS")
		)
		(fp_circle
			(center 13.999972 -16.500094)
			(end 14.469872 -16.500094)
			(stroke
				(width 0.1524)
				(type default)
			)
			(fill no)
			(layer "F.SilkS")
		)
		(fp_circle
			(center 13.999972 16.500094)
			(end 14.469872 16.500094)
			(stroke
				(width 0.1524)
				(type default)
			)
			(fill no)
			(layer "F.SilkS")
		)
		(fp_circle
			(center 16.500094 -16.500094)
			(end 16.969994 -16.500094)
			(stroke
				(width 0.1524)
				(type default)
			)
			(fill no)
			(layer "F.SilkS")
		)
		(fp_circle
			(center 16.500094 -13.999972)
			(end 16.969994 -13.999972)
			(stroke
				(width 0.1524)
				(type default)
			)
			(fill no)
			(layer "F.SilkS")
		)
		(fp_circle
			(center 16.500094 13.999972)
			(end 16.969994 13.999972)
			(stroke
				(width 0.1524)
				(type default)
			)
			(fill no)
			(layer "F.SilkS")
		)
		(fp_circle
			(center 16.500094 16.500094)
			(end 16.969994 16.500094)
			(stroke
				(width 0.1524)
				(type default)
			)
			(fill no)
			(layer "F.SilkS")
		)
		(fp_poly
			(pts
				(xy -16.931894 -16.931894) (xy -16.931894 -18.455894) (xy -18.455894 -16.931894)
			)
			(stroke
				(width 0)
				(type default)
			)
			(fill yes)
			(layer "F.SilkS")
		)
		(fp_line
			(start -14.500098 -14.500098)
			(end -14.500098 -11.452098)
			(stroke
				(width 0.381)
				(type default)
			)
			(layer "B.SilkS")
		)
		(fp_line
			(start -14.500098 11.452098)
			(end -14.500098 14.500098)
			(stroke
				(width 0.381)
				(type default)
			)
			(layer "B.SilkS")
		)
		(fp_line
			(start -14.500098 14.500098)
			(end -11.452098 14.500098)
			(stroke
				(width 0.381)
				(type default)
			)
			(layer "B.SilkS")
		)
		(fp_line
			(start -11.452098 -14.500098)
			(end -14.500098 -14.500098)
			(stroke
				(width 0.381)
				(type default)
			)
			(layer "B.SilkS")
		)
		(fp_line
			(start -11.452098 -11.452098)
			(end -17.548098 -17.548098)
			(stroke
				(width 0.381)
				(type default)
			)
			(layer "B.SilkS")
		)
		(fp_line
			(start -11.452098 11.452098)
			(end -17.548098 17.548098)
			(stroke
				(width 0.381)
				(type default)
			)
			(layer "B.SilkS")
		)
		(fp_line
			(start 11.452098 -14.500098)
			(end 14.500098 -14.500098)
			(stroke
				(width 0.381)
				(type default)
			)
			(layer "B.SilkS")
		)
		(fp_line
			(start 11.452098 -11.452098)
			(end 17.548098 -17.548098)
			(stroke
				(width 0.381)
				(type default)
			)
			(layer "B.SilkS")
		)
		(fp_line
			(start 11.452098 11.452098)
			(end 17.548098 17.548098)
			(stroke
				(width 0.381)
				(type default)
			)
			(layer "B.SilkS")
		)
		(fp_line
			(start 14.500098 -14.500098)
			(end 14.500098 -11.452098)
			(stroke
				(width 0.381)
				(type default)
			)
			(layer "B.SilkS")
		)
		(fp_line
			(start 14.500098 11.452098)
			(end 14.500098 14.500098)
			(stroke
				(width 0.381)
				(type default)
			)
			(layer "B.SilkS")
		)
		(fp_line
			(start 14.500098 14.500098)
			(end 11.452098 14.500098)
			(stroke
				(width 0.381)
				(type default)
			)
			(layer "B.SilkS")
		)
		(fp_rect
			(start -16.500094 16.500094)
			(end 16.500094 -16.500094)
			(stroke
				(width 0)
				(type default)
			)
			(fill no)
			(layer "F.CrtYd")
		)
		(fp_poly
			(pts
				(xy 17.500092 -16.500094) (xy -16.500094 -16.500094) (xy -16.500094 16.500094) (xy 16.500094 16.500094)
				(xy 16.500094 -16.487394) (xy 17.500092 -16.487394) (xy 17.500092 17.500092) (xy -17.500092 17.500092)
				(xy -17.500092 -17.500092) (xy 17.500092 -17.500092)
			)
			(stroke
				(width 0)
				(type default)
			)
			(fill no)
			(layer "F.CrtYd")
		)
		(fp_rect
			(start -18.50009 18.50009)
			(end 18.50009 -18.50009)
			(stroke
				(width 0)
				(type default)
			)
			(fill no)
			(layer "F.Fab")
		)
		(pad "A2" smd circle
			(at -14.500098 -15.500096)
			(size 0.508 0.508)
			(layers "F.Cu" "F.Mask" "F.Paste")
			(net "Net_1261")
		)
		(pad "A3" smd circle
			(at -13.5001 -15.500096)
			(size 0.508 0.508)
			(layers "F.Cu" "F.Mask" "F.Paste")
			(net "GND")
		)
		(pad "A4" smd circle
			(at -12.500102 -15.500096)
			(size 0.4572 0.4572)
			(layers "F.Cu" "F.Mask" "F.Paste")
			(net "Net_1260")
		)
		(pad "A5" smd circle
			(at -11.500104 -15.500096)
			(size 0.4572 0.4572)
			(layers "F.Cu" "F.Mask" "F.Paste")
			(net "Net_1259")
		)
		(pad "A6" smd circle
			(at -10.500106 -15.500096)
			(size 0.4572 0.4572)
			(layers "F.Cu" "F.Mask" "F.Paste")
			(net "GND")
		)
		(pad "A7" smd circle
			(at -9.500108 -15.500096)
			(size 0.4572 0.4572)
			(layers "F.Cu" "F.Mask" "F.Paste")
			(net "P1V8_E")
		)
		(pad "A8" smd circle
			(at -8.50011 -15.500096)
			(size 0.4572 0.4572)
			(layers "F.Cu" "F.Mask" "F.Paste")
			(net "GND")
		)
		(pad "A9" smd circle
			(at -7.500112 -15.500096)
			(size 0.4572 0.4572)
			(layers "F.Cu" "F.Mask" "F.Paste")
			(net "DRIVE_0_ACT")
		)
		(pad "A10" smd circle
			(at -6.500114 -15.500096)
			(size 0.4572 0.4572)
			(layers "F.Cu" "F.Mask" "F.Paste")
			(net "JTAG_EXP_TDO")
		)
		(pad "A11" smd circle
			(at -5.500116 -15.500096)
			(size 0.4572 0.4572)
			(layers "F.Cu" "F.Mask" "F.Paste")
			(net "FW_RESET_N")
		)
		(pad "A12" smd circle
			(at -4.500118 -15.500096)
			(size 0.4572 0.4572)
			(layers "F.Cu" "F.Mask" "F.Paste")
			(net "XM_WBE_0#_TP")
		)
		(pad "A13" smd circle
			(at -3.50012 -15.500096)
			(size 0.4572 0.4572)
			(layers "F.Cu" "F.Mask" "F.Paste")
			(net "XM_DATA6")
		)
		(pad "A14" smd circle
			(at -2.500122 -15.500096)
			(size 0.4572 0.4572)
			(layers "F.Cu" "F.Mask" "F.Paste")
			(net "XM_DATA3")
		)
		(pad "A15" smd circle
			(at -1.500124 -15.500096)
			(size 0.4572 0.4572)
			(layers "F.Cu" "F.Mask" "F.Paste")
			(net "XM_DATA1")
		)
		(pad "A16" smd circle
			(at -0.500126 -15.500096)
			(size 0.4572 0.4572)
			(layers "F.Cu" "F.Mask" "F.Paste")
			(net "EXP_XM_ADDR_5")
		)
		(pad "A17" smd circle
			(at 0.500126 -15.500096)
			(size 0.4572 0.4572)
			(layers "F.Cu" "F.Mask" "F.Paste")
			(net "EXP_XM_ADDR_25")
		)
		(pad "A18" smd circle
			(at 1.500124 -15.500096)
			(size 0.4572 0.4572)
			(layers "F.Cu" "F.Mask" "F.Paste")
			(net "EXP_XM_ADDR_18")
		)
		(pad "A19" smd circle
			(at 2.500122 -15.500096)
			(size 0.4572 0.4572)
			(layers "F.Cu" "F.Mask" "F.Paste")
			(net "EXP_XM_ADDR_13")
		)
		(pad "A20" smd circle
			(at 3.50012 -15.500096)
			(size 0.4572 0.4572)
			(layers "F.Cu" "F.Mask" "F.Paste")
			(net "EXP_GPIO15")
		)
		(pad "A21" smd circle
			(at 4.500118 -15.500096)
			(size 0.4572 0.4572)
			(layers "F.Cu" "F.Mask" "F.Paste")
			(net "SCC_LOC_HEARTBEAT_LS")
		)
		(pad "A22" smd circle
			(at 5.500116 -15.500096)
			(size 0.4572 0.4572)
			(layers "F.Cu" "F.Mask" "F.Paste")
			(net "BMC_EXP_SPARE_1_R_LS")
		)
		(pad "A23" smd circle
			(at 6.500114 -15.500096)
			(size 0.4572 0.4572)
			(layers "F.Cu" "F.Mask" "F.Paste")
			(net "Net_1215")
		)
		(pad "A24" smd circle
			(at 7.500112 -15.500096)
			(size 0.4572 0.4572)
			(layers "F.Cu" "F.Mask" "F.Paste")
			(net "USB_CLK")
		)
		(pad "A25" smd circle
			(at 8.50011 -15.500096)
			(size 0.4572 0.4572)
			(layers "F.Cu" "F.Mask" "F.Paste")
			(net "Net_1214")
		)
		(pad "A26" smd circle
			(at 9.500108 -15.500096)
			(size 0.4572 0.4572)
			(layers "F.Cu" "F.Mask" "F.Paste")
			(net "Net_1213")
		)
		(pad "A27" smd circle
			(at 10.500106 -15.500096)
			(size 0.4572 0.4572)
			(layers "F.Cu" "F.Mask" "F.Paste")
			(net "SDB_R_RX")
		)
		(pad "A28" smd circle
			(at 11.500104 -15.500096)
			(size 0.4572 0.4572)
			(layers "F.Cu" "F.Mask" "F.Paste")
			(net "SMART_TX")
		)
		(pad "A29" smd circle
			(at 12.500102 -15.500096)
			(size 0.4572 0.4572)
			(layers "F.Cu" "F.Mask" "F.Paste")
			(net "UART_CTS")
		)
		(pad "A30" smd circle
			(at 13.5001 -15.500096)
			(size 0.508 0.508)
			(layers "F.Cu" "F.Mask" "F.Paste")
			(net "EXP_I2C_SCL10")
		)
		(pad "A31" smd circle
			(at 14.500098 -15.500096)
			(size 0.508 0.508)
			(layers "F.Cu" "F.Mask" "F.Paste")
			(net "EXP_I2C_SCL9")
		)
		(pad "AA1" smd circle
			(at -15.500096 4.500118)
			(size 0.4572 0.4572)
			(layers "F.Cu" "F.Mask" "F.Paste")
			(net "DRIVE_19_ACT")
		)
		(pad "AA2" smd circle
			(at -14.500098 4.500118)
			(size 0.4572 0.4572)
			(layers "F.Cu" "F.Mask" "F.Paste")
			(net "DRIVE_20_ACT")
		)
		(pad "AA3" smd circle
			(at -13.5001 4.500118)
			(size 0.4572 0.4572)
			(layers "F.Cu" "F.Mask" "F.Paste")
			(net "P1V8_E")
		)
		(pad "AA4" smd circle
			(at -12.500102 4.500118)
			(size 0.4572 0.4572)
			(layers "F.Cu" "F.Mask" "F.Paste")
			(net "DRIVE_23_ACT")
		)
		(pad "AA5" smd circle
			(at -11.500104 4.500118)
			(size 0.4572 0.4572)
			(layers "F.Cu" "F.Mask" "F.Paste")
			(net "DRIVE_22_ACT")
		)
		(pad "AA6" smd circle
			(at -10.500106 4.500118)
			(size 0.4572 0.4572)
			(layers "F.Cu" "F.Mask" "F.Paste")
			(net "GND")
		)
		(pad "AA7" smd circle
			(at -9.500108 4.500118)
			(size 0.4572 0.4572)
			(layers "F.Cu" "F.Mask" "F.Paste")
			(net "DRIVE_24_ACT")
		)
		(pad "AA8" smd circle
			(at -8.50011 4.500118)
			(size 0.4572 0.4572)
			(layers "F.Cu" "F.Mask" "F.Paste")
			(net "DRIVE_36_ACT")
		)
		(pad "AA9" smd circle
			(at -7.500112 4.500118)
			(size 0.4572 0.4572)
			(layers "F.Cu" "F.Mask" "F.Paste")
			(net "LED46")
		)
		(pad "AA10" smd circle
			(at -6.500114 4.500118)
			(size 0.4572 0.4572)
			(layers "F.Cu" "F.Mask" "F.Paste")
			(net "GND")
		)
		(pad "AA11" smd circle
			(at -5.500116 4.500118)
			(size 0.4572 0.4572)
			(layers "F.Cu" "F.Mask" "F.Paste")
			(net "GB_VDDH")
		)
		(pad "AA12" smd circle
			(at -4.500118 4.500118)
			(size 0.4572 0.4572)
			(layers "F.Cu" "F.Mask" "F.Paste")
			(net "GB_VDDH")
		)
		(pad "AA13" smd circle
			(at -3.50012 4.500118)
			(size 0.4572 0.4572)
			(layers "F.Cu" "F.Mask" "F.Paste")
			(net "GB_VDDH")
		)
		(pad "AA14" smd circle
			(at -2.500122 4.500118)
			(size 0.4572 0.4572)
			(layers "F.Cu" "F.Mask" "F.Paste")
			(net "GB_VDDH")
		)
		(pad "AA15" smd circle
			(at -1.500124 4.500118)
			(size 0.4572 0.4572)
			(layers "F.Cu" "F.Mask" "F.Paste")
			(net "GB_VDDH")
		)
		(pad "AA16" smd circle
			(at -0.500126 4.500118)
			(size 0.4572 0.4572)
			(layers "F.Cu" "F.Mask" "F.Paste")
			(net "GB_VDDH")
		)
		(pad "AA17" smd circle
			(at 0.500126 4.500118)
			(size 0.4572 0.4572)
			(layers "F.Cu" "F.Mask" "F.Paste")
			(net "GB_VDDH")
		)
		(pad "AA18" smd circle
			(at 1.500124 4.500118)
			(size 0.4572 0.4572)
			(layers "F.Cu" "F.Mask" "F.Paste")
			(net "GB_VDDH")
		)
		(pad "AA19" smd circle
			(at 2.500122 4.500118)
			(size 0.4572 0.4572)
			(layers "F.Cu" "F.Mask" "F.Paste")
			(net "GB_VDDH")
		)
		(pad "AA20" smd circle
			(at 3.50012 4.500118)
			(size 0.4572 0.4572)
			(layers "F.Cu" "F.Mask" "F.Paste")
			(net "GB_VDDH")
		)
		(pad "AA21" smd circle
			(at 4.500118 4.500118)
			(size 0.4572 0.4572)
			(layers "F.Cu" "F.Mask" "F.Paste")
			(net "GB_VDDH")
		)
		(pad "AA22" smd circle
			(at 5.500116 4.500118)
			(size 0.4572 0.4572)
			(layers "F.Cu" "F.Mask" "F.Paste")
			(net "GB_VDDH")
		)
		(pad "AA23" smd circle
			(at 6.500114 4.500118)
			(size 0.4572 0.4572)
			(layers "F.Cu" "F.Mask" "F.Paste")
			(net "GND")
		)
		(pad "AA24" smd circle
			(at 7.500112 4.500118)
			(size 0.4572 0.4572)
			(layers "F.Cu" "F.Mask" "F.Paste")
			(net "GB_VDDA")
		)
		(pad "AA25" smd circle
			(at 8.50011 4.500118)
			(size 0.4572 0.4572)
			(layers "F.Cu" "F.Mask" "F.Paste")
			(net "GND")
		)
		(pad "AA26" smd circle
			(at 9.500108 4.500118)
			(size 0.4572 0.4572)
			(layers "F.Cu" "F.Mask" "F.Paste")
			(net "GB_VDDA")
		)
		(pad "AA27" smd circle
			(at 10.500106 4.500118)
			(size 0.4572 0.4572)
			(layers "F.Cu" "F.Mask" "F.Paste")
			(net "PHY_DPB_TO_SCC_C_29_DN")
		)
		(pad "AA28" smd circle
			(at 11.500104 4.500118)
			(size 0.4572 0.4572)
			(layers "F.Cu" "F.Mask" "F.Paste")
			(net "PHY_DPB_TO_SCC_C_29_DP")
		)
		(pad "AA29" smd circle
			(at 12.500102 4.500118)
			(size 0.4572 0.4572)
			(layers "F.Cu" "F.Mask" "F.Paste")
			(net "GND")
		)
		(pad "AA30" smd circle
			(at 13.5001 4.500118)
			(size 0.4572 0.4572)
			(layers "F.Cu" "F.Mask" "F.Paste")
			(net "GB_VDDA")
		)
		(pad "AA31" smd circle
			(at 14.500098 4.500118)
			(size 0.4572 0.4572)
			(layers "F.Cu" "F.Mask" "F.Paste")
			(net "PHY_SCC_TO_DPB_29_DN")
		)
		(pad "AA32" smd circle
			(at 15.500096 4.500118)
			(size 0.4572 0.4572)
			(layers "F.Cu" "F.Mask" "F.Paste")
			(net "PHY_SCC_TO_DPB_29_DP")
		)
		(pad "AB1" smd circle
			(at -15.500096 5.500116)
			(size 0.4572 0.4572)
			(layers "F.Cu" "F.Mask" "F.Paste")
			(net "DRIVE_25_ACT")
		)
		(pad "AB2" smd circle
			(at -14.500098 5.500116)
			(size 0.4572 0.4572)
			(layers "F.Cu" "F.Mask" "F.Paste")
			(net "DRIVE_28_ACT")
		)
		(pad "AB3" smd circle
			(at -13.5001 5.500116)
			(size 0.4572 0.4572)
			(layers "F.Cu" "F.Mask" "F.Paste")
			(net "GND")
		)
		(pad "AB4" smd circle
			(at -12.500102 5.500116)
			(size 0.4572 0.4572)
			(layers "F.Cu" "F.Mask" "F.Paste")
			(net "DRIVE_27_ACT")
		)
		(pad "AB5" smd circle
			(at -11.500104 5.500116)
			(size 0.4572 0.4572)
			(layers "F.Cu" "F.Mask" "F.Paste")
			(net "DRIVE_29_ACT")
		)
		(pad "AB6" smd circle
			(at -10.500106 5.500116)
			(size 0.4572 0.4572)
			(layers "F.Cu" "F.Mask" "F.Paste")
			(net "P1V8_E")
		)
		(pad "AB7" smd circle
			(at -9.500108 5.500116)
			(size 0.4572 0.4572)
			(layers "F.Cu" "F.Mask" "F.Paste")
			(net "DRIVE_30_ACT")
		)
		(pad "AB8" smd circle
			(at -8.50011 5.500116)
			(size 0.4572 0.4572)
			(layers "F.Cu" "F.Mask" "F.Paste")
			(net "LED41")
		)
		(pad "AB9" smd circle
			(at -7.500112 5.500116)
			(size 0.4572 0.4572)
			(layers "F.Cu" "F.Mask" "F.Paste")
			(net "P1V8_E")
		)
		(pad "AB10" smd circle
			(at -6.500114 5.500116)
			(size 0.4572 0.4572)
			(layers "F.Cu" "F.Mask" "F.Paste")
			(net "GND")
		)
		(pad "AB11" smd circle
			(at -5.500116 5.500116)
			(size 0.4572 0.4572)
			(layers "F.Cu" "F.Mask" "F.Paste")
			(net "GND")
		)
		(pad "AB12" smd circle
			(at -4.500118 5.500116)
			(size 0.4572 0.4572)
			(layers "F.Cu" "F.Mask" "F.Paste")
			(net "GND")
		)
		(pad "AB13" smd circle
			(at -3.50012 5.500116)
			(size 0.4572 0.4572)
			(layers "F.Cu" "F.Mask" "F.Paste")
			(net "GND")
		)
		(pad "AB14" smd circle
			(at -2.500122 5.500116)
			(size 0.4572 0.4572)
			(layers "F.Cu" "F.Mask" "F.Paste")
			(net "GND")
		)
		(pad "AB15" smd circle
			(at -1.500124 5.500116)
			(size 0.4572 0.4572)
			(layers "F.Cu" "F.Mask" "F.Paste")
			(net "GND")
		)
		(pad "AB16" smd circle
			(at -0.500126 5.500116)
			(size 0.4572 0.4572)
			(layers "F.Cu" "F.Mask" "F.Paste")
			(net "GND")
		)
		(pad "AB17" smd circle
			(at 0.500126 5.500116)
			(size 0.4572 0.4572)
			(layers "F.Cu" "F.Mask" "F.Paste")
			(net "GND")
		)
		(pad "AB18" smd circle
			(at 1.500124 5.500116)
			(size 0.4572 0.4572)
			(layers "F.Cu" "F.Mask" "F.Paste")
			(net "GND")
		)
		(pad "AB19" smd circle
			(at 2.500122 5.500116)
			(size 0.4572 0.4572)
			(layers "F.Cu" "F.Mask" "F.Paste")
			(net "GND")
		)
		(pad "AB20" smd circle
			(at 3.50012 5.500116)
			(size 0.4572 0.4572)
			(layers "F.Cu" "F.Mask" "F.Paste")
			(net "GND")
		)
		(pad "AB21" smd circle
			(at 4.500118 5.500116)
			(size 0.4572 0.4572)
			(layers "F.Cu" "F.Mask" "F.Paste")
			(net "GND")
		)
		(pad "AB22" smd circle
			(at 5.500116 5.500116)
			(size 0.4572 0.4572)
			(layers "F.Cu" "F.Mask" "F.Paste")
			(net "GND")
		)
		(pad "AB23" smd circle
			(at 6.500114 5.500116)
			(size 0.4572 0.4572)
			(layers "F.Cu" "F.Mask" "F.Paste")
			(net "GND")
		)
		(pad "AB24" smd circle
			(at 7.500112 5.500116)
			(size 0.4572 0.4572)
			(layers "F.Cu" "F.Mask" "F.Paste")
			(net "GND")
		)
		(pad "AB25" smd circle
			(at 8.50011 5.500116)
			(size 0.4572 0.4572)
			(layers "F.Cu" "F.Mask" "F.Paste")
			(net "GND")
		)
		(pad "AB26" smd circle
			(at 9.500108 5.500116)
			(size 0.4572 0.4572)
			(layers "F.Cu" "F.Mask" "F.Paste")
			(net "GND")
		)
		(pad "AB27" smd circle
			(at 10.500106 5.500116)
			(size 0.4572 0.4572)
			(layers "F.Cu" "F.Mask" "F.Paste")
			(net "PHY_DPB_TO_SCC_C_28_DN")
		)
		(pad "AB28" smd circle
			(at 11.500104 5.500116)
			(size 0.4572 0.4572)
			(layers "F.Cu" "F.Mask" "F.Paste")
			(net "PHY_DPB_TO_SCC_C_28_DP")
		)
		(pad "AB29" smd circle
			(at 12.500102 5.500116)
			(size 0.4572 0.4572)
			(layers "F.Cu" "F.Mask" "F.Paste")
			(net "GB_VDDA")
		)
		(pad "AB30" smd circle
			(at 13.5001 5.500116)
			(size 0.4572 0.4572)
			(layers "F.Cu" "F.Mask" "F.Paste")
			(net "PHY_SCC_TO_DPB_28_DN")
		)
		(pad "AB31" smd circle
			(at 14.500098 5.500116)
			(size 0.4572 0.4572)
			(layers "F.Cu" "F.Mask" "F.Paste")
			(net "PHY_SCC_TO_DPB_28_DP")
		)
		(pad "AB32" smd circle
			(at 15.500096 5.500116)
			(size 0.4572 0.4572)
			(layers "F.Cu" "F.Mask" "F.Paste")
			(net "GND")
		)
		(pad "AC1" smd circle
			(at -15.500096 6.500114)
			(size 0.4572 0.4572)
			(layers "F.Cu" "F.Mask" "F.Paste")
			(net "DRIVE_33_ACT")
		)
		(pad "AC2" smd circle
			(at -14.500098 6.500114)
			(size 0.4572 0.4572)
			(layers "F.Cu" "F.Mask" "F.Paste")
			(net "DRIVE_32_ACT")
		)
		(pad "AC3" smd circle
			(at -13.5001 6.500114)
			(size 0.4572 0.4572)
			(layers "F.Cu" "F.Mask" "F.Paste")
			(net "P1V8_E")
		)
		(pad "AC4" smd circle
			(at -12.500102 6.500114)
			(size 0.4572 0.4572)
			(layers "F.Cu" "F.Mask" "F.Paste")
			(net "DRIVE_34_ACT")
		)
		(pad "AC5" smd circle
			(at -11.500104 6.500114)
			(size 0.4572 0.4572)
			(layers "F.Cu" "F.Mask" "F.Paste")
			(net "DRIVE_35_ACT")
		)
		(pad "AC6" smd circle
			(at -10.500106 6.500114)
			(size 0.4572 0.4572)
			(layers "F.Cu" "F.Mask" "F.Paste")
			(net "GND")
		)
		(pad "AC7" smd circle
			(at -9.500108 6.500114)
			(size 0.4572 0.4572)
			(layers "F.Cu" "F.Mask" "F.Paste")
			(net "DRIVE_38_ACT")
		)
		(pad "AC8" smd circle
			(at -8.50011 6.500114)
			(size 0.4572 0.4572)
			(layers "F.Cu" "F.Mask" "F.Paste")
			(net "LED47")
		)
		(pad "AC9" smd circle
			(at -7.500112 6.500114)
			(size 0.4572 0.4572)
			(layers "F.Cu" "F.Mask" "F.Paste")
			(net "GND")
		)
		(pad "AC10" smd circle
			(at -6.500114 6.500114)
			(size 0.4572 0.4572)
			(layers "F.Cu" "F.Mask" "F.Paste")
			(net "GND")
		)
		(pad "AC11" smd circle
			(at -5.500116 6.500114)
			(size 0.4572 0.4572)
			(layers "F.Cu" "F.Mask" "F.Paste")
			(net "GB_VDDA")
		)
		(pad "AC12" smd circle
			(at -4.500118 6.500114)
			(size 0.4572 0.4572)
			(layers "F.Cu" "F.Mask" "F.Paste")
			(net "GND")
		)
		(pad "AC13" smd circle
			(at -3.50012 6.500114)
			(size 0.4572 0.4572)
			(layers "F.Cu" "F.Mask" "F.Paste")
			(net "GB_VDDA")
		)
		(pad "AC14" smd circle
			(at -2.500122 6.500114)
			(size 0.4572 0.4572)
			(layers "F.Cu" "F.Mask" "F.Paste")
			(net "GND")
		)
		(pad "AC15" smd circle
			(at -1.500124 6.500114)
			(size 0.4572 0.4572)
			(layers "F.Cu" "F.Mask" "F.Paste")
			(net "GB_VDDA")
		)
		(pad "AC16" smd circle
			(at -0.500126 6.500114)
			(size 0.4572 0.4572)
			(layers "F.Cu" "F.Mask" "F.Paste")
			(net "GND")
		)
		(pad "AC17" smd circle
			(at 0.500126 6.500114)
			(size 0.4572 0.4572)
			(layers "F.Cu" "F.Mask" "F.Paste")
			(net "GB_VDDA")
		)
		(pad "AC18" smd circle
			(at 1.500124 6.500114)
			(size 0.4572 0.4572)
			(layers "F.Cu" "F.Mask" "F.Paste")
			(net "GND")
		)
		(pad "AC19" smd circle
			(at 2.500122 6.500114)
			(size 0.4572 0.4572)
			(layers "F.Cu" "F.Mask" "F.Paste")
			(net "GB_VDDA")
		)
		(pad "AC20" smd circle
			(at 3.50012 6.500114)
			(size 0.4572 0.4572)
			(layers "F.Cu" "F.Mask" "F.Paste")
			(net "GND")
		)
		(pad "AC21" smd circle
			(at 4.500118 6.500114)
			(size 0.4572 0.4572)
			(layers "F.Cu" "F.Mask" "F.Paste")
			(net "GB_VDDA")
		)
		(pad "AC22" smd circle
			(at 5.500116 6.500114)
			(size 0.4572 0.4572)
			(layers "F.Cu" "F.Mask" "F.Paste")
			(net "GND")
		)
		(pad "AC23" smd circle
			(at 6.500114 6.500114)
			(size 0.4572 0.4572)
			(layers "F.Cu" "F.Mask" "F.Paste")
			(net "GND")
		)
		(pad "AC24" smd circle
			(at 7.500112 6.500114)
			(size 0.4572 0.4572)
			(layers "F.Cu" "F.Mask" "F.Paste")
			(net "GB_VDDA")
		)
		(pad "AC25" smd circle
			(at 8.50011 6.500114)
			(size 0.4572 0.4572)
			(layers "F.Cu" "F.Mask" "F.Paste")
			(net "GND")
		)
		(pad "AC26" smd circle
			(at 9.500108 6.500114)
			(size 0.4572 0.4572)
			(layers "F.Cu" "F.Mask" "F.Paste")
			(net "GND")
		)
		(pad "AC27" smd circle
			(at 10.500106 6.500114)
			(size 0.4572 0.4572)
			(layers "F.Cu" "F.Mask" "F.Paste")
			(net "PHY_IOC_TO_SCC_C_47_DN")
		)
		(pad "AC28" smd circle
			(at 11.500104 6.500114)
			(size 0.4572 0.4572)
			(layers "F.Cu" "F.Mask" "F.Paste")
			(net "PHY_IOC_TO_SCC_C_47_DP")
		)
		(pad "AC29" smd circle
			(at 12.500102 6.500114)
			(size 0.4572 0.4572)
			(layers "F.Cu" "F.Mask" "F.Paste")
			(net "GND")
		)
		(pad "AC30" smd circle
			(at 13.5001 6.500114)
			(size 0.4572 0.4572)
			(layers "F.Cu" "F.Mask" "F.Paste")
			(net "GB_VDDA")
		)
		(pad "AC31" smd circle
			(at 14.500098 6.500114)
			(size 0.4572 0.4572)
			(layers "F.Cu" "F.Mask" "F.Paste")
			(net "PHY_SCC_TO_IOC_47_DN")
		)
		(pad "AC32" smd circle
			(at 15.500096 6.500114)
			(size 0.4572 0.4572)
			(layers "F.Cu" "F.Mask" "F.Paste")
			(net "PHY_SCC_TO_IOC_47_DP")
		)
		(pad "AD1" smd circle
			(at -15.500096 7.500112)
			(size 0.4572 0.4572)
			(layers "F.Cu" "F.Mask" "F.Paste")
			(net "DRIVE_37_ACT")
		)
		(pad "AD2" smd circle
			(at -14.500098 7.500112)
			(size 0.4572 0.4572)
			(layers "F.Cu" "F.Mask" "F.Paste")
			(net "DRIVE_39_ACT")
		)
		(pad "AD3" smd circle
			(at -13.5001 7.500112)
			(size 0.4572 0.4572)
			(layers "F.Cu" "F.Mask" "F.Paste")
			(net "GND")
		)
		(pad "AD4" smd circle
			(at -12.500102 7.500112)
			(size 0.4572 0.4572)
			(layers "F.Cu" "F.Mask" "F.Paste")
			(net "LED40")
		)
		(pad "AD5" smd circle
			(at -11.500104 7.500112)
			(size 0.4572 0.4572)
			(layers "F.Cu" "F.Mask" "F.Paste")
			(net "LED43")
		)
		(pad "AD6" smd circle
			(at -10.500106 7.500112)
			(size 0.4572 0.4572)
			(layers "F.Cu" "F.Mask" "F.Paste")
			(net "P1V8_E")
		)
		(pad "AD7" smd circle
			(at -9.500108 7.500112)
			(size 0.4572 0.4572)
			(layers "F.Cu" "F.Mask" "F.Paste")
			(net "LED44")
		)
		(pad "AD8" smd circle
			(at -8.50011 7.500112)
			(size 0.4572 0.4572)
			(layers "F.Cu" "F.Mask" "F.Paste")
			(net "GND")
		)
		(pad "AD9" smd circle
			(at -7.500112 7.500112)
			(size 0.4572 0.4572)
			(layers "F.Cu" "F.Mask" "F.Paste")
			(net "GND")
		)
		(pad "AD10" smd circle
			(at -6.500114 7.500112)
			(size 0.4572 0.4572)
			(layers "F.Cu" "F.Mask" "F.Paste")
			(net "GB_VDDA")
		)
		(pad "AD11" smd circle
			(at -5.500116 7.500112)
			(size 0.4572 0.4572)
			(layers "F.Cu" "F.Mask" "F.Paste")
			(net "GND")
		)
		(pad "AD12" smd circle
			(at -4.500118 7.500112)
			(size 0.4572 0.4572)
			(layers "F.Cu" "F.Mask" "F.Paste")
			(net "GB_VDDA")
		)
		(pad "AD13" smd circle
			(at -3.50012 7.500112)
			(size 0.4572 0.4572)
			(layers "F.Cu" "F.Mask" "F.Paste")
			(net "GND")
		)
		(pad "AD14" smd circle
			(at -2.500122 7.500112)
			(size 0.4572 0.4572)
			(layers "F.Cu" "F.Mask" "F.Paste")
			(net "GB_VDDA")
		)
		(pad "AD15" smd circle
			(at -1.500124 7.500112)
			(size 0.4572 0.4572)
			(layers "F.Cu" "F.Mask" "F.Paste")
			(net "GND")
		)
		(pad "AD16" smd circle
			(at -0.500126 7.500112)
			(size 0.4572 0.4572)
			(layers "F.Cu" "F.Mask" "F.Paste")
			(net "GB_VDDA")
		)
		(pad "AD17" smd circle
			(at 0.500126 7.500112)
			(size 0.4572 0.4572)
			(layers "F.Cu" "F.Mask" "F.Paste")
			(net "GND")
		)
		(pad "AD18" smd circle
			(at 1.500124 7.500112)
			(size 0.4572 0.4572)
			(layers "F.Cu" "F.Mask" "F.Paste")
			(net "GB_VDDA")
		)
		(pad "AD19" smd circle
			(at 2.500122 7.500112)
			(size 0.4572 0.4572)
			(layers "F.Cu" "F.Mask" "F.Paste")
			(net "GND")
		)
		(pad "AD20" smd circle
			(at 3.50012 7.500112)
			(size 0.4572 0.4572)
			(layers "F.Cu" "F.Mask" "F.Paste")
			(net "GB_VDDA")
		)
		(pad "AD21" smd circle
			(at 4.500118 7.500112)
			(size 0.4572 0.4572)
			(layers "F.Cu" "F.Mask" "F.Paste")
			(net "GND")
		)
		(pad "AD22" smd circle
			(at 5.500116 7.500112)
			(size 0.4572 0.4572)
			(layers "F.Cu" "F.Mask" "F.Paste")
			(net "GB_VDDA")
		)
		(pad "AD23" smd circle
			(at 6.500114 7.500112)
			(size 0.4572 0.4572)
			(layers "F.Cu" "F.Mask" "F.Paste")
			(net "GND")
		)
		(pad "AD24" smd circle
			(at 7.500112 7.500112)
			(size 0.4572 0.4572)
			(layers "F.Cu" "F.Mask" "F.Paste")
			(net "GND")
		)
		(pad "AD25" smd circle
			(at 8.50011 7.500112)
			(size 0.4572 0.4572)
			(layers "F.Cu" "F.Mask" "F.Paste")
			(net "GB_VDDA")
		)
		(pad "AD26" smd circle
			(at 9.500108 7.500112)
			(size 0.4572 0.4572)
			(layers "F.Cu" "F.Mask" "F.Paste")
			(net "GND")
		)
		(pad "AD27" smd circle
			(at 10.500106 7.500112)
			(size 0.4572 0.4572)
			(layers "F.Cu" "F.Mask" "F.Paste")
			(net "PHY_IOC_TO_SCC_C_46_DN")
		)
		(pad "AD28" smd circle
			(at 11.500104 7.500112)
			(size 0.4572 0.4572)
			(layers "F.Cu" "F.Mask" "F.Paste")
			(net "PHY_IOC_TO_SCC_C_46_DP")
		)
		(pad "AD29" smd circle
			(at 12.500102 7.500112)
			(size 0.4572 0.4572)
			(layers "F.Cu" "F.Mask" "F.Paste")
			(net "GB_VDDA")
		)
		(pad "AD30" smd circle
			(at 13.5001 7.500112)
			(size 0.4572 0.4572)
			(layers "F.Cu" "F.Mask" "F.Paste")
			(net "PHY_SCC_TO_IOC_46_DN")
		)
		(pad "AD31" smd circle
			(at 14.500098 7.500112)
			(size 0.4572 0.4572)
			(layers "F.Cu" "F.Mask" "F.Paste")
			(net "PHY_SCC_TO_IOC_46_DP")
		)
		(pad "AD32" smd circle
			(at 15.500096 7.500112)
			(size 0.4572 0.4572)
			(layers "F.Cu" "F.Mask" "F.Paste")
			(net "GND")
		)
		(pad "AE1" smd circle
			(at -15.500096 8.50011)
			(size 0.4572 0.4572)
			(layers "F.Cu" "F.Mask" "F.Paste")
			(net "GND")
		)
		(pad "AE2" smd circle
			(at -14.500098 8.50011)
			(size 0.4572 0.4572)
			(layers "F.Cu" "F.Mask" "F.Paste")
			(net "GND")
		)
		(pad "AE3" smd circle
			(at -13.5001 8.50011)
			(size 0.4572 0.4572)
			(layers "F.Cu" "F.Mask" "F.Paste")
			(net "P1V8_E")
		)
		(pad "AE4" smd circle
			(at -12.500102 8.50011)
			(size 0.4572 0.4572)
			(layers "F.Cu" "F.Mask" "F.Paste")
			(net "LED42")
		)
		(pad "AE5" smd circle
			(at -11.500104 8.50011)
			(size 0.4572 0.4572)
			(layers "F.Cu" "F.Mask" "F.Paste")
			(net "LED45")
		)
		(pad "AE6" smd circle
			(at -10.500106 8.50011)
			(size 0.4572 0.4572)
			(layers "F.Cu" "F.Mask" "F.Paste")
			(net "GND")
		)
		(pad "AE7" smd circle
			(at -9.500108 8.50011)
			(size 0.4572 0.4572)
			(layers "F.Cu" "F.Mask" "F.Paste")
			(net "GND")
		)
		(pad "AE8" smd circle
			(at -8.50011 8.50011)
			(size 0.4572 0.4572)
			(layers "F.Cu" "F.Mask" "F.Paste")
			(net "GND")
		)
		(pad "AE9" smd circle
			(at -7.500112 8.50011)
			(size 0.4572 0.4572)
			(layers "F.Cu" "F.Mask" "F.Paste")
			(net "GB_VDDA")
		)
		(pad "AE10" smd circle
			(at -6.500114 8.50011)
			(size 0.4572 0.4572)
			(layers "F.Cu" "F.Mask" "F.Paste")
			(net "GND")
		)
		(pad "AE11" smd circle
			(at -5.500116 8.50011)
			(size 0.4572 0.4572)
			(layers "F.Cu" "F.Mask" "F.Paste")
			(net "GB_VDDA")
		)
		(pad "AE12" smd circle
			(at -4.500118 8.50011)
			(size 0.4572 0.4572)
			(layers "F.Cu" "F.Mask" "F.Paste")
			(net "GND")
		)
		(pad "AE13" smd circle
			(at -3.50012 8.50011)
			(size 0.4572 0.4572)
			(layers "F.Cu" "F.Mask" "F.Paste")
			(net "GB_VDDA")
		)
		(pad "AE14" smd circle
			(at -2.500122 8.50011)
			(size 0.4572 0.4572)
			(layers "F.Cu" "F.Mask" "F.Paste")
			(net "GND")
		)
		(pad "AE15" smd circle
			(at -1.500124 8.50011)
			(size 0.4572 0.4572)
			(layers "F.Cu" "F.Mask" "F.Paste")
			(net "GB_VDDA")
		)
		(pad "AE16" smd circle
			(at -0.500126 8.50011)
			(size 0.4572 0.4572)
			(layers "F.Cu" "F.Mask" "F.Paste")
			(net "GND")
		)
		(pad "AE17" smd circle
			(at 0.500126 8.50011)
			(size 0.4572 0.4572)
			(layers "F.Cu" "F.Mask" "F.Paste")
			(net "GB_VDDA")
		)
		(pad "AE18" smd circle
			(at 1.500124 8.50011)
			(size 0.4572 0.4572)
			(layers "F.Cu" "F.Mask" "F.Paste")
			(net "GND")
		)
		(pad "AE19" smd circle
			(at 2.500122 8.50011)
			(size 0.4572 0.4572)
			(layers "F.Cu" "F.Mask" "F.Paste")
			(net "GB_VDDA")
		)
		(pad "AE20" smd circle
			(at 3.50012 8.50011)
			(size 0.4572 0.4572)
			(layers "F.Cu" "F.Mask" "F.Paste")
			(net "GND")
		)
		(pad "AE21" smd circle
			(at 4.500118 8.50011)
			(size 0.4572 0.4572)
			(layers "F.Cu" "F.Mask" "F.Paste")
			(net "GB_VDDA")
		)
		(pad "AE22" smd circle
			(at 5.500116 8.50011)
			(size 0.4572 0.4572)
			(layers "F.Cu" "F.Mask" "F.Paste")
			(net "GND")
		)
		(pad "AE23" smd circle
			(at 6.500114 8.50011)
			(size 0.4572 0.4572)
			(layers "F.Cu" "F.Mask" "F.Paste")
			(net "GB_VDDA")
		)
		(pad "AE24" smd circle
			(at 7.500112 8.50011)
			(size 0.4572 0.4572)
			(layers "F.Cu" "F.Mask" "F.Paste")
			(net "GND")
		)
		(pad "AE25" smd circle
			(at 8.50011 8.50011)
			(size 0.4572 0.4572)
			(layers "F.Cu" "F.Mask" "F.Paste")
			(net "GND")
		)
		(pad "AE26" smd circle
			(at 9.500108 8.50011)
			(size 0.4572 0.4572)
			(layers "F.Cu" "F.Mask" "F.Paste")
			(net "GND")
		)
		(pad "AE27" smd circle
			(at 10.500106 8.50011)
			(size 0.4572 0.4572)
			(layers "F.Cu" "F.Mask" "F.Paste")
			(net "PHY_IOC_TO_SCC_C_45_DN")
		)
		(pad "AE28" smd circle
			(at 11.500104 8.50011)
			(size 0.4572 0.4572)
			(layers "F.Cu" "F.Mask" "F.Paste")
			(net "PHY_IOC_TO_SCC_C_45_DP")
		)
		(pad "AE29" smd circle
			(at 12.500102 8.50011)
			(size 0.4572 0.4572)
			(layers "F.Cu" "F.Mask" "F.Paste")
			(net "GND")
		)
		(pad "AE30" smd circle
			(at 13.5001 8.50011)
			(size 0.4572 0.4572)
			(layers "F.Cu" "F.Mask" "F.Paste")
			(net "GB_VDDA")
		)
		(pad "AE31" smd circle
			(at 14.500098 8.50011)
			(size 0.4572 0.4572)
			(layers "F.Cu" "F.Mask" "F.Paste")
			(net "PHY_SCC_TO_IOC_45_DN")
		)
		(pad "AE32" smd circle
			(at 15.500096 8.50011)
			(size 0.4572 0.4572)
			(layers "F.Cu" "F.Mask" "F.Paste")
			(net "PHY_SCC_TO_IOC_45_DP")
		)
		(pad "AF1" smd circle
			(at -15.500096 9.500108)
			(size 0.4572 0.4572)
			(layers "F.Cu" "F.Mask" "F.Paste")
			(net "EXP_REF_CLK_P")
		)
		(pad "AF2" smd circle
			(at -14.500098 9.500108)
			(size 0.4572 0.4572)
			(layers "F.Cu" "F.Mask" "F.Paste")
			(net "EXP_REF_CLK_N")
		)
		(pad "AF3" smd circle
			(at -13.5001 9.500108)
			(size 0.4572 0.4572)
			(layers "F.Cu" "F.Mask" "F.Paste")
			(net "XTAL_VDDA18")
		)
		(pad "AF4" smd circle
			(at -12.500102 9.500108)
			(size 0.4572 0.4572)
			(layers "F.Cu" "F.Mask" "F.Paste")
			(net "GND")
		)
		(pad "AF5" smd circle
			(at -11.500104 9.500108)
			(size 0.4572 0.4572)
			(layers "F.Cu" "F.Mask" "F.Paste")
			(net "GND")
		)
		(pad "AF6" smd circle
			(at -10.500106 9.500108)
			(size 0.4572 0.4572)
			(layers "F.Cu" "F.Mask" "F.Paste")
			(net "GND")
		)
		(pad "AF7" smd circle
			(at -9.500108 9.500108)
			(size 0.4572 0.4572)
			(layers "F.Cu" "F.Mask" "F.Paste")
			(net "GND")
		)
		(pad "AF8" smd circle
			(at -8.50011 9.500108)
			(size 0.4572 0.4572)
			(layers "F.Cu" "F.Mask" "F.Paste")
			(net "GND")
		)
		(pad "AF9" smd circle
			(at -7.500112 9.500108)
			(size 0.4572 0.4572)
			(layers "F.Cu" "F.Mask" "F.Paste")
			(net "GND")
		)
		(pad "AF10" smd circle
			(at -6.500114 9.500108)
			(size 0.4572 0.4572)
			(layers "F.Cu" "F.Mask" "F.Paste")
			(net "GND")
		)
		(pad "AF11" smd circle
			(at -5.500116 9.500108)
			(size 0.4572 0.4572)
			(layers "F.Cu" "F.Mask" "F.Paste")
			(net "GND")
		)
		(pad "AF12" smd circle
			(at -4.500118 9.500108)
			(size 0.4572 0.4572)
			(layers "F.Cu" "F.Mask" "F.Paste")
			(net "GB_VDDA")
		)
		(pad "AF13" smd circle
			(at -3.50012 9.500108)
			(size 0.4572 0.4572)
			(layers "F.Cu" "F.Mask" "F.Paste")
			(net "GND")
		)
		(pad "AF14" smd circle
			(at -2.500122 9.500108)
			(size 0.4572 0.4572)
			(layers "F.Cu" "F.Mask" "F.Paste")
			(net "GB_VDDA")
		)
		(pad "AF15" smd circle
			(at -1.500124 9.500108)
			(size 0.4572 0.4572)
			(layers "F.Cu" "F.Mask" "F.Paste")
			(net "GND")
		)
		(pad "AF16" smd circle
			(at -0.500126 9.500108)
			(size 0.4572 0.4572)
			(layers "F.Cu" "F.Mask" "F.Paste")
			(net "GB_VDDA")
		)
		(pad "AF17" smd circle
			(at 0.500126 9.500108)
			(size 0.4572 0.4572)
			(layers "F.Cu" "F.Mask" "F.Paste")
			(net "GND")
		)
		(pad "AF18" smd circle
			(at 1.500124 9.500108)
			(size 0.4572 0.4572)
			(layers "F.Cu" "F.Mask" "F.Paste")
			(net "GB_VDDA")
		)
		(pad "AF19" smd circle
			(at 2.500122 9.500108)
			(size 0.4572 0.4572)
			(layers "F.Cu" "F.Mask" "F.Paste")
			(net "GND")
		)
		(pad "AF20" smd circle
			(at 3.50012 9.500108)
			(size 0.4572 0.4572)
			(layers "F.Cu" "F.Mask" "F.Paste")
			(net "GB_VDDA")
		)
		(pad "AF21" smd circle
			(at 4.500118 9.500108)
			(size 0.4572 0.4572)
			(layers "F.Cu" "F.Mask" "F.Paste")
			(net "GND")
		)
		(pad "AF22" smd circle
			(at 5.500116 9.500108)
			(size 0.4572 0.4572)
			(layers "F.Cu" "F.Mask" "F.Paste")
			(net "GB_VDDA")
		)
		(pad "AF23" smd circle
			(at 6.500114 9.500108)
			(size 0.4572 0.4572)
			(layers "F.Cu" "F.Mask" "F.Paste")
			(net "GND")
		)
		(pad "AF24" smd circle
			(at 7.500112 9.500108)
			(size 0.4572 0.4572)
			(layers "F.Cu" "F.Mask" "F.Paste")
			(net "GB_VDDA")
		)
		(pad "AF25" smd circle
			(at 8.50011 9.500108)
			(size 0.4572 0.4572)
			(layers "F.Cu" "F.Mask" "F.Paste")
			(net "GND")
		)
		(pad "AF26" smd circle
			(at 9.500108 9.500108)
			(size 0.4572 0.4572)
			(layers "F.Cu" "F.Mask" "F.Paste")
			(net "GND")
		)
		(pad "AF27" smd circle
			(at 10.500106 9.500108)
			(size 0.4572 0.4572)
			(layers "F.Cu" "F.Mask" "F.Paste")
			(net "PHY_IOC_TO_SCC_C_44_DN")
		)
		(pad "AF28" smd circle
			(at 11.500104 9.500108)
			(size 0.4572 0.4572)
			(layers "F.Cu" "F.Mask" "F.Paste")
			(net "PHY_IOC_TO_SCC_C_44_DP")
		)
		(pad "AF29" smd circle
			(at 12.500102 9.500108)
			(size 0.4572 0.4572)
			(layers "F.Cu" "F.Mask" "F.Paste")
			(net "GB_VDDA")
		)
		(pad "AF30" smd circle
			(at 13.5001 9.500108)
			(size 0.4572 0.4572)
			(layers "F.Cu" "F.Mask" "F.Paste")
			(net "PHY_SCC_TO_IOC_44_DN")
		)
		(pad "AF31" smd circle
			(at 14.500098 9.500108)
			(size 0.4572 0.4572)
			(layers "F.Cu" "F.Mask" "F.Paste")
			(net "PHY_SCC_TO_IOC_44_DP")
		)
		(pad "AF32" smd circle
			(at 15.500096 9.500108)
			(size 0.4572 0.4572)
			(layers "F.Cu" "F.Mask" "F.Paste")
			(net "GND")
		)
		(pad "AG1" smd circle
			(at -15.500096 10.500106)
			(size 0.4572 0.4572)
			(layers "F.Cu" "F.Mask" "F.Paste")
			(net "GND")
		)
		(pad "AG2" smd circle
			(at -14.500098 10.500106)
			(size 0.4572 0.4572)
			(layers "F.Cu" "F.Mask" "F.Paste")
			(net "GND")
		)
		(pad "AG3" smd circle
			(at -13.5001 10.500106)
			(size 0.4572 0.4572)
			(layers "F.Cu" "F.Mask" "F.Paste")
			(net "PHY_DPB_TO_SCC_C_13_DN")
		)
		(pad "AG4" smd circle
			(at -12.500102 10.500106)
			(size 0.4572 0.4572)
			(layers "F.Cu" "F.Mask" "F.Paste")
			(net "PHY_DPB_TO_SCC_C_14_DN")
		)
		(pad "AG5" smd circle
			(at -11.500104 10.500106)
			(size 0.4572 0.4572)
			(layers "F.Cu" "F.Mask" "F.Paste")
			(net "PHY_DPB_TO_SCC_C_15_DN")
		)
		(pad "AG6" smd circle
			(at -10.500106 10.500106)
			(size 0.4572 0.4572)
			(layers "F.Cu" "F.Mask" "F.Paste")
			(net "PHY_DPB_TO_SCC_C_16_DN")
		)
		(pad "AG7" smd circle
			(at -9.500108 10.500106)
			(size 0.4572 0.4572)
			(layers "F.Cu" "F.Mask" "F.Paste")
			(net "PHY_DPB_TO_SCC_C_17_DN")
		)
		(pad "AG8" smd circle
			(at -8.50011 10.500106)
			(size 0.4572 0.4572)
			(layers "F.Cu" "F.Mask" "F.Paste")
			(net "PHY_DPB_TO_SCC_C_18_DN")
		)
		(pad "AG9" smd circle
			(at -7.500112 10.500106)
			(size 0.4572 0.4572)
			(layers "F.Cu" "F.Mask" "F.Paste")
			(net "PHY_DPB_TO_SCC_C_19_DN")
		)
		(pad "AG10" smd circle
			(at -6.500114 10.500106)
			(size 0.4572 0.4572)
			(layers "F.Cu" "F.Mask" "F.Paste")
			(net "PHY_DPB_TO_SCC_C_20_DN")
		)
		(pad "AG11" smd circle
			(at -5.500116 10.500106)
			(size 0.4572 0.4572)
			(layers "F.Cu" "F.Mask" "F.Paste")
			(net "PHY_DPB_TO_SCC_C_21_DN")
		)
		(pad "AG12" smd circle
			(at -4.500118 10.500106)
			(size 0.4572 0.4572)
			(layers "F.Cu" "F.Mask" "F.Paste")
			(net "PHY_DPB_TO_SCC_C_22_DN")
		)
		(pad "AG13" smd circle
			(at -3.50012 10.500106)
			(size 0.4572 0.4572)
			(layers "F.Cu" "F.Mask" "F.Paste")
			(net "PHY_DPB_TO_SCC_C_23_DN")
		)
		(pad "AG14" smd circle
			(at -2.500122 10.500106)
			(size 0.4572 0.4572)
			(layers "F.Cu" "F.Mask" "F.Paste")
			(net "PHY_DPB_TO_SCC_C_24_DN")
		)
		(pad "AG15" smd circle
			(at -1.500124 10.500106)
			(size 0.4572 0.4572)
			(layers "F.Cu" "F.Mask" "F.Paste")
			(net "PHY_DPB_TO_SCC_C_25_DN")
		)
		(pad "AG16" smd circle
			(at -0.500126 10.500106)
			(size 0.4572 0.4572)
			(layers "F.Cu" "F.Mask" "F.Paste")
			(net "PHY_DPB_TO_SCC_C_26_DN")
		)
		(pad "AG17" smd circle
			(at 0.500126 10.500106)
			(size 0.4572 0.4572)
			(layers "F.Cu" "F.Mask" "F.Paste")
			(net "PHY_DPB_TO_SCC_C_27_DN")
		)
		(pad "AG18" smd circle
			(at 1.500124 10.500106)
			(size 0.4572 0.4572)
			(layers "F.Cu" "F.Mask" "F.Paste")
			(net "PHY_DPB_TO_SCC_C_32_DN")
		)
		(pad "AG19" smd circle
			(at 2.500122 10.500106)
			(size 0.4572 0.4572)
			(layers "F.Cu" "F.Mask" "F.Paste")
			(net "PHY_DPB_TO_SCC_C_33_DN")
		)
		(pad "AG20" smd circle
			(at 3.50012 10.500106)
			(size 0.4572 0.4572)
			(layers "F.Cu" "F.Mask" "F.Paste")
			(net "PHY_DPB_TO_SCC_C_34_DN")
		)
		(pad "AG21" smd circle
			(at 4.500118 10.500106)
			(size 0.4572 0.4572)
			(layers "F.Cu" "F.Mask" "F.Paste")
			(net "PHY_DPB_TO_SCC_C_35_DN")
		)
		(pad "AG22" smd circle
			(at 5.500116 10.500106)
			(size 0.4572 0.4572)
			(layers "F.Cu" "F.Mask" "F.Paste")
			(net "PHY_DPB_TO_SCC_C_36_DN")
		)
		(pad "AG23" smd circle
			(at 6.500114 10.500106)
			(size 0.4572 0.4572)
			(layers "F.Cu" "F.Mask" "F.Paste")
			(net "PHY_DPB_TO_SCC_C_37_DN")
		)
		(pad "AG24" smd circle
			(at 7.500112 10.500106)
			(size 0.4572 0.4572)
			(layers "F.Cu" "F.Mask" "F.Paste")
			(net "PHY_DPB_TO_SCC_C_38_DN")
		)
		(pad "AG25" smd circle
			(at 8.50011 10.500106)
			(size 0.4572 0.4572)
			(layers "F.Cu" "F.Mask" "F.Paste")
			(net "PHY_DPB_TO_SCC_C_39_DN")
		)
		(pad "AG26" smd circle
			(at 9.500108 10.500106)
			(size 0.4572 0.4572)
			(layers "F.Cu" "F.Mask" "F.Paste")
			(net "GND")
		)
		(pad "AG27" smd circle
			(at 10.500106 10.500106)
			(size 0.4572 0.4572)
			(layers "F.Cu" "F.Mask" "F.Paste")
			(net "PHY_IOC_TO_SCC_C_43_DN")
		)
		(pad "AG28" smd circle
			(at 11.500104 10.500106)
			(size 0.4572 0.4572)
			(layers "F.Cu" "F.Mask" "F.Paste")
			(net "PHY_IOC_TO_SCC_C_43_DP")
		)
		(pad "AG29" smd circle
			(at 12.500102 10.500106)
			(size 0.4572 0.4572)
			(layers "F.Cu" "F.Mask" "F.Paste")
			(net "GND")
		)
		(pad "AG30" smd circle
			(at 13.5001 10.500106)
			(size 0.4572 0.4572)
			(layers "F.Cu" "F.Mask" "F.Paste")
			(net "GB_VDDA")
		)
		(pad "AG31" smd circle
			(at 14.500098 10.500106)
			(size 0.4572 0.4572)
			(layers "F.Cu" "F.Mask" "F.Paste")
			(net "PHY_SCC_TO_IOC_43_DN")
		)
		(pad "AG32" smd circle
			(at 15.500096 10.500106)
			(size 0.4572 0.4572)
			(layers "F.Cu" "F.Mask" "F.Paste")
			(net "PHY_SCC_TO_IOC_43_DP")
		)
		(pad "AH1" smd circle
			(at -15.500096 11.500104)
			(size 0.4572 0.4572)
			(layers "F.Cu" "F.Mask" "F.Paste")
			(net "PHY_DPB_TO_SCC_C_12_DN")
		)
		(pad "AH2" smd circle
			(at -14.500098 11.500104)
			(size 0.4572 0.4572)
			(layers "F.Cu" "F.Mask" "F.Paste")
			(net "GND")
		)
		(pad "AH3" smd circle
			(at -13.5001 11.500104)
			(size 0.4572 0.4572)
			(layers "F.Cu" "F.Mask" "F.Paste")
			(net "PHY_DPB_TO_SCC_C_13_DP")
		)
		(pad "AH4" smd circle
			(at -12.500102 11.500104)
			(size 0.4572 0.4572)
			(layers "F.Cu" "F.Mask" "F.Paste")
			(net "PHY_DPB_TO_SCC_C_14_DP")
		)
		(pad "AH5" smd circle
			(at -11.500104 11.500104)
			(size 0.4572 0.4572)
			(layers "F.Cu" "F.Mask" "F.Paste")
			(net "PHY_DPB_TO_SCC_C_15_DP")
		)
		(pad "AH6" smd circle
			(at -10.500106 11.500104)
			(size 0.4572 0.4572)
			(layers "F.Cu" "F.Mask" "F.Paste")
			(net "PHY_DPB_TO_SCC_C_16_DP")
		)
		(pad "AH7" smd circle
			(at -9.500108 11.500104)
			(size 0.4572 0.4572)
			(layers "F.Cu" "F.Mask" "F.Paste")
			(net "PHY_DPB_TO_SCC_C_17_DP")
		)
		(pad "AH8" smd circle
			(at -8.50011 11.500104)
			(size 0.4572 0.4572)
			(layers "F.Cu" "F.Mask" "F.Paste")
			(net "PHY_DPB_TO_SCC_C_18_DP")
		)
		(pad "AH9" smd circle
			(at -7.500112 11.500104)
			(size 0.4572 0.4572)
			(layers "F.Cu" "F.Mask" "F.Paste")
			(net "PHY_DPB_TO_SCC_C_19_DP")
		)
		(pad "AH10" smd circle
			(at -6.500114 11.500104)
			(size 0.4572 0.4572)
			(layers "F.Cu" "F.Mask" "F.Paste")
			(net "PHY_DPB_TO_SCC_C_20_DP")
		)
		(pad "AH11" smd circle
			(at -5.500116 11.500104)
			(size 0.4572 0.4572)
			(layers "F.Cu" "F.Mask" "F.Paste")
			(net "PHY_DPB_TO_SCC_C_21_DP")
		)
		(pad "AH12" smd circle
			(at -4.500118 11.500104)
			(size 0.4572 0.4572)
			(layers "F.Cu" "F.Mask" "F.Paste")
			(net "PHY_DPB_TO_SCC_C_22_DP")
		)
		(pad "AH13" smd circle
			(at -3.50012 11.500104)
			(size 0.4572 0.4572)
			(layers "F.Cu" "F.Mask" "F.Paste")
			(net "PHY_DPB_TO_SCC_C_23_DP")
		)
		(pad "AH14" smd circle
			(at -2.500122 11.500104)
			(size 0.4572 0.4572)
			(layers "F.Cu" "F.Mask" "F.Paste")
			(net "PHY_DPB_TO_SCC_C_24_DP")
		)
		(pad "AH15" smd circle
			(at -1.500124 11.500104)
			(size 0.4572 0.4572)
			(layers "F.Cu" "F.Mask" "F.Paste")
			(net "PHY_DPB_TO_SCC_C_25_DP")
		)
		(pad "AH16" smd circle
			(at -0.500126 11.500104)
			(size 0.4572 0.4572)
			(layers "F.Cu" "F.Mask" "F.Paste")
			(net "PHY_DPB_TO_SCC_C_26_DP")
		)
		(pad "AH17" smd circle
			(at 0.500126 11.500104)
			(size 0.4572 0.4572)
			(layers "F.Cu" "F.Mask" "F.Paste")
			(net "PHY_DPB_TO_SCC_C_27_DP")
		)
		(pad "AH18" smd circle
			(at 1.500124 11.500104)
			(size 0.4572 0.4572)
			(layers "F.Cu" "F.Mask" "F.Paste")
			(net "PHY_DPB_TO_SCC_C_32_DP")
		)
		(pad "AH19" smd circle
			(at 2.500122 11.500104)
			(size 0.4572 0.4572)
			(layers "F.Cu" "F.Mask" "F.Paste")
			(net "PHY_DPB_TO_SCC_C_33_DP")
		)
		(pad "AH20" smd circle
			(at 3.50012 11.500104)
			(size 0.4572 0.4572)
			(layers "F.Cu" "F.Mask" "F.Paste")
			(net "PHY_DPB_TO_SCC_C_34_DP")
		)
		(pad "AH21" smd circle
			(at 4.500118 11.500104)
			(size 0.4572 0.4572)
			(layers "F.Cu" "F.Mask" "F.Paste")
			(net "PHY_DPB_TO_SCC_C_35_DP")
		)
		(pad "AH22" smd circle
			(at 5.500116 11.500104)
			(size 0.4572 0.4572)
			(layers "F.Cu" "F.Mask" "F.Paste")
			(net "PHY_DPB_TO_SCC_C_36_DP")
		)
		(pad "AH23" smd circle
			(at 6.500114 11.500104)
			(size 0.4572 0.4572)
			(layers "F.Cu" "F.Mask" "F.Paste")
			(net "PHY_DPB_TO_SCC_C_37_DP")
		)
		(pad "AH24" smd circle
			(at 7.500112 11.500104)
			(size 0.4572 0.4572)
			(layers "F.Cu" "F.Mask" "F.Paste")
			(net "PHY_DPB_TO_SCC_C_38_DP")
		)
		(pad "AH25" smd circle
			(at 8.50011 11.500104)
			(size 0.4572 0.4572)
			(layers "F.Cu" "F.Mask" "F.Paste")
			(net "PHY_DPB_TO_SCC_C_39_DP")
		)
		(pad "AH26" smd circle
			(at 9.500108 11.500104)
			(size 0.4572 0.4572)
			(layers "F.Cu" "F.Mask" "F.Paste")
			(net "GND")
		)
		(pad "AH27" smd circle
			(at 10.500106 11.500104)
			(size 0.4572 0.4572)
			(layers "F.Cu" "F.Mask" "F.Paste")
			(net "PHY_IOC_TO_SCC_C_42_DN")
		)
		(pad "AH28" smd circle
			(at 11.500104 11.500104)
			(size 0.4572 0.4572)
			(layers "F.Cu" "F.Mask" "F.Paste")
			(net "PHY_IOC_TO_SCC_C_42_DP")
		)
		(pad "AH29" smd circle
			(at 12.500102 11.500104)
			(size 0.4572 0.4572)
			(layers "F.Cu" "F.Mask" "F.Paste")
			(net "GB_VDDA")
		)
		(pad "AH30" smd circle
			(at 13.5001 11.500104)
			(size 0.4572 0.4572)
			(layers "F.Cu" "F.Mask" "F.Paste")
			(net "PHY_SCC_TO_IOC_42_DN")
		)
		(pad "AH31" smd circle
			(at 14.500098 11.500104)
			(size 0.4572 0.4572)
			(layers "F.Cu" "F.Mask" "F.Paste")
			(net "PHY_SCC_TO_IOC_42_DP")
		)
		(pad "AH32" smd circle
			(at 15.500096 11.500104)
			(size 0.4572 0.4572)
			(layers "F.Cu" "F.Mask" "F.Paste")
			(net "GND")
		)
		(pad "AJ1" smd circle
			(at -15.500096 12.500102)
			(size 0.4572 0.4572)
			(layers "F.Cu" "F.Mask" "F.Paste")
			(net "PHY_DPB_TO_SCC_C_12_DP")
		)
		(pad "AJ2" smd circle
			(at -14.500098 12.500102)
			(size 0.4572 0.4572)
			(layers "F.Cu" "F.Mask" "F.Paste")
			(net "GND")
		)
		(pad "AJ3" smd circle
			(at -13.5001 12.500102)
			(size 0.4572 0.4572)
			(layers "F.Cu" "F.Mask" "F.Paste")
			(net "GND")
		)
		(pad "AJ4" smd circle
			(at -12.500102 12.500102)
			(size 0.4572 0.4572)
			(layers "F.Cu" "F.Mask" "F.Paste")
			(net "GND")
		)
		(pad "AJ5" smd circle
			(at -11.500104 12.500102)
			(size 0.4572 0.4572)
			(layers "F.Cu" "F.Mask" "F.Paste")
			(net "GB_VDDA")
		)
		(pad "AJ6" smd circle
			(at -10.500106 12.500102)
			(size 0.4572 0.4572)
			(layers "F.Cu" "F.Mask" "F.Paste")
			(net "GND")
		)
		(pad "AJ7" smd circle
			(at -9.500108 12.500102)
			(size 0.4572 0.4572)
			(layers "F.Cu" "F.Mask" "F.Paste")
			(net "GB_VDDA")
		)
		(pad "AJ8" smd circle
			(at -8.50011 12.500102)
			(size 0.4572 0.4572)
			(layers "F.Cu" "F.Mask" "F.Paste")
			(net "GND")
		)
		(pad "AJ9" smd circle
			(at -7.500112 12.500102)
			(size 0.4572 0.4572)
			(layers "F.Cu" "F.Mask" "F.Paste")
			(net "GB_VDDA")
		)
		(pad "AJ10" smd circle
			(at -6.500114 12.500102)
			(size 0.4572 0.4572)
			(layers "F.Cu" "F.Mask" "F.Paste")
			(net "GND")
		)
		(pad "AJ11" smd circle
			(at -5.500116 12.500102)
			(size 0.4572 0.4572)
			(layers "F.Cu" "F.Mask" "F.Paste")
			(net "GB_VDDA")
		)
		(pad "AJ12" smd circle
			(at -4.500118 12.500102)
			(size 0.4572 0.4572)
			(layers "F.Cu" "F.Mask" "F.Paste")
			(net "GND")
		)
		(pad "AJ13" smd circle
			(at -3.50012 12.500102)
			(size 0.4572 0.4572)
			(layers "F.Cu" "F.Mask" "F.Paste")
			(net "GB_VDDA")
		)
		(pad "AJ14" smd circle
			(at -2.500122 12.500102)
			(size 0.4572 0.4572)
			(layers "F.Cu" "F.Mask" "F.Paste")
			(net "GND")
		)
		(pad "AJ15" smd circle
			(at -1.500124 12.500102)
			(size 0.4572 0.4572)
			(layers "F.Cu" "F.Mask" "F.Paste")
			(net "GB_VDDA")
		)
		(pad "AJ16" smd circle
			(at -0.500126 12.500102)
			(size 0.4572 0.4572)
			(layers "F.Cu" "F.Mask" "F.Paste")
			(net "GND")
		)
		(pad "AJ17" smd circle
			(at 0.500126 12.500102)
			(size 0.4572 0.4572)
			(layers "F.Cu" "F.Mask" "F.Paste")
			(net "GB_VDDA")
		)
		(pad "AJ18" smd circle
			(at 1.500124 12.500102)
			(size 0.4572 0.4572)
			(layers "F.Cu" "F.Mask" "F.Paste")
			(net "GND")
		)
		(pad "AJ19" smd circle
			(at 2.500122 12.500102)
			(size 0.4572 0.4572)
			(layers "F.Cu" "F.Mask" "F.Paste")
			(net "GB_VDDA")
		)
		(pad "AJ20" smd circle
			(at 3.50012 12.500102)
			(size 0.4572 0.4572)
			(layers "F.Cu" "F.Mask" "F.Paste")
			(net "GND")
		)
		(pad "AJ21" smd circle
			(at 4.500118 12.500102)
			(size 0.4572 0.4572)
			(layers "F.Cu" "F.Mask" "F.Paste")
			(net "GB_VDDA")
		)
		(pad "AJ22" smd circle
			(at 5.500116 12.500102)
			(size 0.4572 0.4572)
			(layers "F.Cu" "F.Mask" "F.Paste")
			(net "GND")
		)
		(pad "AJ23" smd circle
			(at 6.500114 12.500102)
			(size 0.4572 0.4572)
			(layers "F.Cu" "F.Mask" "F.Paste")
			(net "GB_VDDA")
		)
		(pad "AJ24" smd circle
			(at 7.500112 12.500102)
			(size 0.4572 0.4572)
			(layers "F.Cu" "F.Mask" "F.Paste")
			(net "GND")
		)
		(pad "AJ25" smd circle
			(at 8.50011 12.500102)
			(size 0.4572 0.4572)
			(layers "F.Cu" "F.Mask" "F.Paste")
			(net "GB_VDDA")
		)
		(pad "AJ26" smd circle
			(at 9.500108 12.500102)
			(size 0.4572 0.4572)
			(layers "F.Cu" "F.Mask" "F.Paste")
			(net "GND")
		)
		(pad "AJ27" smd circle
			(at 10.500106 12.500102)
			(size 0.4572 0.4572)
			(layers "F.Cu" "F.Mask" "F.Paste")
			(net "PHY_IOC_TO_SCC_C_41_DN")
		)
		(pad "AJ28" smd circle
			(at 11.500104 12.500102)
			(size 0.4572 0.4572)
			(layers "F.Cu" "F.Mask" "F.Paste")
			(net "PHY_IOC_TO_SCC_C_41_DP")
		)
		(pad "AJ29" smd circle
			(at 12.500102 12.500102)
			(size 0.4572 0.4572)
			(layers "F.Cu" "F.Mask" "F.Paste")
			(net "GND")
		)
		(pad "AJ30" smd circle
			(at 13.5001 12.500102)
			(size 0.4572 0.4572)
			(layers "F.Cu" "F.Mask" "F.Paste")
			(net "GB_VDDA")
		)
		(pad "AJ31" smd circle
			(at 14.500098 12.500102)
			(size 0.4572 0.4572)
			(layers "F.Cu" "F.Mask" "F.Paste")
			(net "PHY_SCC_TO_IOC_41_DN")
		)
		(pad "AJ32" smd circle
			(at 15.500096 12.500102)
			(size 0.4572 0.4572)
			(layers "F.Cu" "F.Mask" "F.Paste")
			(net "PHY_SCC_TO_IOC_41_DP")
		)
		(pad "AK1" smd circle
			(at -15.500096 13.5001)
			(size 0.508 0.508)
			(layers "F.Cu" "F.Mask" "F.Paste")
			(net "GND")
		)
		(pad "AK2" smd circle
			(at -14.500098 13.5001)
			(size 0.508 0.508)
			(layers "F.Cu" "F.Mask" "F.Paste")
			(net "GB_VDDA")
		)
		(pad "AK3" smd circle
			(at -13.5001 13.5001)
			(size 0.508 0.508)
			(layers "F.Cu" "F.Mask" "F.Paste")
			(net "PHY_SCC_TO_DPB_13_DN")
		)
		(pad "AK4" smd circle
			(at -12.500102 13.5001)
			(size 0.4572 0.4572)
			(layers "F.Cu" "F.Mask" "F.Paste")
			(net "GB_VDDA")
		)
		(pad "AK5" smd circle
			(at -11.500104 13.5001)
			(size 0.4572 0.4572)
			(layers "F.Cu" "F.Mask" "F.Paste")
			(net "PHY_SCC_TO_DPB_15_DN")
		)
		(pad "AK6" smd circle
			(at -10.500106 13.5001)
			(size 0.4572 0.4572)
			(layers "F.Cu" "F.Mask" "F.Paste")
			(net "GB_VDDA")
		)
		(pad "AK7" smd circle
			(at -9.500108 13.5001)
			(size 0.4572 0.4572)
			(layers "F.Cu" "F.Mask" "F.Paste")
			(net "PHY_SCC_TO_DPB_17_DN")
		)
		(pad "AK8" smd circle
			(at -8.50011 13.5001)
			(size 0.4572 0.4572)
			(layers "F.Cu" "F.Mask" "F.Paste")
			(net "GB_VDDA")
		)
		(pad "AK9" smd circle
			(at -7.500112 13.5001)
			(size 0.4572 0.4572)
			(layers "F.Cu" "F.Mask" "F.Paste")
			(net "PHY_SCC_TO_DPB_19_DN")
		)
		(pad "AK10" smd circle
			(at -6.500114 13.5001)
			(size 0.4572 0.4572)
			(layers "F.Cu" "F.Mask" "F.Paste")
			(net "GB_VDDA")
		)
		(pad "AK11" smd circle
			(at -5.500116 13.5001)
			(size 0.4572 0.4572)
			(layers "F.Cu" "F.Mask" "F.Paste")
			(net "PHY_SCC_TO_DPB_21_DN")
		)
		(pad "AK12" smd circle
			(at -4.500118 13.5001)
			(size 0.4572 0.4572)
			(layers "F.Cu" "F.Mask" "F.Paste")
			(net "GB_VDDA")
		)
		(pad "AK13" smd circle
			(at -3.50012 13.5001)
			(size 0.4572 0.4572)
			(layers "F.Cu" "F.Mask" "F.Paste")
			(net "PHY_SCC_TO_DPB_23_DN")
		)
		(pad "AK14" smd circle
			(at -2.500122 13.5001)
			(size 0.4572 0.4572)
			(layers "F.Cu" "F.Mask" "F.Paste")
			(net "GB_VDDA")
		)
		(pad "AK15" smd circle
			(at -1.500124 13.5001)
			(size 0.4572 0.4572)
			(layers "F.Cu" "F.Mask" "F.Paste")
			(net "PHY_SCC_TO_DPB_25_DN")
		)
		(pad "AK16" smd circle
			(at -0.500126 13.5001)
			(size 0.4572 0.4572)
			(layers "F.Cu" "F.Mask" "F.Paste")
			(net "GB_VDDA")
		)
		(pad "AK17" smd circle
			(at 0.500126 13.5001)
			(size 0.4572 0.4572)
			(layers "F.Cu" "F.Mask" "F.Paste")
			(net "PHY_SCC_TO_DPB_27_DN")
		)
		(pad "AK18" smd circle
			(at 1.500124 13.5001)
			(size 0.4572 0.4572)
			(layers "F.Cu" "F.Mask" "F.Paste")
			(net "GB_VDDA")
		)
		(pad "AK19" smd circle
			(at 2.500122 13.5001)
			(size 0.4572 0.4572)
			(layers "F.Cu" "F.Mask" "F.Paste")
			(net "PHY_SCC_TO_DPB_33_DN")
		)
		(pad "AK20" smd circle
			(at 3.50012 13.5001)
			(size 0.4572 0.4572)
			(layers "F.Cu" "F.Mask" "F.Paste")
			(net "GB_VDDA")
		)
		(pad "AK21" smd circle
			(at 4.500118 13.5001)
			(size 0.4572 0.4572)
			(layers "F.Cu" "F.Mask" "F.Paste")
			(net "PHY_SCC_TO_DPB_35_DN")
		)
		(pad "AK22" smd circle
			(at 5.500116 13.5001)
			(size 0.4572 0.4572)
			(layers "F.Cu" "F.Mask" "F.Paste")
			(net "GB_VDDA")
		)
		(pad "AK23" smd circle
			(at 6.500114 13.5001)
			(size 0.4572 0.4572)
			(layers "F.Cu" "F.Mask" "F.Paste")
			(net "PHY_SCC_TO_DPB_37_DN")
		)
		(pad "AK24" smd circle
			(at 7.500112 13.5001)
			(size 0.4572 0.4572)
			(layers "F.Cu" "F.Mask" "F.Paste")
			(net "GB_VDDA")
		)
		(pad "AK25" smd circle
			(at 8.50011 13.5001)
			(size 0.4572 0.4572)
			(layers "F.Cu" "F.Mask" "F.Paste")
			(net "PHY_SCC_TO_DPB_39_DN")
		)
		(pad "AK26" smd circle
			(at 9.500108 13.5001)
			(size 0.4572 0.4572)
			(layers "F.Cu" "F.Mask" "F.Paste")
			(net "GND")
		)
		(pad "AK27" smd circle
			(at 10.500106 13.5001)
			(size 0.4572 0.4572)
			(layers "F.Cu" "F.Mask" "F.Paste")
			(net "GB_VDDA")
		)
		(pad "AK28" smd circle
			(at 11.500104 13.5001)
			(size 0.4572 0.4572)
			(layers "F.Cu" "F.Mask" "F.Paste")
			(net "PHY_IOC_TO_SCC_C_40_DN")
		)
		(pad "AK29" smd circle
			(at 12.500102 13.5001)
			(size 0.4572 0.4572)
			(layers "F.Cu" "F.Mask" "F.Paste")
			(net "PHY_IOC_TO_SCC_C_40_DP")
		)
		(pad "AK30" smd circle
			(at 13.5001 13.5001)
			(size 0.508 0.508)
			(layers "F.Cu" "F.Mask" "F.Paste")
			(net "GND")
		)
		(pad "AK31" smd circle
			(at 14.500098 13.5001)
			(size 0.508 0.508)
			(layers "F.Cu" "F.Mask" "F.Paste")
			(net "GND")
		)
		(pad "AK32" smd circle
			(at 15.500096 13.5001)
			(size 0.508 0.508)
			(layers "F.Cu" "F.Mask" "F.Paste")
			(net "GND")
		)
		(pad "AL1" smd circle
			(at -15.500096 14.500098)
			(size 0.508 0.508)
			(layers "F.Cu" "F.Mask" "F.Paste")
			(net "GND")
		)
		(pad "AL2" smd circle
			(at -14.500098 14.500098)
			(size 0.508 0.508)
			(layers "F.Cu" "F.Mask" "F.Paste")
			(net "PHY_SCC_TO_DPB_12_DN")
		)
		(pad "AL3" smd circle
			(at -13.5001 14.500098)
			(size 0.508 0.508)
			(layers "F.Cu" "F.Mask" "F.Paste")
			(net "PHY_SCC_TO_DPB_13_DP")
		)
		(pad "AL4" smd circle
			(at -12.500102 14.500098)
			(size 0.4572 0.4572)
			(layers "F.Cu" "F.Mask" "F.Paste")
			(net "PHY_SCC_TO_DPB_14_DN")
		)
		(pad "AL5" smd circle
			(at -11.500104 14.500098)
			(size 0.4572 0.4572)
			(layers "F.Cu" "F.Mask" "F.Paste")
			(net "PHY_SCC_TO_DPB_15_DP")
		)
		(pad "AL6" smd circle
			(at -10.500106 14.500098)
			(size 0.4572 0.4572)
			(layers "F.Cu" "F.Mask" "F.Paste")
			(net "PHY_SCC_TO_DPB_16_DN")
		)
		(pad "AL7" smd circle
			(at -9.500108 14.500098)
			(size 0.4572 0.4572)
			(layers "F.Cu" "F.Mask" "F.Paste")
			(net "PHY_SCC_TO_DPB_17_DP")
		)
		(pad "AL8" smd circle
			(at -8.50011 14.500098)
			(size 0.4572 0.4572)
			(layers "F.Cu" "F.Mask" "F.Paste")
			(net "PHY_SCC_TO_DPB_18_DN")
		)
		(pad "AL9" smd circle
			(at -7.500112 14.500098)
			(size 0.4572 0.4572)
			(layers "F.Cu" "F.Mask" "F.Paste")
			(net "PHY_SCC_TO_DPB_19_DP")
		)
		(pad "AL10" smd circle
			(at -6.500114 14.500098)
			(size 0.4572 0.4572)
			(layers "F.Cu" "F.Mask" "F.Paste")
			(net "PHY_SCC_TO_DPB_20_DN")
		)
		(pad "AL11" smd circle
			(at -5.500116 14.500098)
			(size 0.4572 0.4572)
			(layers "F.Cu" "F.Mask" "F.Paste")
			(net "PHY_SCC_TO_DPB_21_DP")
		)
		(pad "AL12" smd circle
			(at -4.500118 14.500098)
			(size 0.4572 0.4572)
			(layers "F.Cu" "F.Mask" "F.Paste")
			(net "PHY_SCC_TO_DPB_22_DN")
		)
		(pad "AL13" smd circle
			(at -3.50012 14.500098)
			(size 0.4572 0.4572)
			(layers "F.Cu" "F.Mask" "F.Paste")
			(net "PHY_SCC_TO_DPB_23_DP")
		)
		(pad "AL14" smd circle
			(at -2.500122 14.500098)
			(size 0.4572 0.4572)
			(layers "F.Cu" "F.Mask" "F.Paste")
			(net "PHY_SCC_TO_DPB_24_DN")
		)
		(pad "AL15" smd circle
			(at -1.500124 14.500098)
			(size 0.4572 0.4572)
			(layers "F.Cu" "F.Mask" "F.Paste")
			(net "PHY_SCC_TO_DPB_25_DP")
		)
		(pad "AL16" smd circle
			(at -0.500126 14.500098)
			(size 0.4572 0.4572)
			(layers "F.Cu" "F.Mask" "F.Paste")
			(net "PHY_SCC_TO_DPB_26_DN")
		)
		(pad "AL17" smd circle
			(at 0.500126 14.500098)
			(size 0.4572 0.4572)
			(layers "F.Cu" "F.Mask" "F.Paste")
			(net "PHY_SCC_TO_DPB_27_DP")
		)
		(pad "AL18" smd circle
			(at 1.500124 14.500098)
			(size 0.4572 0.4572)
			(layers "F.Cu" "F.Mask" "F.Paste")
			(net "PHY_SCC_TO_DPB_32_DN")
		)
		(pad "AL19" smd circle
			(at 2.500122 14.500098)
			(size 0.4572 0.4572)
			(layers "F.Cu" "F.Mask" "F.Paste")
			(net "PHY_SCC_TO_DPB_33_DP")
		)
		(pad "AL20" smd circle
			(at 3.50012 14.500098)
			(size 0.4572 0.4572)
			(layers "F.Cu" "F.Mask" "F.Paste")
			(net "PHY_SCC_TO_DPB_34_DN")
		)
		(pad "AL21" smd circle
			(at 4.500118 14.500098)
			(size 0.4572 0.4572)
			(layers "F.Cu" "F.Mask" "F.Paste")
			(net "PHY_SCC_TO_DPB_35_DP")
		)
		(pad "AL22" smd circle
			(at 5.500116 14.500098)
			(size 0.4572 0.4572)
			(layers "F.Cu" "F.Mask" "F.Paste")
			(net "PHY_SCC_TO_DPB_36_DN")
		)
		(pad "AL23" smd circle
			(at 6.500114 14.500098)
			(size 0.4572 0.4572)
			(layers "F.Cu" "F.Mask" "F.Paste")
			(net "PHY_SCC_TO_DPB_37_DP")
		)
		(pad "AL24" smd circle
			(at 7.500112 14.500098)
			(size 0.4572 0.4572)
			(layers "F.Cu" "F.Mask" "F.Paste")
			(net "PHY_SCC_TO_DPB_38_DN")
		)
		(pad "AL25" smd circle
			(at 8.50011 14.500098)
			(size 0.4572 0.4572)
			(layers "F.Cu" "F.Mask" "F.Paste")
			(net "PHY_SCC_TO_DPB_39_DP")
		)
		(pad "AL26" smd circle
			(at 9.500108 14.500098)
			(size 0.4572 0.4572)
			(layers "F.Cu" "F.Mask" "F.Paste")
			(net "GND")
		)
		(pad "AL27" smd circle
			(at 10.500106 14.500098)
			(size 0.4572 0.4572)
			(layers "F.Cu" "F.Mask" "F.Paste")
			(net "GND")
		)
		(pad "AL28" smd circle
			(at 11.500104 14.500098)
			(size 0.4572 0.4572)
			(layers "F.Cu" "F.Mask" "F.Paste")
			(net "GND")
		)
		(pad "AL29" smd circle
			(at 12.500102 14.500098)
			(size 0.4572 0.4572)
			(layers "F.Cu" "F.Mask" "F.Paste")
			(net "GND")
		)
		(pad "AL30" smd circle
			(at 13.5001 14.500098)
			(size 0.508 0.508)
			(layers "F.Cu" "F.Mask" "F.Paste")
			(net "GND")
		)
		(pad "AL31" smd circle
			(at 14.500098 14.500098)
			(size 0.508 0.508)
			(layers "F.Cu" "F.Mask" "F.Paste")
			(net "PHY_SCC_TO_IOC_40_DN")
		)
		(pad "AL32" smd circle
			(at 15.500096 14.500098)
			(size 0.508 0.508)
			(layers "F.Cu" "F.Mask" "F.Paste")
			(net "PHY_SCC_TO_IOC_40_DP")
		)
		(pad "AM2" smd circle
			(at -14.500098 15.500096)
			(size 0.508 0.508)
			(layers "F.Cu" "F.Mask" "F.Paste")
			(net "PHY_SCC_TO_DPB_12_DP")
		)
		(pad "AM3" smd circle
			(at -13.5001 15.500096)
			(size 0.508 0.508)
			(layers "F.Cu" "F.Mask" "F.Paste")
			(net "GND")
		)
		(pad "AM4" smd circle
			(at -12.500102 15.500096)
			(size 0.4572 0.4572)
			(layers "F.Cu" "F.Mask" "F.Paste")
			(net "PHY_SCC_TO_DPB_14_DP")
		)
		(pad "AM5" smd circle
			(at -11.500104 15.500096)
			(size 0.4572 0.4572)
			(layers "F.Cu" "F.Mask" "F.Paste")
			(net "GND")
		)
		(pad "AM6" smd circle
			(at -10.500106 15.500096)
			(size 0.4572 0.4572)
			(layers "F.Cu" "F.Mask" "F.Paste")
			(net "PHY_SCC_TO_DPB_16_DP")
		)
		(pad "AM7" smd circle
			(at -9.500108 15.500096)
			(size 0.4572 0.4572)
			(layers "F.Cu" "F.Mask" "F.Paste")
			(net "GND")
		)
		(pad "AM8" smd circle
			(at -8.50011 15.500096)
			(size 0.4572 0.4572)
			(layers "F.Cu" "F.Mask" "F.Paste")
			(net "PHY_SCC_TO_DPB_18_DP")
		)
		(pad "AM9" smd circle
			(at -7.500112 15.500096)
			(size 0.4572 0.4572)
			(layers "F.Cu" "F.Mask" "F.Paste")
			(net "GND")
		)
		(pad "AM10" smd circle
			(at -6.500114 15.500096)
			(size 0.4572 0.4572)
			(layers "F.Cu" "F.Mask" "F.Paste")
			(net "PHY_SCC_TO_DPB_20_DP")
		)
		(pad "AM11" smd circle
			(at -5.500116 15.500096)
			(size 0.4572 0.4572)
			(layers "F.Cu" "F.Mask" "F.Paste")
			(net "GND")
		)
		(pad "AM12" smd circle
			(at -4.500118 15.500096)
			(size 0.4572 0.4572)
			(layers "F.Cu" "F.Mask" "F.Paste")
			(net "PHY_SCC_TO_DPB_22_DP")
		)
		(pad "AM13" smd circle
			(at -3.50012 15.500096)
			(size 0.4572 0.4572)
			(layers "F.Cu" "F.Mask" "F.Paste")
			(net "GND")
		)
		(pad "AM14" smd circle
			(at -2.500122 15.500096)
			(size 0.4572 0.4572)
			(layers "F.Cu" "F.Mask" "F.Paste")
			(net "PHY_SCC_TO_DPB_24_DP")
		)
		(pad "AM15" smd circle
			(at -1.500124 15.500096)
			(size 0.4572 0.4572)
			(layers "F.Cu" "F.Mask" "F.Paste")
			(net "GND")
		)
		(pad "AM16" smd circle
			(at -0.500126 15.500096)
			(size 0.4572 0.4572)
			(layers "F.Cu" "F.Mask" "F.Paste")
			(net "PHY_SCC_TO_DPB_26_DP")
		)
		(pad "AM17" smd circle
			(at 0.500126 15.500096)
			(size 0.4572 0.4572)
			(layers "F.Cu" "F.Mask" "F.Paste")
			(net "GND")
		)
		(pad "AM18" smd circle
			(at 1.500124 15.500096)
			(size 0.4572 0.4572)
			(layers "F.Cu" "F.Mask" "F.Paste")
			(net "PHY_SCC_TO_DPB_32_DP")
		)
		(pad "AM19" smd circle
			(at 2.500122 15.500096)
			(size 0.4572 0.4572)
			(layers "F.Cu" "F.Mask" "F.Paste")
			(net "GND")
		)
		(pad "AM20" smd circle
			(at 3.50012 15.500096)
			(size 0.4572 0.4572)
			(layers "F.Cu" "F.Mask" "F.Paste")
			(net "PHY_SCC_TO_DPB_34_DP")
		)
		(pad "AM21" smd circle
			(at 4.500118 15.500096)
			(size 0.4572 0.4572)
			(layers "F.Cu" "F.Mask" "F.Paste")
			(net "GND")
		)
		(pad "AM22" smd circle
			(at 5.500116 15.500096)
			(size 0.4572 0.4572)
			(layers "F.Cu" "F.Mask" "F.Paste")
			(net "PHY_SCC_TO_DPB_36_DP")
		)
		(pad "AM23" smd circle
			(at 6.500114 15.500096)
			(size 0.4572 0.4572)
			(layers "F.Cu" "F.Mask" "F.Paste")
			(net "GND")
		)
		(pad "AM24" smd circle
			(at 7.500112 15.500096)
			(size 0.4572 0.4572)
			(layers "F.Cu" "F.Mask" "F.Paste")
			(net "PHY_SCC_TO_DPB_38_DP")
		)
		(pad "AM25" smd circle
			(at 8.50011 15.500096)
			(size 0.4572 0.4572)
			(layers "F.Cu" "F.Mask" "F.Paste")
			(net "GND")
		)
		(pad "AM26" smd circle
			(at 9.500108 15.500096)
			(size 0.4572 0.4572)
			(layers "F.Cu" "F.Mask" "F.Paste")
			(net "GND")
		)
		(pad "AM27" smd circle
			(at 10.500106 15.500096)
			(size 0.4572 0.4572)
			(layers "F.Cu" "F.Mask" "F.Paste")
			(net "GND")
		)
		(pad "AM28" smd circle
			(at 11.500104 15.500096)
			(size 0.4572 0.4572)
			(layers "F.Cu" "F.Mask" "F.Paste")
			(net "RTRIM_A")
		)
		(pad "AM29" smd circle
			(at 12.500102 15.500096)
			(size 0.4572 0.4572)
			(layers "F.Cu" "F.Mask" "F.Paste")
			(net "RTRIM_AN")
		)
		(pad "AM30" smd circle
			(at 13.5001 15.500096)
			(size 0.508 0.508)
			(layers "F.Cu" "F.Mask" "F.Paste")
			(net "GND")
		)
		(pad "AM31" smd circle
			(at 14.500098 15.500096)
			(size 0.508 0.508)
			(layers "F.Cu" "F.Mask" "F.Paste")
			(net "GND")
		)
		(pad "B1" smd circle
			(at -15.500096 -14.500098)
			(size 0.508 0.508)
			(layers "F.Cu" "F.Mask" "F.Paste")
			(net "Net_1258")
		)
		(pad "B2" smd circle
			(at -14.500098 -14.500098)
			(size 0.508 0.508)
			(layers "F.Cu" "F.Mask" "F.Paste")
			(net "VDDIO_DDR")
		)
		(pad "B3" smd circle
			(at -13.5001 -14.500098)
			(size 0.508 0.508)
			(layers "F.Cu" "F.Mask" "F.Paste")
			(net "Net_1257")
		)
		(pad "B4" smd circle
			(at -12.500102 -14.500098)
			(size 0.4572 0.4572)
			(layers "F.Cu" "F.Mask" "F.Paste")
			(net "VDDIO_DDR")
		)
		(pad "B5" smd circle
			(at -11.500104 -14.500098)
			(size 0.4572 0.4572)
			(layers "F.Cu" "F.Mask" "F.Paste")
			(net "Net_1256")
		)
		(pad "B6" smd circle
			(at -10.500106 -14.500098)
			(size 0.4572 0.4572)
			(layers "F.Cu" "F.Mask" "F.Paste")
			(net "GND")
		)
		(pad "B7" smd circle
			(at -9.500108 -14.500098)
			(size 0.4572 0.4572)
			(layers "F.Cu" "F.Mask" "F.Paste")
			(net "DRIVE_5_ACT")
		)
		(pad "B8" smd circle
			(at -8.50011 -14.500098)
			(size 0.4572 0.4572)
			(layers "F.Cu" "F.Mask" "F.Paste")
			(net "DRIVE_1_ACT")
		)
		(pad "B9" smd circle
			(at -7.500112 -14.500098)
			(size 0.4572 0.4572)
			(layers "F.Cu" "F.Mask" "F.Paste")
			(net "SXP_ACTIVE_2")
		)
		(pad "B10" smd circle
			(at -6.500114 -14.500098)
			(size 0.4572 0.4572)
			(layers "F.Cu" "F.Mask" "F.Paste")
			(net "JTAG_EXP_TMS")
		)
		(pad "B11" smd circle
			(at -5.500116 -14.500098)
			(size 0.4572 0.4572)
			(layers "F.Cu" "F.Mask" "F.Paste")
			(net "SOFT_RESET_N")
		)
		(pad "B12" smd circle
			(at -4.500118 -14.500098)
			(size 0.4572 0.4572)
			(layers "F.Cu" "F.Mask" "F.Paste")
			(net "EXP_XM_OE_N")
		)
		(pad "B13" smd circle
			(at -3.50012 -14.500098)
			(size 0.4572 0.4572)
			(layers "F.Cu" "F.Mask" "F.Paste")
			(net "XM_DATA5")
		)
		(pad "B14" smd circle
			(at -2.500122 -14.500098)
			(size 0.4572 0.4572)
			(layers "F.Cu" "F.Mask" "F.Paste")
			(net "XM_DATA2")
		)
		(pad "B15" smd circle
			(at -1.500124 -14.500098)
			(size 0.4572 0.4572)
			(layers "F.Cu" "F.Mask" "F.Paste")
			(net "XM_DATA10")
		)
		(pad "B16" smd circle
			(at -0.500126 -14.500098)
			(size 0.4572 0.4572)
			(layers "F.Cu" "F.Mask" "F.Paste")
			(net "EXP_XM_ADDR_4")
		)
		(pad "B17" smd circle
			(at 0.500126 -14.500098)
			(size 0.4572 0.4572)
			(layers "F.Cu" "F.Mask" "F.Paste")
			(net "EXP_XM_ADDR_3")
		)
		(pad "B18" smd circle
			(at 1.500124 -14.500098)
			(size 0.4572 0.4572)
			(layers "F.Cu" "F.Mask" "F.Paste")
			(net "EXP_XM_ADDR_16")
		)
		(pad "B19" smd circle
			(at 2.500122 -14.500098)
			(size 0.4572 0.4572)
			(layers "F.Cu" "F.Mask" "F.Paste")
			(net "EXP_XM_ADDR_0")
		)
		(pad "B20" smd circle
			(at 3.50012 -14.500098)
			(size 0.4572 0.4572)
			(layers "F.Cu" "F.Mask" "F.Paste")
			(net "EXP_GPIO13")
		)
		(pad "B21" smd circle
			(at 4.500118 -14.500098)
			(size 0.4572 0.4572)
			(layers "F.Cu" "F.Mask" "F.Paste")
			(net "SCC_TYPE_2_LS")
		)
		(pad "B22" smd circle
			(at 5.500116 -14.500098)
			(size 0.4572 0.4572)
			(layers "F.Cu" "F.Mask" "F.Paste")
			(net "USB_NXT")
		)
		(pad "B23" smd circle
			(at 6.500114 -14.500098)
			(size 0.4572 0.4572)
			(layers "F.Cu" "F.Mask" "F.Paste")
			(net "Net_1212")
		)
		(pad "B24" smd circle
			(at 7.500112 -14.500098)
			(size 0.4572 0.4572)
			(layers "F.Cu" "F.Mask" "F.Paste")
			(net "PHY_CLK")
		)
		(pad "B25" smd circle
			(at 8.50011 -14.500098)
			(size 0.4572 0.4572)
			(layers "F.Cu" "F.Mask" "F.Paste")
			(net "Net_1211")
		)
		(pad "B26" smd circle
			(at 9.500108 -14.500098)
			(size 0.4572 0.4572)
			(layers "F.Cu" "F.Mask" "F.Paste")
			(net "Net_1210")
		)
		(pad "B27" smd circle
			(at 10.500106 -14.500098)
			(size 0.4572 0.4572)
			(layers "F.Cu" "F.Mask" "F.Paste")
			(net "SDB_R_TX")
		)
		(pad "B28" smd circle
			(at 11.500104 -14.500098)
			(size 0.4572 0.4572)
			(layers "F.Cu" "F.Mask" "F.Paste")
			(net "SMART_RX")
		)
		(pad "B29" smd circle
			(at 12.500102 -14.500098)
			(size 0.4572 0.4572)
			(layers "F.Cu" "F.Mask" "F.Paste")
			(net "EXP_SIO_D_IN")
		)
		(pad "B30" smd circle
			(at 13.5001 -14.500098)
			(size 0.508 0.508)
			(layers "F.Cu" "F.Mask" "F.Paste")
			(net "EXP_I2C_SDA10")
		)
		(pad "B31" smd circle
			(at 14.500098 -14.500098)
			(size 0.508 0.508)
			(layers "F.Cu" "F.Mask" "F.Paste")
			(net "I2C_EXP_IOC_SCL8")
		)
		(pad "B32" smd circle
			(at 15.500096 -14.500098)
			(size 0.508 0.508)
			(layers "F.Cu" "F.Mask" "F.Paste")
			(net "I2C_DRIVE_FLT_LED_SDA6_LS")
		)
		(pad "C1" smd circle
			(at -15.500096 -13.5001)
			(size 0.508 0.508)
			(layers "F.Cu" "F.Mask" "F.Paste")
			(net "Net_1255")
		)
		(pad "C2" smd circle
			(at -14.500098 -13.5001)
			(size 0.508 0.508)
			(layers "F.Cu" "F.Mask" "F.Paste")
			(net "Net_1254")
		)
		(pad "C3" smd circle
			(at -13.5001 -13.5001)
			(size 0.508 0.508)
			(layers "F.Cu" "F.Mask" "F.Paste")
			(net "GND")
		)
		(pad "C4" smd circle
			(at -12.500102 -13.5001)
			(size 0.4572 0.4572)
			(layers "F.Cu" "F.Mask" "F.Paste")
			(net "Net_1253")
		)
		(pad "C5" smd circle
			(at -11.500104 -13.5001)
			(size 0.4572 0.4572)
			(layers "F.Cu" "F.Mask" "F.Paste")
			(net "Net_1252")
		)
		(pad "C6" smd circle
			(at -10.500106 -13.5001)
			(size 0.4572 0.4572)
			(layers "F.Cu" "F.Mask" "F.Paste")
			(net "GND")
		)
		(pad "C7" smd circle
			(at -9.500108 -13.5001)
			(size 0.4572 0.4572)
			(layers "F.Cu" "F.Mask" "F.Paste")
			(net "DRIVE_6_ACT")
		)
		(pad "C8" smd circle
			(at -8.50011 -13.5001)
			(size 0.4572 0.4572)
			(layers "F.Cu" "F.Mask" "F.Paste")
			(net "GND")
		)
		(pad "C9" smd circle
			(at -7.500112 -13.5001)
			(size 0.4572 0.4572)
			(layers "F.Cu" "F.Mask" "F.Paste")
			(net "DRIVE_2_ACT")
		)
		(pad "C10" smd circle
			(at -6.500114 -13.5001)
			(size 0.4572 0.4572)
			(layers "F.Cu" "F.Mask" "F.Paste")
			(net "EXP_BLINK_IN")
		)
		(pad "C11" smd circle
			(at -5.500116 -13.5001)
			(size 0.4572 0.4572)
			(layers "F.Cu" "F.Mask" "F.Paste")
			(net "TMUX_EN")
		)
		(pad "C12" smd circle
			(at -4.500118 -13.5001)
			(size 0.4572 0.4572)
			(layers "F.Cu" "F.Mask" "F.Paste")
			(net "XM_WBE_1#_TP")
		)
		(pad "C13" smd circle
			(at -3.50012 -13.5001)
			(size 0.4572 0.4572)
			(layers "F.Cu" "F.Mask" "F.Paste")
			(net "XM_DATA7")
		)
		(pad "C14" smd circle
			(at -2.500122 -13.5001)
			(size 0.4572 0.4572)
			(layers "F.Cu" "F.Mask" "F.Paste")
			(net "GND")
		)
		(pad "C15" smd circle
			(at -1.500124 -13.5001)
			(size 0.4572 0.4572)
			(layers "F.Cu" "F.Mask" "F.Paste")
			(net "EXP_XM_BUSY_N")
		)
		(pad "C16" smd circle
			(at -0.500126 -13.5001)
			(size 0.4572 0.4572)
			(layers "F.Cu" "F.Mask" "F.Paste")
			(net "GND")
		)
		(pad "C17" smd circle
			(at 0.500126 -13.5001)
			(size 0.4572 0.4572)
			(layers "F.Cu" "F.Mask" "F.Paste")
			(net "EXP_XM_ADDR_23")
		)
		(pad "C18" smd circle
			(at 1.500124 -13.5001)
			(size 0.4572 0.4572)
			(layers "F.Cu" "F.Mask" "F.Paste")
			(net "GND")
		)
		(pad "C19" smd circle
			(at 2.500122 -13.5001)
			(size 0.4572 0.4572)
			(layers "F.Cu" "F.Mask" "F.Paste")
			(net "PWM_OUT_ZONE_D_LS")
		)
		(pad "C20" smd circle
			(at 3.50012 -13.5001)
			(size 0.4572 0.4572)
			(layers "F.Cu" "F.Mask" "F.Paste")
			(net "GND")
		)
		(pad "C21" smd circle
			(at 4.500118 -13.5001)
			(size 0.4572 0.4572)
			(layers "F.Cu" "F.Mask" "F.Paste")
			(net "SCC_TYPE_3_LS")
		)
		(pad "C22" smd circle
			(at 5.500116 -13.5001)
			(size 0.4572 0.4572)
			(layers "F.Cu" "F.Mask" "F.Paste")
			(net "GND")
		)
		(pad "C23" smd circle
			(at 6.500114 -13.5001)
			(size 0.4572 0.4572)
			(layers "F.Cu" "F.Mask" "F.Paste")
			(net "Net_1209")
		)
		(pad "C24" smd circle
			(at 7.500112 -13.5001)
			(size 0.4572 0.4572)
			(layers "F.Cu" "F.Mask" "F.Paste")
			(net "GND")
		)
		(pad "C25" smd circle
			(at 8.50011 -13.5001)
			(size 0.4572 0.4572)
			(layers "F.Cu" "F.Mask" "F.Paste")
			(net "EXP_RGMII_RXC")
		)
		(pad "C26" smd circle
			(at 9.500108 -13.5001)
			(size 0.4572 0.4572)
			(layers "F.Cu" "F.Mask" "F.Paste")
			(net "GND")
		)
		(pad "C27" smd circle
			(at 10.500106 -13.5001)
			(size 0.4572 0.4572)
			(layers "F.Cu" "F.Mask" "F.Paste")
			(net "ICE_TDO")
		)
		(pad "C28" smd circle
			(at 11.500104 -13.5001)
			(size 0.4572 0.4572)
			(layers "F.Cu" "F.Mask" "F.Paste")
			(net "GND")
		)
		(pad "C29" smd circle
			(at 12.500102 -13.5001)
			(size 0.4572 0.4572)
			(layers "F.Cu" "F.Mask" "F.Paste")
			(net "EXP_I2C_SDA11")
		)
		(pad "C30" smd circle
			(at 13.5001 -13.5001)
			(size 0.508 0.508)
			(layers "F.Cu" "F.Mask" "F.Paste")
			(net "GND")
		)
		(pad "C31" smd circle
			(at 14.500098 -13.5001)
			(size 0.508 0.508)
			(layers "F.Cu" "F.Mask" "F.Paste")
			(net "I2C_DRIVE_FLT_LED_SCL6_LS")
		)
		(pad "C32" smd circle
			(at 15.500096 -13.5001)
			(size 0.508 0.508)
			(layers "F.Cu" "F.Mask" "F.Paste")
			(net "GND")
		)
		(pad "D1" smd circle
			(at -15.500096 -12.500102)
			(size 0.4572 0.4572)
			(layers "F.Cu" "F.Mask" "F.Paste")
			(net "Net_1251")
		)
		(pad "D2" smd circle
			(at -14.500098 -12.500102)
			(size 0.4572 0.4572)
			(layers "F.Cu" "F.Mask" "F.Paste")
			(net "VDDIO_DDR")
		)
		(pad "D3" smd circle
			(at -13.5001 -12.500102)
			(size 0.4572 0.4572)
			(layers "F.Cu" "F.Mask" "F.Paste")
			(net "Net_1250")
		)
		(pad "D4" smd circle
			(at -12.500102 -12.500102)
			(size 0.4572 0.4572)
			(layers "F.Cu" "F.Mask" "F.Paste")
			(net "VDDIO_DDR")
		)
		(pad "D5" smd circle
			(at -11.500104 -12.500102)
			(size 0.4572 0.4572)
			(layers "F.Cu" "F.Mask" "F.Paste")
			(net "Net_1249")
		)
		(pad "D6" smd circle
			(at -10.500106 -12.500102)
			(size 0.4572 0.4572)
			(layers "F.Cu" "F.Mask" "F.Paste")
			(net "GND")
		)
		(pad "D7" smd circle
			(at -9.500108 -12.500102)
			(size 0.4572 0.4572)
			(layers "F.Cu" "F.Mask" "F.Paste")
			(net "EXP_ADC_IN0")
		)
		(pad "D8" smd circle
			(at -8.50011 -12.500102)
			(size 0.4572 0.4572)
			(layers "F.Cu" "F.Mask" "F.Paste")
			(net "P1V8_E")
		)
		(pad "D9" smd circle
			(at -7.500112 -12.500102)
			(size 0.4572 0.4572)
			(layers "F.Cu" "F.Mask" "F.Paste")
			(net "DRIVE_4_ACT")
		)
		(pad "D10" smd circle
			(at -6.500114 -12.500102)
			(size 0.4572 0.4572)
			(layers "F.Cu" "F.Mask" "F.Paste")
			(net "LSI_TRST_N")
		)
		(pad "D11" smd circle
			(at -5.500116 -12.500102)
			(size 0.4572 0.4572)
			(layers "F.Cu" "F.Mask" "F.Paste")
			(net "EXP_CPU_MODE_1")
		)
		(pad "D12" smd circle
			(at -4.500118 -12.500102)
			(size 0.4572 0.4572)
			(layers "F.Cu" "F.Mask" "F.Paste")
			(net "EXP_XM_WE_N")
		)
		(pad "D13" smd circle
			(at -3.50012 -12.500102)
			(size 0.4572 0.4572)
			(layers "F.Cu" "F.Mask" "F.Paste")
			(net "XM_DATA8")
		)
		(pad "D14" smd circle
			(at -2.500122 -12.500102)
			(size 0.4572 0.4572)
			(layers "F.Cu" "F.Mask" "F.Paste")
			(net "P1V8_E")
		)
		(pad "D15" smd circle
			(at -1.500124 -12.500102)
			(size 0.4572 0.4572)
			(layers "F.Cu" "F.Mask" "F.Paste")
			(net "EXP_XM_ADDR_9")
		)
		(pad "D16" smd circle
			(at -0.500126 -12.500102)
			(size 0.4572 0.4572)
			(layers "F.Cu" "F.Mask" "F.Paste")
			(net "P1V8_E")
		)
		(pad "D17" smd circle
			(at 0.500126 -12.500102)
			(size 0.4572 0.4572)
			(layers "F.Cu" "F.Mask" "F.Paste")
			(net "EXP_XM_ADDR_17")
		)
		(pad "D18" smd circle
			(at 1.500124 -12.500102)
			(size 0.4572 0.4572)
			(layers "F.Cu" "F.Mask" "F.Paste")
			(net "P1V8_E")
		)
		(pad "D19" smd circle
			(at 2.500122 -12.500102)
			(size 0.4572 0.4572)
			(layers "F.Cu" "F.Mask" "F.Paste")
			(net "PWM_OUT_ZONE_C_LS")
		)
		(pad "D20" smd circle
			(at 3.50012 -12.500102)
			(size 0.4572 0.4572)
			(layers "F.Cu" "F.Mask" "F.Paste")
			(net "P1V8_E")
		)
		(pad "D21" smd circle
			(at 4.500118 -12.500102)
			(size 0.4572 0.4572)
			(layers "F.Cu" "F.Mask" "F.Paste")
			(net "SLOT_ID_1")
		)
		(pad "D22" smd circle
			(at 5.500116 -12.500102)
			(size 0.4572 0.4572)
			(layers "F.Cu" "F.Mask" "F.Paste")
			(net "P1V8_E")
		)
		(pad "D23" smd circle
			(at 6.500114 -12.500102)
			(size 0.4572 0.4572)
			(layers "F.Cu" "F.Mask" "F.Paste")
			(net "Net_1208")
		)
		(pad "D24" smd circle
			(at 7.500112 -12.500102)
			(size 0.4572 0.4572)
			(layers "F.Cu" "F.Mask" "F.Paste")
			(net "P1V8_E")
		)
		(pad "D25" smd circle
			(at 8.50011 -12.500102)
			(size 0.4572 0.4572)
			(layers "F.Cu" "F.Mask" "F.Paste")
			(net "Net_1207")
		)
		(pad "D26" smd circle
			(at 9.500108 -12.500102)
			(size 0.4572 0.4572)
			(layers "F.Cu" "F.Mask" "F.Paste")
			(net "P1V8_E")
		)
		(pad "D27" smd circle
			(at 10.500106 -12.500102)
			(size 0.4572 0.4572)
			(layers "F.Cu" "F.Mask" "F.Paste")
			(net "UART_RTS")
		)
		(pad "D28" smd circle
			(at 11.500104 -12.500102)
			(size 0.4572 0.4572)
			(layers "F.Cu" "F.Mask" "F.Paste")
			(net "P1V8_E")
		)
		(pad "D29" smd circle
			(at 12.500102 -12.500102)
			(size 0.4572 0.4572)
			(layers "F.Cu" "F.Mask" "F.Paste")
			(net "EXP_I2C_SCL11")
		)
		(pad "D30" smd circle
			(at 13.5001 -12.500102)
			(size 0.4572 0.4572)
			(layers "F.Cu" "F.Mask" "F.Paste")
			(net "P1V8_E")
		)
		(pad "D31" smd circle
			(at 14.500098 -12.500102)
			(size 0.4572 0.4572)
			(layers "F.Cu" "F.Mask" "F.Paste")
			(net "I2C_DRIVE_INS_SCL5_LS")
		)
		(pad "D32" smd circle
			(at 15.500096 -12.500102)
			(size 0.4572 0.4572)
			(layers "F.Cu" "F.Mask" "F.Paste")
			(net "P1V8_E")
		)
		(pad "E1" smd circle
			(at -15.500096 -11.500104)
			(size 0.4572 0.4572)
			(layers "F.Cu" "F.Mask" "F.Paste")
			(net "Net_1248")
		)
		(pad "E2" smd circle
			(at -14.500098 -11.500104)
			(size 0.4572 0.4572)
			(layers "F.Cu" "F.Mask" "F.Paste")
			(net "Net_1247")
		)
		(pad "E3" smd circle
			(at -13.5001 -11.500104)
			(size 0.4572 0.4572)
			(layers "F.Cu" "F.Mask" "F.Paste")
			(net "GND")
		)
		(pad "E4" smd circle
			(at -12.500102 -11.500104)
			(size 0.4572 0.4572)
			(layers "F.Cu" "F.Mask" "F.Paste")
			(net "Net_1246")
		)
		(pad "E5" smd circle
			(at -11.500104 -11.500104)
			(size 0.4572 0.4572)
			(layers "F.Cu" "F.Mask" "F.Paste")
			(net "Net_1245")
		)
		(pad "E6" smd circle
			(at -10.500106 -11.500104)
			(size 0.4572 0.4572)
			(layers "F.Cu" "F.Mask" "F.Paste")
			(net "GND")
		)
		(pad "E7" smd circle
			(at -9.500108 -11.500104)
			(size 0.4572 0.4572)
			(layers "F.Cu" "F.Mask" "F.Paste")
			(net "GND")
		)
		(pad "E8" smd circle
			(at -8.50011 -11.500104)
			(size 0.4572 0.4572)
			(layers "F.Cu" "F.Mask" "F.Paste")
			(net "TESTIBIAS")
		)
		(pad "E9" smd circle
			(at -7.500112 -11.500104)
			(size 0.4572 0.4572)
			(layers "F.Cu" "F.Mask" "F.Paste")
			(net "DRIVE_7_ACT")
		)
		(pad "E10" smd circle
			(at -6.500114 -11.500104)
			(size 0.4572 0.4572)
			(layers "F.Cu" "F.Mask" "F.Paste")
			(net "GND")
		)
		(pad "E11" smd circle
			(at -5.500116 -11.500104)
			(size 0.4572 0.4572)
			(layers "F.Cu" "F.Mask" "F.Paste")
			(net "EXP_IDDT")
		)
		(pad "E12" smd circle
			(at -4.500118 -11.500104)
			(size 0.4572 0.4572)
			(layers "F.Cu" "F.Mask" "F.Paste")
			(net "GND")
		)
		(pad "E13" smd circle
			(at -3.50012 -11.500104)
			(size 0.4572 0.4572)
			(layers "F.Cu" "F.Mask" "F.Paste")
			(net "XM_GP_CS_1#_TP")
		)
		(pad "E14" smd circle
			(at -2.500122 -11.500104)
			(size 0.4572 0.4572)
			(layers "F.Cu" "F.Mask" "F.Paste")
			(net "XM_DATA14")
		)
		(pad "E15" smd circle
			(at -1.500124 -11.500104)
			(size 0.4572 0.4572)
			(layers "F.Cu" "F.Mask" "F.Paste")
			(net "EXP_XM_ADDR_7")
		)
		(pad "E16" smd circle
			(at -0.500126 -11.500104)
			(size 0.4572 0.4572)
			(layers "F.Cu" "F.Mask" "F.Paste")
			(net "EXP_XM_ADDR_22")
		)
		(pad "E17" smd circle
			(at 0.500126 -11.500104)
			(size 0.4572 0.4572)
			(layers "F.Cu" "F.Mask" "F.Paste")
			(net "EXP_XM_ADDR_14")
		)
		(pad "E18" smd circle
			(at 1.500124 -11.500104)
			(size 0.4572 0.4572)
			(layers "F.Cu" "F.Mask" "F.Paste")
			(net "EXP_XM_ADDR_12")
		)
		(pad "E19" smd circle
			(at 2.500122 -11.500104)
			(size 0.4572 0.4572)
			(layers "F.Cu" "F.Mask" "F.Paste")
			(net "SCC_RMT_HEARTBEAT_LS")
		)
		(pad "E20" smd circle
			(at 3.50012 -11.500104)
			(size 0.4572 0.4572)
			(layers "F.Cu" "F.Mask" "F.Paste")
			(net "EXP_GPIO12")
		)
		(pad "E21" smd circle
			(at 4.500118 -11.500104)
			(size 0.4572 0.4572)
			(layers "F.Cu" "F.Mask" "F.Paste")
			(net "SLOT_ID_0")
		)
		(pad "E22" smd circle
			(at 5.500116 -11.500104)
			(size 0.4572 0.4572)
			(layers "F.Cu" "F.Mask" "F.Paste")
			(net "USB_DIR")
		)
		(pad "E23" smd circle
			(at 6.500114 -11.500104)
			(size 0.4572 0.4572)
			(layers "F.Cu" "F.Mask" "F.Paste")
			(net "Net_1206")
		)
		(pad "E24" smd circle
			(at 7.500112 -11.500104)
			(size 0.4572 0.4572)
			(layers "F.Cu" "F.Mask" "F.Paste")
			(net "Net_1205")
		)
		(pad "E25" smd circle
			(at 8.50011 -11.500104)
			(size 0.4572 0.4572)
			(layers "F.Cu" "F.Mask" "F.Paste")
			(net "ICE_TMS")
		)
		(pad "E26" smd circle
			(at 9.500108 -11.500104)
			(size 0.4572 0.4572)
			(layers "F.Cu" "F.Mask" "F.Paste")
			(net "EXP_SIO_LOAD_IN")
		)
		(pad "E27" smd circle
			(at 10.500106 -11.500104)
			(size 0.4572 0.4572)
			(layers "F.Cu" "F.Mask" "F.Paste")
			(net "I2C_EXP_IOC_SDA8")
		)
		(pad "E28" smd circle
			(at 11.500104 -11.500104)
			(size 0.4572 0.4572)
			(layers "F.Cu" "F.Mask" "F.Paste")
			(net "I2C_DRIVE_INS_SDA5_LS")
		)
		(pad "E29" smd circle
			(at 12.500102 -11.500104)
			(size 0.4572 0.4572)
			(layers "F.Cu" "F.Mask" "F.Paste")
			(net "I2C_DRIVE_PWR_SCL4_LS")
		)
		(pad "E30" smd circle
			(at 13.5001 -11.500104)
			(size 0.4572 0.4572)
			(layers "F.Cu" "F.Mask" "F.Paste")
			(net "I2C_BMC_RMT_SDA1_LS")
		)
		(pad "E31" smd circle
			(at 14.500098 -11.500104)
			(size 0.4572 0.4572)
			(layers "F.Cu" "F.Mask" "F.Paste")
			(net "I2C_BMC_RMT_SCL1_LS")
		)
		(pad "E32" smd circle
			(at 15.500096 -11.500104)
			(size 0.4572 0.4572)
			(layers "F.Cu" "F.Mask" "F.Paste")
			(net "I2C_BMC_LOC_SCL0_LS")
		)
		(pad "F1" smd circle
			(at -15.500096 -10.500106)
			(size 0.4572 0.4572)
			(layers "F.Cu" "F.Mask" "F.Paste")
			(net "Net_1244")
		)
		(pad "F2" smd circle
			(at -14.500098 -10.500106)
			(size 0.4572 0.4572)
			(layers "F.Cu" "F.Mask" "F.Paste")
			(net "VDDIO_DDR")
		)
		(pad "F3" smd circle
			(at -13.5001 -10.500106)
			(size 0.4572 0.4572)
			(layers "F.Cu" "F.Mask" "F.Paste")
			(net "Net_1243")
		)
		(pad "F4" smd circle
			(at -12.500102 -10.500106)
			(size 0.4572 0.4572)
			(layers "F.Cu" "F.Mask" "F.Paste")
			(net "VDDIO_DDR")
		)
		(pad "F5" smd circle
			(at -11.500104 -10.500106)
			(size 0.4572 0.4572)
			(layers "F.Cu" "F.Mask" "F.Paste")
			(net "Net_1242")
		)
		(pad "F6" smd circle
			(at -10.500106 -10.500106)
			(size 0.4572 0.4572)
			(layers "F.Cu" "F.Mask" "F.Paste")
			(net "VDDIO_DDR")
		)
		(pad "F7" smd circle
			(at -9.500108 -10.500106)
			(size 0.4572 0.4572)
			(layers "F.Cu" "F.Mask" "F.Paste")
			(net "GND")
		)
		(pad "F8" smd circle
			(at -8.50011 -10.500106)
			(size 0.4572 0.4572)
			(layers "F.Cu" "F.Mask" "F.Paste")
			(net "GND")
		)
		(pad "F9" smd circle
			(at -7.500112 -10.500106)
			(size 0.4572 0.4572)
			(layers "F.Cu" "F.Mask" "F.Paste")
			(net "SYS_PWR_LED_LS_N")
		)
		(pad "F10" smd circle
			(at -6.500114 -10.500106)
			(size 0.4572 0.4572)
			(layers "F.Cu" "F.Mask" "F.Paste")
			(net "P1V8_E")
		)
		(pad "F11" smd circle
			(at -5.500116 -10.500106)
			(size 0.4572 0.4572)
			(layers "F.Cu" "F.Mask" "F.Paste")
			(net "LSI_PROCMON")
		)
		(pad "F12" smd circle
			(at -4.500118 -10.500106)
			(size 0.4572 0.4572)
			(layers "F.Cu" "F.Mask" "F.Paste")
			(net "P1V8_E")
		)
		(pad "F13" smd circle
			(at -3.50012 -10.500106)
			(size 0.4572 0.4572)
			(layers "F.Cu" "F.Mask" "F.Paste")
			(net "XM_GP_CS_3#_TP")
		)
		(pad "F14" smd circle
			(at -2.500122 -10.500106)
			(size 0.4572 0.4572)
			(layers "F.Cu" "F.Mask" "F.Paste")
			(net "XM_DATA15")
		)
		(pad "F15" smd circle
			(at -1.500124 -10.500106)
			(size 0.4572 0.4572)
			(layers "F.Cu" "F.Mask" "F.Paste")
			(net "EXP_XM_ADDR_8")
		)
		(pad "F16" smd circle
			(at -0.500126 -10.500106)
			(size 0.4572 0.4572)
			(layers "F.Cu" "F.Mask" "F.Paste")
			(net "EXP_XM_ADDR_19")
		)
		(pad "F17" smd circle
			(at 0.500126 -10.500106)
			(size 0.4572 0.4572)
			(layers "F.Cu" "F.Mask" "F.Paste")
			(net "EXP_XM_ADDR_11")
		)
		(pad "F18" smd circle
			(at 1.500124 -10.500106)
			(size 0.4572 0.4572)
			(layers "F.Cu" "F.Mask" "F.Paste")
			(net "EXP_XM_ADDR_1")
		)
		(pad "F19" smd circle
			(at 2.500122 -10.500106)
			(size 0.4572 0.4572)
			(layers "F.Cu" "F.Mask" "F.Paste")
			(net "BMC_RMT_HEARTBEAT_LS")
		)
		(pad "F20" smd circle
			(at 3.50012 -10.500106)
			(size 0.4572 0.4572)
			(layers "F.Cu" "F.Mask" "F.Paste")
			(net "SCC_TYPE_0_LS")
		)
		(pad "F21" smd circle
			(at 4.500118 -10.500106)
			(size 0.4572 0.4572)
			(layers "F.Cu" "F.Mask" "F.Paste")
			(net "BMC_EXP_SPARE_0_R_LS")
		)
		(pad "F22" smd circle
			(at 5.500116 -10.500106)
			(size 0.4572 0.4572)
			(layers "F.Cu" "F.Mask" "F.Paste")
			(net "Net_1204")
		)
		(pad "F23" smd circle
			(at 6.500114 -10.500106)
			(size 0.4572 0.4572)
			(layers "F.Cu" "F.Mask" "F.Paste")
			(net "Net_1203")
		)
		(pad "F24" smd circle
			(at 7.500112 -10.500106)
			(size 0.4572 0.4572)
			(layers "F.Cu" "F.Mask" "F.Paste")
			(net "ICE_TRST_N")
		)
		(pad "F25" smd circle
			(at 8.50011 -10.500106)
			(size 0.4572 0.4572)
			(layers "F.Cu" "F.Mask" "F.Paste")
			(net "EXP_SIO_D_OUT")
		)
		(pad "F26" smd circle
			(at 9.500108 -10.500106)
			(size 0.4572 0.4572)
			(layers "F.Cu" "F.Mask" "F.Paste")
			(net "I2C_CLIP_SDA7_LS")
		)
		(pad "F27" smd circle
			(at 10.500106 -10.500106)
			(size 0.4572 0.4572)
			(layers "F.Cu" "F.Mask" "F.Paste")
			(net "GND")
		)
		(pad "F28" smd circle
			(at 11.500104 -10.500106)
			(size 0.4572 0.4572)
			(layers "F.Cu" "F.Mask" "F.Paste")
			(net "GND")
		)
		(pad "F29" smd circle
			(at 12.500102 -10.500106)
			(size 0.4572 0.4572)
			(layers "F.Cu" "F.Mask" "F.Paste")
			(net "I2C_BMC_LOC_SDA0_LS")
		)
		(pad "F30" smd circle
			(at 13.5001 -10.500106)
			(size 0.4572 0.4572)
			(layers "F.Cu" "F.Mask" "F.Paste")
			(net "GND")
		)
		(pad "F31" smd circle
			(at 14.500098 -10.500106)
			(size 0.4572 0.4572)
			(layers "F.Cu" "F.Mask" "F.Paste")
			(net "GND")
		)
		(pad "F32" smd circle
			(at 15.500096 -10.500106)
			(size 0.4572 0.4572)
			(layers "F.Cu" "F.Mask" "F.Paste")
			(net "GND")
		)
		(pad "G1" smd circle
			(at -15.500096 -9.500108)
			(size 0.4572 0.4572)
			(layers "F.Cu" "F.Mask" "F.Paste")
			(net "Net_1241")
		)
		(pad "G2" smd circle
			(at -14.500098 -9.500108)
			(size 0.4572 0.4572)
			(layers "F.Cu" "F.Mask" "F.Paste")
			(net "Net_1240")
		)
		(pad "G3" smd circle
			(at -13.5001 -9.500108)
			(size 0.4572 0.4572)
			(layers "F.Cu" "F.Mask" "F.Paste")
			(net "GND")
		)
		(pad "G4" smd circle
			(at -12.500102 -9.500108)
			(size 0.4572 0.4572)
			(layers "F.Cu" "F.Mask" "F.Paste")
			(net "Net_1239")
		)
		(pad "G5" smd circle
			(at -11.500104 -9.500108)
			(size 0.4572 0.4572)
			(layers "F.Cu" "F.Mask" "F.Paste")
			(net "GND")
		)
		(pad "G6" smd circle
			(at -10.500106 -9.500108)
			(size 0.4572 0.4572)
			(layers "F.Cu" "F.Mask" "F.Paste")
			(net "Net_1226")
		)
		(pad "G7" smd circle
			(at -9.500108 -9.500108)
			(size 0.4572 0.4572)
			(layers "F.Cu" "F.Mask" "F.Paste")
			(net "Net_1225")
		)
		(pad "G8" smd circle
			(at -8.50011 -9.500108)
			(size 0.4572 0.4572)
			(layers "F.Cu" "F.Mask" "F.Paste")
			(net "GND")
		)
		(pad "G9" smd circle
			(at -7.500112 -9.500108)
			(size 0.4572 0.4572)
			(layers "F.Cu" "F.Mask" "F.Paste")
			(net "ENCL_FAULT_LED_LS")
		)
		(pad "G10" smd circle
			(at -6.500114 -9.500108)
			(size 0.4572 0.4572)
			(layers "F.Cu" "F.Mask" "F.Paste")
			(net "EXP_BLINK_OUT")
		)
		(pad "G11" smd circle
			(at -5.500116 -9.500108)
			(size 0.4572 0.4572)
			(layers "F.Cu" "F.Mask" "F.Paste")
			(net "JTAG_EXP_TDI")
		)
		(pad "G12" smd circle
			(at -4.500118 -9.500108)
			(size 0.4572 0.4572)
			(layers "F.Cu" "F.Mask" "F.Paste")
			(net "EXP_RESET_N")
		)
		(pad "G13" smd circle
			(at -3.50012 -9.500108)
			(size 0.4572 0.4572)
			(layers "F.Cu" "F.Mask" "F.Paste")
			(net "XM_GP_CS_2#_TP")
		)
		(pad "G14" smd circle
			(at -2.500122 -9.500108)
			(size 0.4572 0.4572)
			(layers "F.Cu" "F.Mask" "F.Paste")
			(net "XM_DATA12")
		)
		(pad "G15" smd circle
			(at -1.500124 -9.500108)
			(size 0.4572 0.4572)
			(layers "F.Cu" "F.Mask" "F.Paste")
			(net "GND")
		)
		(pad "G16" smd circle
			(at -0.500126 -9.500108)
			(size 0.4572 0.4572)
			(layers "F.Cu" "F.Mask" "F.Paste")
			(net "EXP_XM_ADDR_20")
		)
		(pad "G17" smd circle
			(at 0.500126 -9.500108)
			(size 0.4572 0.4572)
			(layers "F.Cu" "F.Mask" "F.Paste")
			(net "GND")
		)
		(pad "G18" smd circle
			(at 1.500124 -9.500108)
			(size 0.4572 0.4572)
			(layers "F.Cu" "F.Mask" "F.Paste")
			(net "BMC_LOC_HEARTBEAT_LS")
		)
		(pad "G19" smd circle
			(at 2.500122 -9.500108)
			(size 0.4572 0.4572)
			(layers "F.Cu" "F.Mask" "F.Paste")
			(net "GND")
		)
		(pad "G20" smd circle
			(at 3.50012 -9.500108)
			(size 0.4572 0.4572)
			(layers "F.Cu" "F.Mask" "F.Paste")
			(net "EXP_GPIO1")
		)
		(pad "G21" smd circle
			(at 4.500118 -9.500108)
			(size 0.4572 0.4572)
			(layers "F.Cu" "F.Mask" "F.Paste")
			(net "GND")
		)
		(pad "G22" smd circle
			(at 5.500116 -9.500108)
			(size 0.4572 0.4572)
			(layers "F.Cu" "F.Mask" "F.Paste")
			(net "Net_1202")
		)
		(pad "G23" smd circle
			(at 6.500114 -9.500108)
			(size 0.4572 0.4572)
			(layers "F.Cu" "F.Mask" "F.Paste")
			(net "GND")
		)
		(pad "G24" smd circle
			(at 7.500112 -9.500108)
			(size 0.4572 0.4572)
			(layers "F.Cu" "F.Mask" "F.Paste")
			(net "ICE_TDI")
		)
		(pad "G25" smd circle
			(at 8.50011 -9.500108)
			(size 0.4572 0.4572)
			(layers "F.Cu" "F.Mask" "F.Paste")
			(net "I2C_DPB_SDA3_LS")
		)
		(pad "G26" smd circle
			(at 9.500108 -9.500108)
			(size 0.4572 0.4572)
			(layers "F.Cu" "F.Mask" "F.Paste")
			(net "GND")
		)
		(pad "G27" smd circle
			(at 10.500106 -9.500108)
			(size 0.4572 0.4572)
			(layers "F.Cu" "F.Mask" "F.Paste")
			(net "PHY_CONN_TO_EXP_C_11_DN")
		)
		(pad "G28" smd circle
			(at 11.500104 -9.500108)
			(size 0.4572 0.4572)
			(layers "F.Cu" "F.Mask" "F.Paste")
			(net "PHY_CONN_TO_EXP_C_11_DP")
		)
		(pad "G29" smd circle
			(at 12.500102 -9.500108)
			(size 0.4572 0.4572)
			(layers "F.Cu" "F.Mask" "F.Paste")
			(net "GND")
		)
		(pad "G30" smd circle
			(at 13.5001 -9.500108)
			(size 0.4572 0.4572)
			(layers "F.Cu" "F.Mask" "F.Paste")
			(net "GB_VDDA")
		)
		(pad "G31" smd circle
			(at 14.500098 -9.500108)
			(size 0.4572 0.4572)
			(layers "F.Cu" "F.Mask" "F.Paste")
			(net "PHY_EXP_TO_CONN_C_11_DN")
		)
		(pad "G32" smd circle
			(at 15.500096 -9.500108)
			(size 0.4572 0.4572)
			(layers "F.Cu" "F.Mask" "F.Paste")
			(net "PHY_EXP_TO_CONN_C_11_DP")
		)
		(pad "H1" smd circle
			(at -15.500096 -8.50011)
			(size 0.4572 0.4572)
			(layers "F.Cu" "F.Mask" "F.Paste")
			(net "Net_1282")
		)
		(pad "H2" smd circle
			(at -14.500098 -8.50011)
			(size 0.4572 0.4572)
			(layers "F.Cu" "F.Mask" "F.Paste")
			(net "VDDIO_DDR")
		)
		(pad "H3" smd circle
			(at -13.5001 -8.50011)
			(size 0.4572 0.4572)
			(layers "F.Cu" "F.Mask" "F.Paste")
			(net "Net_1281")
		)
		(pad "H4" smd circle
			(at -12.500102 -8.50011)
			(size 0.4572 0.4572)
			(layers "F.Cu" "F.Mask" "F.Paste")
			(net "VDDIO_DDR")
		)
		(pad "H5" smd circle
			(at -11.500104 -8.50011)
			(size 0.4572 0.4572)
			(layers "F.Cu" "F.Mask" "F.Paste")
			(net "Net_1280")
		)
		(pad "H6" smd circle
			(at -10.500106 -8.50011)
			(size 0.4572 0.4572)
			(layers "F.Cu" "F.Mask" "F.Paste")
			(net "VDDIO_DDR")
		)
		(pad "H7" smd circle
			(at -9.500108 -8.50011)
			(size 0.4572 0.4572)
			(layers "F.Cu" "F.Mask" "F.Paste")
			(net "Net_1237")
		)
		(pad "H8" smd circle
			(at -8.50011 -8.50011)
			(size 0.4572 0.4572)
			(layers "F.Cu" "F.Mask" "F.Paste")
			(net "GND")
		)
		(pad "H9" smd circle
			(at -7.500112 -8.50011)
			(size 0.4572 0.4572)
			(layers "F.Cu" "F.Mask" "F.Paste")
			(net "LED11")
		)
		(pad "H10" smd circle
			(at -6.500114 -8.50011)
			(size 0.4572 0.4572)
			(layers "F.Cu" "F.Mask" "F.Paste")
			(net "SXP_ACTIVE_0")
		)
		(pad "H11" smd circle
			(at -5.500116 -8.50011)
			(size 0.4572 0.4572)
			(layers "F.Cu" "F.Mask" "F.Paste")
			(net "JTAG_EXP_TCK")
		)
		(pad "H12" smd circle
			(at -4.500118 -8.50011)
			(size 0.4572 0.4572)
			(layers "F.Cu" "F.Mask" "F.Paste")
			(net "EXP_CLK_SEL1")
		)
		(pad "H13" smd circle
			(at -3.50012 -8.50011)
			(size 0.4572 0.4572)
			(layers "F.Cu" "F.Mask" "F.Paste")
			(net "EXP_XM_CS_N_0")
		)
		(pad "H14" smd circle
			(at -2.500122 -8.50011)
			(size 0.4572 0.4572)
			(layers "F.Cu" "F.Mask" "F.Paste")
			(net "XM_DATA11")
		)
		(pad "H15" smd circle
			(at -1.500124 -8.50011)
			(size 0.4572 0.4572)
			(layers "F.Cu" "F.Mask" "F.Paste")
			(net "P1V8_E")
		)
		(pad "H16" smd circle
			(at -0.500126 -8.50011)
			(size 0.4572 0.4572)
			(layers "F.Cu" "F.Mask" "F.Paste")
			(net "EXP_XM_ADDR_21")
		)
		(pad "H17" smd circle
			(at 0.500126 -8.50011)
			(size 0.4572 0.4572)
			(layers "F.Cu" "F.Mask" "F.Paste")
			(net "P1V8_E")
		)
		(pad "H18" smd circle
			(at 1.500124 -8.50011)
			(size 0.4572 0.4572)
			(layers "F.Cu" "F.Mask" "F.Paste")
			(net "COMP_EXP_SPARE_1_R_LS")
		)
		(pad "H19" smd circle
			(at 2.500122 -8.50011)
			(size 0.4572 0.4572)
			(layers "F.Cu" "F.Mask" "F.Paste")
			(net "P1V8_E")
		)
		(pad "H20" smd circle
			(at 3.50012 -8.50011)
			(size 0.4572 0.4572)
			(layers "F.Cu" "F.Mask" "F.Paste")
			(net "Net_1224")
		)
		(pad "H21" smd circle
			(at 4.500118 -8.50011)
			(size 0.4572 0.4572)
			(layers "F.Cu" "F.Mask" "F.Paste")
			(net "P1V8_E")
		)
		(pad "H22" smd circle
			(at 5.500116 -8.50011)
			(size 0.4572 0.4572)
			(layers "F.Cu" "F.Mask" "F.Paste")
			(net "Net_1218")
		)
		(pad "H23" smd circle
			(at 6.500114 -8.50011)
			(size 0.4572 0.4572)
			(layers "F.Cu" "F.Mask" "F.Paste")
			(net "P1V8_E")
		)
		(pad "H24" smd circle
			(at 7.500112 -8.50011)
			(size 0.4572 0.4572)
			(layers "F.Cu" "F.Mask" "F.Paste")
			(net "EXP_SIO_CLK_OUT")
		)
		(pad "H25" smd circle
			(at 8.50011 -8.50011)
			(size 0.4572 0.4572)
			(layers "F.Cu" "F.Mask" "F.Paste")
			(net "P1V8_E")
		)
		(pad "H26" smd circle
			(at 9.500108 -8.50011)
			(size 0.4572 0.4572)
			(layers "F.Cu" "F.Mask" "F.Paste")
			(net "GND")
		)
		(pad "H27" smd circle
			(at 10.500106 -8.50011)
			(size 0.4572 0.4572)
			(layers "F.Cu" "F.Mask" "F.Paste")
			(net "PHY_CONN_TO_EXP_C_10_DN")
		)
		(pad "H28" smd circle
			(at 11.500104 -8.50011)
			(size 0.4572 0.4572)
			(layers "F.Cu" "F.Mask" "F.Paste")
			(net "PHY_CONN_TO_EXP_C_10_DP")
		)
		(pad "H29" smd circle
			(at 12.500102 -8.50011)
			(size 0.4572 0.4572)
			(layers "F.Cu" "F.Mask" "F.Paste")
			(net "GB_VDDA")
		)
		(pad "H30" smd circle
			(at 13.5001 -8.50011)
			(size 0.4572 0.4572)
			(layers "F.Cu" "F.Mask" "F.Paste")
			(net "PHY_EXP_TO_CONN_C_10_DN")
		)
		(pad "H31" smd circle
			(at 14.500098 -8.50011)
			(size 0.4572 0.4572)
			(layers "F.Cu" "F.Mask" "F.Paste")
			(net "PHY_EXP_TO_CONN_C_10_DP")
		)
		(pad "H32" smd circle
			(at 15.500096 -8.50011)
			(size 0.4572 0.4572)
			(layers "F.Cu" "F.Mask" "F.Paste")
			(net "GND")
		)
		(pad "J1" smd circle
			(at -15.500096 -7.500112)
			(size 0.4572 0.4572)
			(layers "F.Cu" "F.Mask" "F.Paste")
			(net "Net_1279")
		)
		(pad "J2" smd circle
			(at -14.500098 -7.500112)
			(size 0.4572 0.4572)
			(layers "F.Cu" "F.Mask" "F.Paste")
			(net "Net_1278")
		)
		(pad "J3" smd circle
			(at -13.5001 -7.500112)
			(size 0.4572 0.4572)
			(layers "F.Cu" "F.Mask" "F.Paste")
			(net "GND")
		)
		(pad "J4" smd circle
			(at -12.500102 -7.500112)
			(size 0.4572 0.4572)
			(layers "F.Cu" "F.Mask" "F.Paste")
			(net "Net_1277")
		)
		(pad "J5" smd circle
			(at -11.500104 -7.500112)
			(size 0.4572 0.4572)
			(layers "F.Cu" "F.Mask" "F.Paste")
			(net "GND")
		)
		(pad "J6" smd circle
			(at -10.500106 -7.500112)
			(size 0.4572 0.4572)
			(layers "F.Cu" "F.Mask" "F.Paste")
			(net "Net_1236")
		)
		(pad "J7" smd circle
			(at -9.500108 -7.500112)
			(size 0.4572 0.4572)
			(layers "F.Cu" "F.Mask" "F.Paste")
			(net "Net_1235")
		)
		(pad "J8" smd circle
			(at -8.50011 -7.500112)
			(size 0.4572 0.4572)
			(layers "F.Cu" "F.Mask" "F.Paste")
			(net "Net_1234")
		)
		(pad "J9" smd circle
			(at -7.500112 -7.500112)
			(size 0.4572 0.4572)
			(layers "F.Cu" "F.Mask" "F.Paste")
			(net "GND")
		)
		(pad "J10" smd circle
			(at -6.500114 -7.500112)
			(size 0.4572 0.4572)
			(layers "F.Cu" "F.Mask" "F.Paste")
			(net "LED8")
		)
		(pad "J11" smd circle
			(at -5.500116 -7.500112)
			(size 0.4572 0.4572)
			(layers "F.Cu" "F.Mask" "F.Paste")
			(net "LSI_T_N")
		)
		(pad "J12" smd circle
			(at -4.500118 -7.500112)
			(size 0.4572 0.4572)
			(layers "F.Cu" "F.Mask" "F.Paste")
			(net "EXP_CLK_SEL0")
		)
		(pad "J13" smd circle
			(at -3.50012 -7.500112)
			(size 0.4572 0.4572)
			(layers "F.Cu" "F.Mask" "F.Paste")
			(net "XM_DATA9")
		)
		(pad "J14" smd circle
			(at -2.500122 -7.500112)
			(size 0.4572 0.4572)
			(layers "F.Cu" "F.Mask" "F.Paste")
			(net "XM_DATA0")
		)
		(pad "J15" smd circle
			(at -1.500124 -7.500112)
			(size 0.4572 0.4572)
			(layers "F.Cu" "F.Mask" "F.Paste")
			(net "EXP_XM_ADDR_6")
		)
		(pad "J16" smd circle
			(at -0.500126 -7.500112)
			(size 0.4572 0.4572)
			(layers "F.Cu" "F.Mask" "F.Paste")
			(net "EXP_XM_ADDR_2")
		)
		(pad "J17" smd circle
			(at 0.500126 -7.500112)
			(size 0.4572 0.4572)
			(layers "F.Cu" "F.Mask" "F.Paste")
			(net "Net_135")
		)
		(pad "J18" smd circle
			(at 1.500124 -7.500112)
			(size 0.4572 0.4572)
			(layers "F.Cu" "F.Mask" "F.Paste")
			(net "SCC_TYPE_1_LS")
		)
		(pad "J19" smd circle
			(at 2.500122 -7.500112)
			(size 0.4572 0.4572)
			(layers "F.Cu" "F.Mask" "F.Paste")
			(net "Net_1223")
		)
		(pad "J20" smd circle
			(at 3.50012 -7.500112)
			(size 0.4572 0.4572)
			(layers "F.Cu" "F.Mask" "F.Paste")
			(net "Net_1222")
		)
		(pad "J21" smd circle
			(at 4.500118 -7.500112)
			(size 0.4572 0.4572)
			(layers "F.Cu" "F.Mask" "F.Paste")
			(net "Net_1217")
		)
		(pad "J22" smd circle
			(at 5.500116 -7.500112)
			(size 0.4572 0.4572)
			(layers "F.Cu" "F.Mask" "F.Paste")
			(net "Net_1216")
		)
		(pad "J23" smd circle
			(at 6.500114 -7.500112)
			(size 0.4572 0.4572)
			(layers "F.Cu" "F.Mask" "F.Paste")
			(net "EXP_SIO_CLK_IN")
		)
		(pad "J24" smd circle
			(at 7.500112 -7.500112)
			(size 0.4572 0.4572)
			(layers "F.Cu" "F.Mask" "F.Paste")
			(net "I2C_DRIVE_PWR_SDA4_LS")
		)
		(pad "J25" smd circle
			(at 8.50011 -7.500112)
			(size 0.4572 0.4572)
			(layers "F.Cu" "F.Mask" "F.Paste")
			(net "I2C_SCC_SDA2_LS")
		)
		(pad "J26" smd circle
			(at 9.500108 -7.500112)
			(size 0.4572 0.4572)
			(layers "F.Cu" "F.Mask" "F.Paste")
			(net "GND")
		)
		(pad "J27" smd circle
			(at 10.500106 -7.500112)
			(size 0.4572 0.4572)
			(layers "F.Cu" "F.Mask" "F.Paste")
			(net "PHY_CONN_TO_EXP_C_9_DN")
		)
		(pad "J28" smd circle
			(at 11.500104 -7.500112)
			(size 0.4572 0.4572)
			(layers "F.Cu" "F.Mask" "F.Paste")
			(net "PHY_CONN_TO_EXP_C_9_DP")
		)
		(pad "J29" smd circle
			(at 12.500102 -7.500112)
			(size 0.4572 0.4572)
			(layers "F.Cu" "F.Mask" "F.Paste")
			(net "GND")
		)
		(pad "J30" smd circle
			(at 13.5001 -7.500112)
			(size 0.4572 0.4572)
			(layers "F.Cu" "F.Mask" "F.Paste")
			(net "GB_VDDA")
		)
		(pad "J31" smd circle
			(at 14.500098 -7.500112)
			(size 0.4572 0.4572)
			(layers "F.Cu" "F.Mask" "F.Paste")
			(net "PHY_EXP_TO_CONN_C_9_DN")
		)
		(pad "J32" smd circle
			(at 15.500096 -7.500112)
			(size 0.4572 0.4572)
			(layers "F.Cu" "F.Mask" "F.Paste")
			(net "PHY_EXP_TO_CONN_C_9_DP")
		)
		(pad "K1" smd circle
			(at -15.500096 -6.500114)
			(size 0.4572 0.4572)
			(layers "F.Cu" "F.Mask" "F.Paste")
			(net "Net_1276")
		)
		(pad "K2" smd circle
			(at -14.500098 -6.500114)
			(size 0.4572 0.4572)
			(layers "F.Cu" "F.Mask" "F.Paste")
			(net "VDDIO_DDR")
		)
		(pad "K3" smd circle
			(at -13.5001 -6.500114)
			(size 0.4572 0.4572)
			(layers "F.Cu" "F.Mask" "F.Paste")
			(net "Net_1275")
		)
		(pad "K4" smd circle
			(at -12.500102 -6.500114)
			(size 0.4572 0.4572)
			(layers "F.Cu" "F.Mask" "F.Paste")
			(net "VDDIO_DDR")
		)
		(pad "K5" smd circle
			(at -11.500104 -6.500114)
			(size 0.4572 0.4572)
			(layers "F.Cu" "F.Mask" "F.Paste")
			(net "Net_1274")
		)
		(pad "K6" smd circle
			(at -10.500106 -6.500114)
			(size 0.4572 0.4572)
			(layers "F.Cu" "F.Mask" "F.Paste")
			(net "VDDIO_DDR")
		)
		(pad "K7" smd circle
			(at -9.500108 -6.500114)
			(size 0.4572 0.4572)
			(layers "F.Cu" "F.Mask" "F.Paste")
			(net "Net_1233")
		)
		(pad "K8" smd circle
			(at -8.50011 -6.500114)
			(size 0.4572 0.4572)
			(layers "F.Cu" "F.Mask" "F.Paste")
			(net "Net_1232")
		)
		(pad "K9" smd circle
			(at -7.500112 -6.500114)
			(size 0.4572 0.4572)
			(layers "F.Cu" "F.Mask" "F.Paste")
			(net "GND")
		)
		(pad "K10" smd circle
			(at -6.500114 -6.500114)
			(size 0.4572 0.4572)
			(layers "F.Cu" "F.Mask" "F.Paste")
			(net "EXP_ADC_IN1")
		)
		(pad "K11" smd circle
			(at -5.500116 -6.500114)
			(size 0.4572 0.4572)
			(layers "F.Cu" "F.Mask" "F.Paste")
			(net "SXP_ACTIVE_1")
		)
		(pad "K12" smd circle
			(at -4.500118 -6.500114)
			(size 0.4572 0.4572)
			(layers "F.Cu" "F.Mask" "F.Paste")
			(net "EXP_CPU_MODE_0")
		)
		(pad "K13" smd circle
			(at -3.50012 -6.500114)
			(size 0.4572 0.4572)
			(layers "F.Cu" "F.Mask" "F.Paste")
			(net "EXP_XM_NOR_CS_N")
		)
		(pad "K14" smd circle
			(at -2.500122 -6.500114)
			(size 0.4572 0.4572)
			(layers "F.Cu" "F.Mask" "F.Paste")
			(net "XM_DATA13")
		)
		(pad "K15" smd circle
			(at -1.500124 -6.500114)
			(size 0.4572 0.4572)
			(layers "F.Cu" "F.Mask" "F.Paste")
			(net "EXP_XM_ADDR_24")
		)
		(pad "K16" smd circle
			(at -0.500126 -6.500114)
			(size 0.4572 0.4572)
			(layers "F.Cu" "F.Mask" "F.Paste")
			(net "EXP_XM_ADDR_15")
		)
		(pad "K17" smd circle
			(at 0.500126 -6.500114)
			(size 0.4572 0.4572)
			(layers "F.Cu" "F.Mask" "F.Paste")
			(net "EXP_GPIO14")
		)
		(pad "K18" smd circle
			(at 1.500124 -6.500114)
			(size 0.4572 0.4572)
			(layers "F.Cu" "F.Mask" "F.Paste")
			(net "DRIVE_INSERT_ALERT_LS_N")
		)
		(pad "K19" smd circle
			(at 2.500122 -6.500114)
			(size 0.4572 0.4572)
			(layers "F.Cu" "F.Mask" "F.Paste")
			(net "Net_1221")
		)
		(pad "K20" smd circle
			(at 3.50012 -6.500114)
			(size 0.4572 0.4572)
			(layers "F.Cu" "F.Mask" "F.Paste")
			(net "Net_1220")
		)
		(pad "K21" smd circle
			(at 4.500118 -6.500114)
			(size 0.4572 0.4572)
			(layers "F.Cu" "F.Mask" "F.Paste")
			(net "ICE_TCK")
		)
		(pad "K22" smd circle
			(at 5.500116 -6.500114)
			(size 0.4572 0.4572)
			(layers "F.Cu" "F.Mask" "F.Paste")
			(net "EXP_SIO_LOAD_OUT")
		)
		(pad "K23" smd circle
			(at 6.500114 -6.500114)
			(size 0.4572 0.4572)
			(layers "F.Cu" "F.Mask" "F.Paste")
			(net "I2C_CLIP_SCL7_LS")
		)
		(pad "K24" smd circle
			(at 7.500112 -6.500114)
			(size 0.4572 0.4572)
			(layers "F.Cu" "F.Mask" "F.Paste")
			(net "I2C_DPB_SCL3_LS")
		)
		(pad "K25" smd circle
			(at 8.50011 -6.500114)
			(size 0.4572 0.4572)
			(layers "F.Cu" "F.Mask" "F.Paste")
			(net "GND")
		)
		(pad "K26" smd circle
			(at 9.500108 -6.500114)
			(size 0.4572 0.4572)
			(layers "F.Cu" "F.Mask" "F.Paste")
			(net "GND")
		)
		(pad "K27" smd circle
			(at 10.500106 -6.500114)
			(size 0.4572 0.4572)
			(layers "F.Cu" "F.Mask" "F.Paste")
			(net "PHY_CONN_TO_EXP_C_8_DN")
		)
		(pad "K28" smd circle
			(at 11.500104 -6.500114)
			(size 0.4572 0.4572)
			(layers "F.Cu" "F.Mask" "F.Paste")
			(net "PHY_CONN_TO_EXP_C_8_DP")
		)
		(pad "K29" smd circle
			(at 12.500102 -6.500114)
			(size 0.4572 0.4572)
			(layers "F.Cu" "F.Mask" "F.Paste")
			(net "GB_VDDA")
		)
		(pad "K30" smd circle
			(at 13.5001 -6.500114)
			(size 0.4572 0.4572)
			(layers "F.Cu" "F.Mask" "F.Paste")
			(net "PHY_EXP_TO_CONN_C_8_DN")
		)
		(pad "K31" smd circle
			(at 14.500098 -6.500114)
			(size 0.4572 0.4572)
			(layers "F.Cu" "F.Mask" "F.Paste")
			(net "PHY_EXP_TO_CONN_C_8_DP")
		)
		(pad "K32" smd circle
			(at 15.500096 -6.500114)
			(size 0.4572 0.4572)
			(layers "F.Cu" "F.Mask" "F.Paste")
			(net "GND")
		)
		(pad "L1" smd circle
			(at -15.500096 -5.500116)
			(size 0.4572 0.4572)
			(layers "F.Cu" "F.Mask" "F.Paste")
			(net "Net_1273")
		)
		(pad "L2" smd circle
			(at -14.500098 -5.500116)
			(size 0.4572 0.4572)
			(layers "F.Cu" "F.Mask" "F.Paste")
			(net "Net_1272")
		)
		(pad "L3" smd circle
			(at -13.5001 -5.500116)
			(size 0.4572 0.4572)
			(layers "F.Cu" "F.Mask" "F.Paste")
			(net "GND")
		)
		(pad "L4" smd circle
			(at -12.500102 -5.500116)
			(size 0.4572 0.4572)
			(layers "F.Cu" "F.Mask" "F.Paste")
			(net "Net_1271")
		)
		(pad "L5" smd circle
			(at -11.500104 -5.500116)
			(size 0.4572 0.4572)
			(layers "F.Cu" "F.Mask" "F.Paste")
			(net "GND")
		)
		(pad "L6" smd circle
			(at -10.500106 -5.500116)
			(size 0.4572 0.4572)
			(layers "F.Cu" "F.Mask" "F.Paste")
			(net "Net_1231")
		)
		(pad "L7" smd circle
			(at -9.500108 -5.500116)
			(size 0.4572 0.4572)
			(layers "F.Cu" "F.Mask" "F.Paste")
			(net "Net_1230")
		)
		(pad "L8" smd circle
			(at -8.50011 -5.500116)
			(size 0.4572 0.4572)
			(layers "F.Cu" "F.Mask" "F.Paste")
			(net "Net_1229")
		)
		(pad "L9" smd circle
			(at -7.500112 -5.500116)
			(size 0.4572 0.4572)
			(layers "F.Cu" "F.Mask" "F.Paste")
			(net "GND")
		)
		(pad "L10" smd circle
			(at -6.500114 -5.500116)
			(size 0.4572 0.4572)
			(layers "F.Cu" "F.Mask" "F.Paste")
			(net "P1V8_E")
		)
		(pad "L11" smd circle
			(at -5.500116 -5.500116)
			(size 0.4572 0.4572)
			(layers "F.Cu" "F.Mask" "F.Paste")
			(net "DRIVE_3_ACT")
		)
		(pad "L12" smd circle
			(at -4.500118 -5.500116)
			(size 0.4572 0.4572)
			(layers "F.Cu" "F.Mask" "F.Paste")
			(net "LSI_SCAN_ENABLE")
		)
		(pad "L13" smd circle
			(at -3.50012 -5.500116)
			(size 0.4572 0.4572)
			(layers "F.Cu" "F.Mask" "F.Paste")
			(net "P1V8_E")
		)
		(pad "L14" smd circle
			(at -2.500122 -5.500116)
			(size 0.4572 0.4572)
			(layers "F.Cu" "F.Mask" "F.Paste")
			(net "XM_DATA4")
		)
		(pad "L15" smd circle
			(at -1.500124 -5.500116)
			(size 0.4572 0.4572)
			(layers "F.Cu" "F.Mask" "F.Paste")
			(net "P1V8_E")
		)
		(pad "L16" smd circle
			(at -0.500126 -5.500116)
			(size 0.4572 0.4572)
			(layers "F.Cu" "F.Mask" "F.Paste")
			(net "EXP_XM_ADDR_10")
		)
		(pad "L17" smd circle
			(at 0.500126 -5.500116)
			(size 0.4572 0.4572)
			(layers "F.Cu" "F.Mask" "F.Paste")
			(net "P1V8_E")
		)
		(pad "L18" smd circle
			(at 1.500124 -5.500116)
			(size 0.4572 0.4572)
			(layers "F.Cu" "F.Mask" "F.Paste")
			(net "Net_1219")
		)
		(pad "L19" smd circle
			(at 2.500122 -5.500116)
			(size 0.4572 0.4572)
			(layers "F.Cu" "F.Mask" "F.Paste")
			(net "P1V8_E")
		)
		(pad "L20" smd circle
			(at 3.50012 -5.500116)
			(size 0.4572 0.4572)
			(layers "F.Cu" "F.Mask" "F.Paste")
			(net "LSI_EFUSE")
		)
		(pad "L21" smd circle
			(at 4.500118 -5.500116)
			(size 0.4572 0.4572)
			(layers "F.Cu" "F.Mask" "F.Paste")
			(net "P1V8_E")
		)
		(pad "L22" smd circle
			(at 5.500116 -5.500116)
			(size 0.4572 0.4572)
			(layers "F.Cu" "F.Mask" "F.Paste")
			(net "EXP_I2C_SDA9")
		)
		(pad "L23" smd circle
			(at 6.500114 -5.500116)
			(size 0.4572 0.4572)
			(layers "F.Cu" "F.Mask" "F.Paste")
			(net "P1V8_E")
		)
		(pad "L24" smd circle
			(at 7.500112 -5.500116)
			(size 0.4572 0.4572)
			(layers "F.Cu" "F.Mask" "F.Paste")
			(net "I2C_SCC_SCL2_LS")
		)
		(pad "L25" smd circle
			(at 8.50011 -5.500116)
			(size 0.4572 0.4572)
			(layers "F.Cu" "F.Mask" "F.Paste")
			(net "GND")
		)
		(pad "L26" smd circle
			(at 9.500108 -5.500116)
			(size 0.4572 0.4572)
			(layers "F.Cu" "F.Mask" "F.Paste")
			(net "GB_VDDA")
		)
		(pad "L27" smd circle
			(at 10.500106 -5.500116)
			(size 0.4572 0.4572)
			(layers "F.Cu" "F.Mask" "F.Paste")
			(net "PHY_DPB_TO_SCC_C_7_DN")
		)
		(pad "L28" smd circle
			(at 11.500104 -5.500116)
			(size 0.4572 0.4572)
			(layers "F.Cu" "F.Mask" "F.Paste")
			(net "PHY_DPB_TO_SCC_C_7_DP")
		)
		(pad "L29" smd circle
			(at 12.500102 -5.500116)
			(size 0.4572 0.4572)
			(layers "F.Cu" "F.Mask" "F.Paste")
			(net "GND")
		)
		(pad "L30" smd circle
			(at 13.5001 -5.500116)
			(size 0.4572 0.4572)
			(layers "F.Cu" "F.Mask" "F.Paste")
			(net "GB_VDDA")
		)
		(pad "L31" smd circle
			(at 14.500098 -5.500116)
			(size 0.4572 0.4572)
			(layers "F.Cu" "F.Mask" "F.Paste")
			(net "PHY_SCC_TO_DPB_7_DN")
		)
		(pad "L32" smd circle
			(at 15.500096 -5.500116)
			(size 0.4572 0.4572)
			(layers "F.Cu" "F.Mask" "F.Paste")
			(net "PHY_SCC_TO_DPB_7_DP")
		)
		(pad "M1" smd circle
			(at -15.500096 -4.500118)
			(size 0.4572 0.4572)
			(layers "F.Cu" "F.Mask" "F.Paste")
			(net "Net_1270")
		)
		(pad "M2" smd circle
			(at -14.500098 -4.500118)
			(size 0.4572 0.4572)
			(layers "F.Cu" "F.Mask" "F.Paste")
			(net "VDDIO_DDR")
		)
		(pad "M3" smd circle
			(at -13.5001 -4.500118)
			(size 0.4572 0.4572)
			(layers "F.Cu" "F.Mask" "F.Paste")
			(net "Net_1269")
		)
		(pad "M4" smd circle
			(at -12.500102 -4.500118)
			(size 0.4572 0.4572)
			(layers "F.Cu" "F.Mask" "F.Paste")
			(net "VDDIO_DDR")
		)
		(pad "M5" smd circle
			(at -11.500104 -4.500118)
			(size 0.4572 0.4572)
			(layers "F.Cu" "F.Mask" "F.Paste")
			(net "Net_1268")
		)
		(pad "M6" smd circle
			(at -10.500106 -4.500118)
			(size 0.4572 0.4572)
			(layers "F.Cu" "F.Mask" "F.Paste")
			(net "VDDIO_DDR")
		)
		(pad "M7" smd circle
			(at -9.500108 -4.500118)
			(size 0.4572 0.4572)
			(layers "F.Cu" "F.Mask" "F.Paste")
			(net "VDDIO_DDR")
		)
		(pad "M8" smd circle
			(at -8.50011 -4.500118)
			(size 0.4572 0.4572)
			(layers "F.Cu" "F.Mask" "F.Paste")
			(net "GND")
		)
		(pad "M9" smd circle
			(at -7.500112 -4.500118)
			(size 0.4572 0.4572)
			(layers "F.Cu" "F.Mask" "F.Paste")
			(net "VDDIO_DDR")
		)
		(pad "M10" smd circle
			(at -6.500114 -4.500118)
			(size 0.4572 0.4572)
			(layers "F.Cu" "F.Mask" "F.Paste")
			(net "GND")
		)
		(pad "M11" smd circle
			(at -5.500116 -4.500118)
			(size 0.4572 0.4572)
			(layers "F.Cu" "F.Mask" "F.Paste")
			(net "GND")
		)
		(pad "M12" smd circle
			(at -4.500118 -4.500118)
			(size 0.4572 0.4572)
			(layers "F.Cu" "F.Mask" "F.Paste")
			(net "P1V8_E")
		)
		(pad "M13" smd circle
			(at -3.50012 -4.500118)
			(size 0.4572 0.4572)
			(layers "F.Cu" "F.Mask" "F.Paste")
			(net "GND")
		)
		(pad "M14" smd circle
			(at -2.500122 -4.500118)
			(size 0.4572 0.4572)
			(layers "F.Cu" "F.Mask" "F.Paste")
			(net "P1V8_E")
		)
		(pad "M15" smd circle
			(at -1.500124 -4.500118)
			(size 0.4572 0.4572)
			(layers "F.Cu" "F.Mask" "F.Paste")
			(net "GND")
		)
		(pad "M16" smd circle
			(at -0.500126 -4.500118)
			(size 0.4572 0.4572)
			(layers "F.Cu" "F.Mask" "F.Paste")
			(net "P1V8_E")
		)
		(pad "M17" smd circle
			(at 0.500126 -4.500118)
			(size 0.4572 0.4572)
			(layers "F.Cu" "F.Mask" "F.Paste")
			(net "GND")
		)
		(pad "M18" smd circle
			(at 1.500124 -4.500118)
			(size 0.4572 0.4572)
			(layers "F.Cu" "F.Mask" "F.Paste")
			(net "P1V8_E")
		)
		(pad "M19" smd circle
			(at 2.500122 -4.500118)
			(size 0.4572 0.4572)
			(layers "F.Cu" "F.Mask" "F.Paste")
			(net "GND")
		)
		(pad "M20" smd circle
			(at 3.50012 -4.500118)
			(size 0.4572 0.4572)
			(layers "F.Cu" "F.Mask" "F.Paste")
			(net "P1V8_E")
		)
		(pad "M21" smd circle
			(at 4.500118 -4.500118)
			(size 0.4572 0.4572)
			(layers "F.Cu" "F.Mask" "F.Paste")
			(net "GND")
		)
		(pad "M22" smd circle
			(at 5.500116 -4.500118)
			(size 0.4572 0.4572)
			(layers "F.Cu" "F.Mask" "F.Paste")
			(net "GND")
		)
		(pad "M23" smd circle
			(at 6.500114 -4.500118)
			(size 0.4572 0.4572)
			(layers "F.Cu" "F.Mask" "F.Paste")
			(net "GND")
		)
		(pad "M24" smd circle
			(at 7.500112 -4.500118)
			(size 0.4572 0.4572)
			(layers "F.Cu" "F.Mask" "F.Paste")
			(net "GND")
		)
		(pad "M25" smd circle
			(at 8.50011 -4.500118)
			(size 0.4572 0.4572)
			(layers "F.Cu" "F.Mask" "F.Paste")
			(net "GB_VDDA")
		)
		(pad "M26" smd circle
			(at 9.500108 -4.500118)
			(size 0.4572 0.4572)
			(layers "F.Cu" "F.Mask" "F.Paste")
			(net "GND")
		)
		(pad "M27" smd circle
			(at 10.500106 -4.500118)
			(size 0.4572 0.4572)
			(layers "F.Cu" "F.Mask" "F.Paste")
			(net "PHY_DPB_TO_SCC_C_6_DN")
		)
		(pad "M28" smd circle
			(at 11.500104 -4.500118)
			(size 0.4572 0.4572)
			(layers "F.Cu" "F.Mask" "F.Paste")
			(net "PHY_DPB_TO_SCC_C_6_DP")
		)
		(pad "M29" smd circle
			(at 12.500102 -4.500118)
			(size 0.4572 0.4572)
			(layers "F.Cu" "F.Mask" "F.Paste")
			(net "GB_VDDA")
		)
		(pad "M30" smd circle
			(at 13.5001 -4.500118)
			(size 0.4572 0.4572)
			(layers "F.Cu" "F.Mask" "F.Paste")
			(net "PHY_SCC_TO_DPB_6_DN")
		)
		(pad "M31" smd circle
			(at 14.500098 -4.500118)
			(size 0.4572 0.4572)
			(layers "F.Cu" "F.Mask" "F.Paste")
			(net "PHY_SCC_TO_DPB_6_DP")
		)
		(pad "M32" smd circle
			(at 15.500096 -4.500118)
			(size 0.4572 0.4572)
			(layers "F.Cu" "F.Mask" "F.Paste")
			(net "GND")
		)
		(pad "N1" smd circle
			(at -15.500096 -3.50012)
			(size 0.4572 0.4572)
			(layers "F.Cu" "F.Mask" "F.Paste")
			(net "Net_1267")
		)
		(pad "N2" smd circle
			(at -14.500098 -3.50012)
			(size 0.4572 0.4572)
			(layers "F.Cu" "F.Mask" "F.Paste")
			(net "Net_1266")
		)
		(pad "N3" smd circle
			(at -13.5001 -3.50012)
			(size 0.4572 0.4572)
			(layers "F.Cu" "F.Mask" "F.Paste")
			(net "GND")
		)
		(pad "N4" smd circle
			(at -12.500102 -3.50012)
			(size 0.4572 0.4572)
			(layers "F.Cu" "F.Mask" "F.Paste")
			(net "Net_1265")
		)
		(pad "N5" smd circle
			(at -11.500104 -3.50012)
			(size 0.4572 0.4572)
			(layers "F.Cu" "F.Mask" "F.Paste")
			(net "GND")
		)
		(pad "N6" smd circle
			(at -10.500106 -3.50012)
			(size 0.4572 0.4572)
			(layers "F.Cu" "F.Mask" "F.Paste")
			(net "Net_1228")
		)
		(pad "N7" smd circle
			(at -9.500108 -3.50012)
			(size 0.4572 0.4572)
			(layers "F.Cu" "F.Mask" "F.Paste")
			(net "GND")
		)
		(pad "N8" smd circle
			(at -8.50011 -3.50012)
			(size 0.4572 0.4572)
			(layers "F.Cu" "F.Mask" "F.Paste")
			(net "VDDIO_DDR")
		)
		(pad "N9" smd circle
			(at -7.500112 -3.50012)
			(size 0.4572 0.4572)
			(layers "F.Cu" "F.Mask" "F.Paste")
			(net "GND")
		)
		(pad "N10" smd circle
			(at -6.500114 -3.50012)
			(size 0.4572 0.4572)
			(layers "F.Cu" "F.Mask" "F.Paste")
			(net "VDDIO_DDR")
		)
		(pad "N11" smd circle
			(at -5.500116 -3.50012)
			(size 0.4572 0.4572)
			(layers "F.Cu" "F.Mask" "F.Paste")
			(net "GND")
		)
		(pad "N12" smd circle
			(at -4.500118 -3.50012)
			(size 0.4572 0.4572)
			(layers "F.Cu" "F.Mask" "F.Paste")
			(net "P0V9")
		)
		(pad "N13" smd circle
			(at -3.50012 -3.50012)
			(size 0.4572 0.4572)
			(layers "F.Cu" "F.Mask" "F.Paste")
			(net "GND")
		)
		(pad "N14" smd circle
			(at -2.500122 -3.50012)
			(size 0.4572 0.4572)
			(layers "F.Cu" "F.Mask" "F.Paste")
			(net "P0V9")
		)
		(pad "N15" smd circle
			(at -1.500124 -3.50012)
			(size 0.4572 0.4572)
			(layers "F.Cu" "F.Mask" "F.Paste")
			(net "GND")
		)
		(pad "N16" smd circle
			(at -0.500126 -3.50012)
			(size 0.4572 0.4572)
			(layers "F.Cu" "F.Mask" "F.Paste")
			(net "P0V9")
		)
		(pad "N17" smd circle
			(at 0.500126 -3.50012)
			(size 0.4572 0.4572)
			(layers "F.Cu" "F.Mask" "F.Paste")
			(net "GND")
		)
		(pad "N18" smd circle
			(at 1.500124 -3.50012)
			(size 0.4572 0.4572)
			(layers "F.Cu" "F.Mask" "F.Paste")
			(net "P0V9")
		)
		(pad "N19" smd circle
			(at 2.500122 -3.50012)
			(size 0.4572 0.4572)
			(layers "F.Cu" "F.Mask" "F.Paste")
			(net "GND")
		)
		(pad "N20" smd circle
			(at 3.50012 -3.50012)
			(size 0.4572 0.4572)
			(layers "F.Cu" "F.Mask" "F.Paste")
			(net "P0V9")
		)
		(pad "N21" smd circle
			(at 4.500118 -3.50012)
			(size 0.4572 0.4572)
			(layers "F.Cu" "F.Mask" "F.Paste")
			(net "GND")
		)
		(pad "N22" smd circle
			(at 5.500116 -3.50012)
			(size 0.4572 0.4572)
			(layers "F.Cu" "F.Mask" "F.Paste")
			(net "GB_VDDH")
		)
		(pad "N23" smd circle
			(at 6.500114 -3.50012)
			(size 0.4572 0.4572)
			(layers "F.Cu" "F.Mask" "F.Paste")
			(net "GND")
		)
		(pad "N24" smd circle
			(at 7.500112 -3.50012)
			(size 0.4572 0.4572)
			(layers "F.Cu" "F.Mask" "F.Paste")
			(net "GB_VDDA")
		)
		(pad "N25" smd circle
			(at 8.50011 -3.50012)
			(size 0.4572 0.4572)
			(layers "F.Cu" "F.Mask" "F.Paste")
			(net "GND")
		)
		(pad "N26" smd circle
			(at 9.500108 -3.50012)
			(size 0.4572 0.4572)
			(layers "F.Cu" "F.Mask" "F.Paste")
			(net "GB_VDDA")
		)
		(pad "N27" smd circle
			(at 10.500106 -3.50012)
			(size 0.4572 0.4572)
			(layers "F.Cu" "F.Mask" "F.Paste")
			(net "PHY_DPB_TO_SCC_C_5_DN")
		)
		(pad "N28" smd circle
			(at 11.500104 -3.50012)
			(size 0.4572 0.4572)
			(layers "F.Cu" "F.Mask" "F.Paste")
			(net "PHY_DPB_TO_SCC_C_5_DP")
		)
		(pad "N29" smd circle
			(at 12.500102 -3.50012)
			(size 0.4572 0.4572)
			(layers "F.Cu" "F.Mask" "F.Paste")
			(net "GND")
		)
		(pad "N30" smd circle
			(at 13.5001 -3.50012)
			(size 0.4572 0.4572)
			(layers "F.Cu" "F.Mask" "F.Paste")
			(net "GB_VDDA")
		)
		(pad "N31" smd circle
			(at 14.500098 -3.50012)
			(size 0.4572 0.4572)
			(layers "F.Cu" "F.Mask" "F.Paste")
			(net "PHY_SCC_TO_DPB_5_DN")
		)
		(pad "N32" smd circle
			(at 15.500096 -3.50012)
			(size 0.4572 0.4572)
			(layers "F.Cu" "F.Mask" "F.Paste")
			(net "PHY_SCC_TO_DPB_5_DP")
		)
		(pad "P1" smd circle
			(at -15.500096 -2.500122)
			(size 0.4572 0.4572)
			(layers "F.Cu" "F.Mask" "F.Paste")
			(net "Net_1264")
		)
		(pad "P2" smd circle
			(at -14.500098 -2.500122)
			(size 0.4572 0.4572)
			(layers "F.Cu" "F.Mask" "F.Paste")
			(net "VDDIO_DDR")
		)
		(pad "P3" smd circle
			(at -13.5001 -2.500122)
			(size 0.4572 0.4572)
			(layers "F.Cu" "F.Mask" "F.Paste")
			(net "Net_1263")
		)
		(pad "P4" smd circle
			(at -12.500102 -2.500122)
			(size 0.4572 0.4572)
			(layers "F.Cu" "F.Mask" "F.Paste")
			(net "VDDIO_DDR")
		)
		(pad "P5" smd circle
			(at -11.500104 -2.500122)
			(size 0.4572 0.4572)
			(layers "F.Cu" "F.Mask" "F.Paste")
			(net "Net_1262")
		)
		(pad "P6" smd circle
			(at -10.500106 -2.500122)
			(size 0.4572 0.4572)
			(layers "F.Cu" "F.Mask" "F.Paste")
			(net "GND")
		)
		(pad "P7" smd circle
			(at -9.500108 -2.500122)
			(size 0.4572 0.4572)
			(layers "F.Cu" "F.Mask" "F.Paste")
			(net "Net_1227")
		)
		(pad "P8" smd circle
			(at -8.50011 -2.500122)
			(size 0.4572 0.4572)
			(layers "F.Cu" "F.Mask" "F.Paste")
			(net "GND")
		)
		(pad "P9" smd circle
			(at -7.500112 -2.500122)
			(size 0.4572 0.4572)
			(layers "F.Cu" "F.Mask" "F.Paste")
			(net "VDDIO_DDR")
		)
		(pad "P10" smd circle
			(at -6.500114 -2.500122)
			(size 0.4572 0.4572)
			(layers "F.Cu" "F.Mask" "F.Paste")
			(net "GND")
		)
		(pad "P11" smd circle
			(at -5.500116 -2.500122)
			(size 0.4572 0.4572)
			(layers "F.Cu" "F.Mask" "F.Paste")
			(net "VDDIO_DDR")
		)
		(pad "P12" smd circle
			(at -4.500118 -2.500122)
			(size 0.4572 0.4572)
			(layers "F.Cu" "F.Mask" "F.Paste")
			(net "GND")
		)
		(pad "P13" smd circle
			(at -3.50012 -2.500122)
			(size 0.4572 0.4572)
			(layers "F.Cu" "F.Mask" "F.Paste")
			(net "P0V9")
		)
		(pad "P14" smd circle
			(at -2.500122 -2.500122)
			(size 0.4572 0.4572)
			(layers "F.Cu" "F.Mask" "F.Paste")
			(net "GND")
		)
		(pad "P15" smd circle
			(at -1.500124 -2.500122)
			(size 0.4572 0.4572)
			(layers "F.Cu" "F.Mask" "F.Paste")
			(net "P0V9")
		)
		(pad "P16" smd circle
			(at -0.500126 -2.500122)
			(size 0.4572 0.4572)
			(layers "F.Cu" "F.Mask" "F.Paste")
			(net "GND")
		)
		(pad "P17" smd circle
			(at 0.500126 -2.500122)
			(size 0.4572 0.4572)
			(layers "F.Cu" "F.Mask" "F.Paste")
			(net "P0V9")
		)
		(pad "P18" smd circle
			(at 1.500124 -2.500122)
			(size 0.4572 0.4572)
			(layers "F.Cu" "F.Mask" "F.Paste")
			(net "GND")
		)
		(pad "P19" smd circle
			(at 2.500122 -2.500122)
			(size 0.4572 0.4572)
			(layers "F.Cu" "F.Mask" "F.Paste")
			(net "P0V9")
		)
		(pad "P20" smd circle
			(at 3.50012 -2.500122)
			(size 0.4572 0.4572)
			(layers "F.Cu" "F.Mask" "F.Paste")
			(net "GND")
		)
		(pad "P21" smd circle
			(at 4.500118 -2.500122)
			(size 0.4572 0.4572)
			(layers "F.Cu" "F.Mask" "F.Paste")
			(net "GND")
		)
		(pad "P22" smd circle
			(at 5.500116 -2.500122)
			(size 0.4572 0.4572)
			(layers "F.Cu" "F.Mask" "F.Paste")
			(net "GB_VDDH")
		)
		(pad "P23" smd circle
			(at 6.500114 -2.500122)
			(size 0.4572 0.4572)
			(layers "F.Cu" "F.Mask" "F.Paste")
			(net "GND")
		)
		(pad "P24" smd circle
			(at 7.500112 -2.500122)
			(size 0.4572 0.4572)
			(layers "F.Cu" "F.Mask" "F.Paste")
			(net "GND")
		)
		(pad "P25" smd circle
			(at 8.50011 -2.500122)
			(size 0.4572 0.4572)
			(layers "F.Cu" "F.Mask" "F.Paste")
			(net "GB_VDDA")
		)
		(pad "P26" smd circle
			(at 9.500108 -2.500122)
			(size 0.4572 0.4572)
			(layers "F.Cu" "F.Mask" "F.Paste")
			(net "GND")
		)
		(pad "P27" smd circle
			(at 10.500106 -2.500122)
			(size 0.4572 0.4572)
			(layers "F.Cu" "F.Mask" "F.Paste")
			(net "PHY_DPB_TO_SCC_C_4_DN")
		)
		(pad "P28" smd circle
			(at 11.500104 -2.500122)
			(size 0.4572 0.4572)
			(layers "F.Cu" "F.Mask" "F.Paste")
			(net "PHY_DPB_TO_SCC_C_4_DP")
		)
		(pad "P29" smd circle
			(at 12.500102 -2.500122)
			(size 0.4572 0.4572)
			(layers "F.Cu" "F.Mask" "F.Paste")
			(net "GB_VDDA")
		)
		(pad "P30" smd circle
			(at 13.5001 -2.500122)
			(size 0.4572 0.4572)
			(layers "F.Cu" "F.Mask" "F.Paste")
			(net "PHY_SCC_TO_DPB_4_DN")
		)
		(pad "P31" smd circle
			(at 14.500098 -2.500122)
			(size 0.4572 0.4572)
			(layers "F.Cu" "F.Mask" "F.Paste")
			(net "PHY_SCC_TO_DPB_4_DP")
		)
		(pad "P32" smd circle
			(at 15.500096 -2.500122)
			(size 0.4572 0.4572)
			(layers "F.Cu" "F.Mask" "F.Paste")
			(net "GND")
		)
		(pad "R1" smd circle
			(at -15.500096 -1.500124)
			(size 0.4572 0.4572)
			(layers "F.Cu" "F.Mask" "F.Paste")
			(net "Net_1294")
		)
		(pad "R2" smd circle
			(at -14.500098 -1.500124)
			(size 0.4572 0.4572)
			(layers "F.Cu" "F.Mask" "F.Paste")
			(net "Net_1293")
		)
		(pad "R3" smd circle
			(at -13.5001 -1.500124)
			(size 0.4572 0.4572)
			(layers "F.Cu" "F.Mask" "F.Paste")
			(net "GND")
		)
		(pad "R4" smd circle
			(at -12.500102 -1.500124)
			(size 0.4572 0.4572)
			(layers "F.Cu" "F.Mask" "F.Paste")
			(net "Net_1292")
		)
		(pad "R5" smd circle
			(at -11.500104 -1.500124)
			(size 0.4572 0.4572)
			(layers "F.Cu" "F.Mask" "F.Paste")
			(net "GND")
		)
		(pad "R6" smd circle
			(at -10.500106 -1.500124)
			(size 0.4572 0.4572)
			(layers "F.Cu" "F.Mask" "F.Paste")
			(net "Net_1238")
		)
		(pad "R7" smd circle
			(at -9.500108 -1.500124)
			(size 0.4572 0.4572)
			(layers "F.Cu" "F.Mask" "F.Paste")
			(net "GND")
		)
		(pad "R8" smd circle
			(at -8.50011 -1.500124)
			(size 0.4572 0.4572)
			(layers "F.Cu" "F.Mask" "F.Paste")
			(net "VDDIO_DDR")
		)
		(pad "R9" smd circle
			(at -7.500112 -1.500124)
			(size 0.4572 0.4572)
			(layers "F.Cu" "F.Mask" "F.Paste")
			(net "GND")
		)
		(pad "R10" smd circle
			(at -6.500114 -1.500124)
			(size 0.4572 0.4572)
			(layers "F.Cu" "F.Mask" "F.Paste")
			(net "VDDIO_DDR")
		)
		(pad "R11" smd circle
			(at -5.500116 -1.500124)
			(size 0.4572 0.4572)
			(layers "F.Cu" "F.Mask" "F.Paste")
			(net "GND")
		)
		(pad "R12" smd circle
			(at -4.500118 -1.500124)
			(size 0.4572 0.4572)
			(layers "F.Cu" "F.Mask" "F.Paste")
			(net "P0V9")
		)
		(pad "R13" smd circle
			(at -3.50012 -1.500124)
			(size 0.4572 0.4572)
			(layers "F.Cu" "F.Mask" "F.Paste")
			(net "GND")
		)
		(pad "R14" smd circle
			(at -2.500122 -1.500124)
			(size 0.4572 0.4572)
			(layers "F.Cu" "F.Mask" "F.Paste")
			(net "P0V9")
		)
		(pad "R15" smd circle
			(at -1.500124 -1.500124)
			(size 0.4572 0.4572)
			(layers "F.Cu" "F.Mask" "F.Paste")
			(net "GND")
		)
		(pad "R16" smd circle
			(at -0.500126 -1.500124)
			(size 0.4572 0.4572)
			(layers "F.Cu" "F.Mask" "F.Paste")
			(net "P0V9")
		)
		(pad "R17" smd circle
			(at 0.500126 -1.500124)
			(size 0.4572 0.4572)
			(layers "F.Cu" "F.Mask" "F.Paste")
			(net "GND")
		)
		(pad "R18" smd circle
			(at 1.500124 -1.500124)
			(size 0.4572 0.4572)
			(layers "F.Cu" "F.Mask" "F.Paste")
			(net "P0V9")
		)
		(pad "R19" smd circle
			(at 2.500122 -1.500124)
			(size 0.4572 0.4572)
			(layers "F.Cu" "F.Mask" "F.Paste")
			(net "GND")
		)
		(pad "R20" smd circle
			(at 3.50012 -1.500124)
			(size 0.4572 0.4572)
			(layers "F.Cu" "F.Mask" "F.Paste")
			(net "P0V9")
		)
		(pad "R21" smd circle
			(at 4.500118 -1.500124)
			(size 0.4572 0.4572)
			(layers "F.Cu" "F.Mask" "F.Paste")
			(net "GND")
		)
		(pad "R22" smd circle
			(at 5.500116 -1.500124)
			(size 0.4572 0.4572)
			(layers "F.Cu" "F.Mask" "F.Paste")
			(net "GB_VDDH")
		)
		(pad "R23" smd circle
			(at 6.500114 -1.500124)
			(size 0.4572 0.4572)
			(layers "F.Cu" "F.Mask" "F.Paste")
			(net "GND")
		)
		(pad "R24" smd circle
			(at 7.500112 -1.500124)
			(size 0.4572 0.4572)
			(layers "F.Cu" "F.Mask" "F.Paste")
			(net "GB_VDDA")
		)
		(pad "R25" smd circle
			(at 8.50011 -1.500124)
			(size 0.4572 0.4572)
			(layers "F.Cu" "F.Mask" "F.Paste")
			(net "GND")
		)
		(pad "R26" smd circle
			(at 9.500108 -1.500124)
			(size 0.4572 0.4572)
			(layers "F.Cu" "F.Mask" "F.Paste")
			(net "GB_VDDA")
		)
		(pad "R27" smd circle
			(at 10.500106 -1.500124)
			(size 0.4572 0.4572)
			(layers "F.Cu" "F.Mask" "F.Paste")
			(net "PHY_DPB_TO_SCC_C_3_DN")
		)
		(pad "R28" smd circle
			(at 11.500104 -1.500124)
			(size 0.4572 0.4572)
			(layers "F.Cu" "F.Mask" "F.Paste")
			(net "PHY_DPB_TO_SCC_C_3_DP")
		)
		(pad "R29" smd circle
			(at 12.500102 -1.500124)
			(size 0.4572 0.4572)
			(layers "F.Cu" "F.Mask" "F.Paste")
			(net "GND")
		)
		(pad "R30" smd circle
			(at 13.5001 -1.500124)
			(size 0.4572 0.4572)
			(layers "F.Cu" "F.Mask" "F.Paste")
			(net "GB_VDDA")
		)
		(pad "R31" smd circle
			(at 14.500098 -1.500124)
			(size 0.4572 0.4572)
			(layers "F.Cu" "F.Mask" "F.Paste")
			(net "PHY_SCC_TO_DPB_3_DN")
		)
		(pad "R32" smd circle
			(at 15.500096 -1.500124)
			(size 0.4572 0.4572)
			(layers "F.Cu" "F.Mask" "F.Paste")
			(net "PHY_SCC_TO_DPB_3_DP")
		)
		(pad "T1" smd circle
			(at -15.500096 -0.500126)
			(size 0.4572 0.4572)
			(layers "F.Cu" "F.Mask" "F.Paste")
			(net "Net_1291")
		)
		(pad "T2" smd circle
			(at -14.500098 -0.500126)
			(size 0.4572 0.4572)
			(layers "F.Cu" "F.Mask" "F.Paste")
			(net "VDDIO_DDR")
		)
		(pad "T3" smd circle
			(at -13.5001 -0.500126)
			(size 0.4572 0.4572)
			(layers "F.Cu" "F.Mask" "F.Paste")
			(net "Net_1290")
		)
		(pad "T4" smd circle
			(at -12.500102 -0.500126)
			(size 0.4572 0.4572)
			(layers "F.Cu" "F.Mask" "F.Paste")
			(net "VDDIO_DDR")
		)
		(pad "T5" smd circle
			(at -11.500104 -0.500126)
			(size 0.4572 0.4572)
			(layers "F.Cu" "F.Mask" "F.Paste")
			(net "Net_1289")
		)
		(pad "T6" smd circle
			(at -10.500106 -0.500126)
			(size 0.4572 0.4572)
			(layers "F.Cu" "F.Mask" "F.Paste")
			(net "GND")
		)
		(pad "T7" smd circle
			(at -9.500108 -0.500126)
			(size 0.4572 0.4572)
			(layers "F.Cu" "F.Mask" "F.Paste")
			(net "VDDIO_DDR")
		)
		(pad "T8" smd circle
			(at -8.50011 -0.500126)
			(size 0.4572 0.4572)
			(layers "F.Cu" "F.Mask" "F.Paste")
			(net "GND")
		)
		(pad "T9" smd circle
			(at -7.500112 -0.500126)
			(size 0.4572 0.4572)
			(layers "F.Cu" "F.Mask" "F.Paste")
			(net "VDDIO_DDR")
		)
		(pad "T10" smd circle
			(at -6.500114 -0.500126)
			(size 0.4572 0.4572)
			(layers "F.Cu" "F.Mask" "F.Paste")
			(net "GND")
		)
		(pad "T11" smd circle
			(at -5.500116 -0.500126)
			(size 0.4572 0.4572)
			(layers "F.Cu" "F.Mask" "F.Paste")
			(net "VDDIO_DDR")
		)
		(pad "T12" smd circle
			(at -4.500118 -0.500126)
			(size 0.4572 0.4572)
			(layers "F.Cu" "F.Mask" "F.Paste")
			(net "GND")
		)
		(pad "T13" smd circle
			(at -3.50012 -0.500126)
			(size 0.4572 0.4572)
			(layers "F.Cu" "F.Mask" "F.Paste")
			(net "P0V9")
		)
		(pad "T14" smd circle
			(at -2.500122 -0.500126)
			(size 0.4572 0.4572)
			(layers "F.Cu" "F.Mask" "F.Paste")
			(net "GND")
		)
		(pad "T15" smd circle
			(at -1.500124 -0.500126)
			(size 0.4572 0.4572)
			(layers "F.Cu" "F.Mask" "F.Paste")
			(net "P0V9")
		)
		(pad "T16" smd circle
			(at -0.500126 -0.500126)
			(size 0.4572 0.4572)
			(layers "F.Cu" "F.Mask" "F.Paste")
			(net "GND")
		)
		(pad "T17" smd circle
			(at 0.500126 -0.500126)
			(size 0.4572 0.4572)
			(layers "F.Cu" "F.Mask" "F.Paste")
			(net "P0V9")
		)
		(pad "T18" smd circle
			(at 1.500124 -0.500126)
			(size 0.4572 0.4572)
			(layers "F.Cu" "F.Mask" "F.Paste")
			(net "GND")
		)
		(pad "T19" smd circle
			(at 2.500122 -0.500126)
			(size 0.4572 0.4572)
			(layers "F.Cu" "F.Mask" "F.Paste")
			(net "P0V9")
		)
		(pad "T20" smd circle
			(at 3.50012 -0.500126)
			(size 0.4572 0.4572)
			(layers "F.Cu" "F.Mask" "F.Paste")
			(net "GND")
		)
		(pad "T21" smd circle
			(at 4.500118 -0.500126)
			(size 0.4572 0.4572)
			(layers "F.Cu" "F.Mask" "F.Paste")
			(net "GND")
		)
		(pad "T22" smd circle
			(at 5.500116 -0.500126)
			(size 0.4572 0.4572)
			(layers "F.Cu" "F.Mask" "F.Paste")
			(net "GB_VDDH")
		)
		(pad "T23" smd circle
			(at 6.500114 -0.500126)
			(size 0.4572 0.4572)
			(layers "F.Cu" "F.Mask" "F.Paste")
			(net "GND")
		)
		(pad "T24" smd circle
			(at 7.500112 -0.500126)
			(size 0.4572 0.4572)
			(layers "F.Cu" "F.Mask" "F.Paste")
			(net "GND")
		)
		(pad "T25" smd circle
			(at 8.50011 -0.500126)
			(size 0.4572 0.4572)
			(layers "F.Cu" "F.Mask" "F.Paste")
			(net "GB_VDDA")
		)
		(pad "T26" smd circle
			(at 9.500108 -0.500126)
			(size 0.4572 0.4572)
			(layers "F.Cu" "F.Mask" "F.Paste")
			(net "GND")
		)
		(pad "T27" smd circle
			(at 10.500106 -0.500126)
			(size 0.4572 0.4572)
			(layers "F.Cu" "F.Mask" "F.Paste")
			(net "PHY_DPB_TO_SCC_C_2_DN")
		)
		(pad "T28" smd circle
			(at 11.500104 -0.500126)
			(size 0.4572 0.4572)
			(layers "F.Cu" "F.Mask" "F.Paste")
			(net "PHY_DPB_TO_SCC_C_2_DP")
		)
		(pad "T29" smd circle
			(at 12.500102 -0.500126)
			(size 0.4572 0.4572)
			(layers "F.Cu" "F.Mask" "F.Paste")
			(net "GB_VDDA")
		)
		(pad "T30" smd circle
			(at 13.5001 -0.500126)
			(size 0.4572 0.4572)
			(layers "F.Cu" "F.Mask" "F.Paste")
			(net "PHY_SCC_TO_DPB_2_DN")
		)
		(pad "T31" smd circle
			(at 14.500098 -0.500126)
			(size 0.4572 0.4572)
			(layers "F.Cu" "F.Mask" "F.Paste")
			(net "PHY_SCC_TO_DPB_2_DP")
		)
		(pad "T32" smd circle
			(at 15.500096 -0.500126)
			(size 0.4572 0.4572)
			(layers "F.Cu" "F.Mask" "F.Paste")
			(net "GND")
		)
		(pad "U1" smd circle
			(at -15.500096 0.500126)
			(size 0.4572 0.4572)
			(layers "F.Cu" "F.Mask" "F.Paste")
			(net "Net_1288")
		)
		(pad "U2" smd circle
			(at -14.500098 0.500126)
			(size 0.4572 0.4572)
			(layers "F.Cu" "F.Mask" "F.Paste")
			(net "Net_1287")
		)
		(pad "U3" smd circle
			(at -13.5001 0.500126)
			(size 0.4572 0.4572)
			(layers "F.Cu" "F.Mask" "F.Paste")
			(net "GND")
		)
		(pad "U4" smd circle
			(at -12.500102 0.500126)
			(size 0.4572 0.4572)
			(layers "F.Cu" "F.Mask" "F.Paste")
			(net "Net_1286")
		)
		(pad "U5" smd circle
			(at -11.500104 0.500126)
			(size 0.4572 0.4572)
			(layers "F.Cu" "F.Mask" "F.Paste")
			(net "GND")
		)
		(pad "U6" smd circle
			(at -10.500106 0.500126)
			(size 0.4572 0.4572)
			(layers "F.Cu" "F.Mask" "F.Paste")
			(net "DDR_BZ")
		)
		(pad "U7" smd circle
			(at -9.500108 0.500126)
			(size 0.4572 0.4572)
			(layers "F.Cu" "F.Mask" "F.Paste")
			(net "GND")
		)
		(pad "U8" smd circle
			(at -8.50011 0.500126)
			(size 0.4572 0.4572)
			(layers "F.Cu" "F.Mask" "F.Paste")
			(net "SYSPLL_VDDA09")
		)
		(pad "U9" smd circle
			(at -7.500112 0.500126)
			(size 0.4572 0.4572)
			(layers "F.Cu" "F.Mask" "F.Paste")
			(net "GND")
		)
		(pad "U10" smd circle
			(at -6.500114 0.500126)
			(size 0.4572 0.4572)
			(layers "F.Cu" "F.Mask" "F.Paste")
			(net "GND")
		)
		(pad "U11" smd circle
			(at -5.500116 0.500126)
			(size 0.4572 0.4572)
			(layers "F.Cu" "F.Mask" "F.Paste")
			(net "GND")
		)
		(pad "U12" smd circle
			(at -4.500118 0.500126)
			(size 0.4572 0.4572)
			(layers "F.Cu" "F.Mask" "F.Paste")
			(net "P0V9")
		)
		(pad "U13" smd circle
			(at -3.50012 0.500126)
			(size 0.4572 0.4572)
			(layers "F.Cu" "F.Mask" "F.Paste")
			(net "GND")
		)
		(pad "U14" smd circle
			(at -2.500122 0.500126)
			(size 0.4572 0.4572)
			(layers "F.Cu" "F.Mask" "F.Paste")
			(net "P0V9")
		)
		(pad "U15" smd circle
			(at -1.500124 0.500126)
			(size 0.4572 0.4572)
			(layers "F.Cu" "F.Mask" "F.Paste")
			(net "GND")
		)
		(pad "U16" smd circle
			(at -0.500126 0.500126)
			(size 0.4572 0.4572)
			(layers "F.Cu" "F.Mask" "F.Paste")
			(net "P0V9")
		)
		(pad "U17" smd circle
			(at 0.500126 0.500126)
			(size 0.4572 0.4572)
			(layers "F.Cu" "F.Mask" "F.Paste")
			(net "GND")
		)
		(pad "U18" smd circle
			(at 1.500124 0.500126)
			(size 0.4572 0.4572)
			(layers "F.Cu" "F.Mask" "F.Paste")
			(net "P0V9")
		)
		(pad "U19" smd circle
			(at 2.500122 0.500126)
			(size 0.4572 0.4572)
			(layers "F.Cu" "F.Mask" "F.Paste")
			(net "GND")
		)
		(pad "U20" smd circle
			(at 3.50012 0.500126)
			(size 0.4572 0.4572)
			(layers "F.Cu" "F.Mask" "F.Paste")
			(net "P0V9")
		)
		(pad "U21" smd circle
			(at 4.500118 0.500126)
			(size 0.4572 0.4572)
			(layers "F.Cu" "F.Mask" "F.Paste")
			(net "GND")
		)
		(pad "U22" smd circle
			(at 5.500116 0.500126)
			(size 0.4572 0.4572)
			(layers "F.Cu" "F.Mask" "F.Paste")
			(net "GB_VDDH")
		)
		(pad "U23" smd circle
			(at 6.500114 0.500126)
			(size 0.4572 0.4572)
			(layers "F.Cu" "F.Mask" "F.Paste")
			(net "GND")
		)
		(pad "U24" smd circle
			(at 7.500112 0.500126)
			(size 0.4572 0.4572)
			(layers "F.Cu" "F.Mask" "F.Paste")
			(net "GB_VDDA")
		)
		(pad "U25" smd circle
			(at 8.50011 0.500126)
			(size 0.4572 0.4572)
			(layers "F.Cu" "F.Mask" "F.Paste")
			(net "GND")
		)
		(pad "U26" smd circle
			(at 9.500108 0.500126)
			(size 0.4572 0.4572)
			(layers "F.Cu" "F.Mask" "F.Paste")
			(net "GB_VDDA")
		)
		(pad "U27" smd circle
			(at 10.500106 0.500126)
			(size 0.4572 0.4572)
			(layers "F.Cu" "F.Mask" "F.Paste")
			(net "PHY_DPB_TO_SCC_C_1_DN")
		)
		(pad "U28" smd circle
			(at 11.500104 0.500126)
			(size 0.4572 0.4572)
			(layers "F.Cu" "F.Mask" "F.Paste")
			(net "PHY_DPB_TO_SCC_C_1_DP")
		)
		(pad "U29" smd circle
			(at 12.500102 0.500126)
			(size 0.4572 0.4572)
			(layers "F.Cu" "F.Mask" "F.Paste")
			(net "GND")
		)
		(pad "U30" smd circle
			(at 13.5001 0.500126)
			(size 0.4572 0.4572)
			(layers "F.Cu" "F.Mask" "F.Paste")
			(net "GB_VDDA")
		)
		(pad "U31" smd circle
			(at 14.500098 0.500126)
			(size 0.4572 0.4572)
			(layers "F.Cu" "F.Mask" "F.Paste")
			(net "PHY_SCC_TO_DPB_1_DN")
		)
		(pad "U32" smd circle
			(at 15.500096 0.500126)
			(size 0.4572 0.4572)
			(layers "F.Cu" "F.Mask" "F.Paste")
			(net "PHY_SCC_TO_DPB_1_DP")
		)
		(pad "V1" smd circle
			(at -15.500096 1.500124)
			(size 0.4572 0.4572)
			(layers "F.Cu" "F.Mask" "F.Paste")
			(net "Net_1285")
		)
		(pad "V2" smd circle
			(at -14.500098 1.500124)
			(size 0.4572 0.4572)
			(layers "F.Cu" "F.Mask" "F.Paste")
			(net "VDDIO_DDR")
		)
		(pad "V3" smd circle
			(at -13.5001 1.500124)
			(size 0.4572 0.4572)
			(layers "F.Cu" "F.Mask" "F.Paste")
			(net "Net_1284")
		)
		(pad "V4" smd circle
			(at -12.500102 1.500124)
			(size 0.4572 0.4572)
			(layers "F.Cu" "F.Mask" "F.Paste")
			(net "VDDIO_DDR")
		)
		(pad "V5" smd circle
			(at -11.500104 1.500124)
			(size 0.4572 0.4572)
			(layers "F.Cu" "F.Mask" "F.Paste")
			(net "Net_1283")
		)
		(pad "V6" smd circle
			(at -10.500106 1.500124)
			(size 0.4572 0.4572)
			(layers "F.Cu" "F.Mask" "F.Paste")
			(net "GND")
		)
		(pad "V7" smd circle
			(at -9.500108 1.500124)
			(size 0.4572 0.4572)
			(layers "F.Cu" "F.Mask" "F.Paste")
			(net "SYSPLL_VDDA18")
		)
		(pad "V8" smd circle
			(at -8.50011 1.500124)
			(size 0.4572 0.4572)
			(layers "F.Cu" "F.Mask" "F.Paste")
			(net "GND")
		)
		(pad "V9" smd circle
			(at -7.500112 1.500124)
			(size 0.4572 0.4572)
			(layers "F.Cu" "F.Mask" "F.Paste")
			(net "PLLDDR_VDDA18")
		)
		(pad "V10" smd circle
			(at -6.500114 1.500124)
			(size 0.4572 0.4572)
			(layers "F.Cu" "F.Mask" "F.Paste")
			(net "GND")
		)
		(pad "V11" smd circle
			(at -5.500116 1.500124)
			(size 0.4572 0.4572)
			(layers "F.Cu" "F.Mask" "F.Paste")
			(net "P1V8_E")
		)
		(pad "V12" smd circle
			(at -4.500118 1.500124)
			(size 0.4572 0.4572)
			(layers "F.Cu" "F.Mask" "F.Paste")
			(net "GND")
		)
		(pad "V13" smd circle
			(at -3.50012 1.500124)
			(size 0.4572 0.4572)
			(layers "F.Cu" "F.Mask" "F.Paste")
			(net "P0V9")
		)
		(pad "V14" smd circle
			(at -2.500122 1.500124)
			(size 0.4572 0.4572)
			(layers "F.Cu" "F.Mask" "F.Paste")
			(net "GND")
		)
		(pad "V15" smd circle
			(at -1.500124 1.500124)
			(size 0.4572 0.4572)
			(layers "F.Cu" "F.Mask" "F.Paste")
			(net "P0V9")
		)
		(pad "V16" smd circle
			(at -0.500126 1.500124)
			(size 0.4572 0.4572)
			(layers "F.Cu" "F.Mask" "F.Paste")
			(net "GND")
		)
		(pad "V17" smd circle
			(at 0.500126 1.500124)
			(size 0.4572 0.4572)
			(layers "F.Cu" "F.Mask" "F.Paste")
			(net "P0V9")
		)
		(pad "V18" smd circle
			(at 1.500124 1.500124)
			(size 0.4572 0.4572)
			(layers "F.Cu" "F.Mask" "F.Paste")
			(net "GND")
		)
		(pad "V19" smd circle
			(at 2.500122 1.500124)
			(size 0.4572 0.4572)
			(layers "F.Cu" "F.Mask" "F.Paste")
			(net "P0V9")
		)
		(pad "V20" smd circle
			(at 3.50012 1.500124)
			(size 0.4572 0.4572)
			(layers "F.Cu" "F.Mask" "F.Paste")
			(net "GND")
		)
		(pad "V21" smd circle
			(at 4.500118 1.500124)
			(size 0.4572 0.4572)
			(layers "F.Cu" "F.Mask" "F.Paste")
			(net "GND")
		)
		(pad "V22" smd circle
			(at 5.500116 1.500124)
			(size 0.4572 0.4572)
			(layers "F.Cu" "F.Mask" "F.Paste")
			(net "GB_VDDH")
		)
		(pad "V23" smd circle
			(at 6.500114 1.500124)
			(size 0.4572 0.4572)
			(layers "F.Cu" "F.Mask" "F.Paste")
			(net "GND")
		)
		(pad "V24" smd circle
			(at 7.500112 1.500124)
			(size 0.4572 0.4572)
			(layers "F.Cu" "F.Mask" "F.Paste")
			(net "GND")
		)
		(pad "V25" smd circle
			(at 8.50011 1.500124)
			(size 0.4572 0.4572)
			(layers "F.Cu" "F.Mask" "F.Paste")
			(net "GND")
		)
		(pad "V26" smd circle
			(at 9.500108 1.500124)
			(size 0.4572 0.4572)
			(layers "F.Cu" "F.Mask" "F.Paste")
			(net "GND")
		)
		(pad "V27" smd circle
			(at 10.500106 1.500124)
			(size 0.4572 0.4572)
			(layers "F.Cu" "F.Mask" "F.Paste")
			(net "PHY_DPB_TO_SCC_C_0_DN")
		)
		(pad "V28" smd circle
			(at 11.500104 1.500124)
			(size 0.4572 0.4572)
			(layers "F.Cu" "F.Mask" "F.Paste")
			(net "PHY_DPB_TO_SCC_C_0_DP")
		)
		(pad "V29" smd circle
			(at 12.500102 1.500124)
			(size 0.4572 0.4572)
			(layers "F.Cu" "F.Mask" "F.Paste")
			(net "GB_VDDA")
		)
		(pad "V30" smd circle
			(at 13.5001 1.500124)
			(size 0.4572 0.4572)
			(layers "F.Cu" "F.Mask" "F.Paste")
			(net "PHY_SCC_TO_DPB_0_DN")
		)
		(pad "V31" smd circle
			(at 14.500098 1.500124)
			(size 0.4572 0.4572)
			(layers "F.Cu" "F.Mask" "F.Paste")
			(net "PHY_SCC_TO_DPB_0_DP")
		)
		(pad "V32" smd circle
			(at 15.500096 1.500124)
			(size 0.4572 0.4572)
			(layers "F.Cu" "F.Mask" "F.Paste")
			(net "GND")
		)
		(pad "W1" smd circle
			(at -15.500096 2.500122)
			(size 0.4572 0.4572)
			(layers "F.Cu" "F.Mask" "F.Paste")
			(net "GND")
		)
		(pad "W2" smd circle
			(at -14.500098 2.500122)
			(size 0.4572 0.4572)
			(layers "F.Cu" "F.Mask" "F.Paste")
			(net "GND")
		)
		(pad "W3" smd circle
			(at -13.5001 2.500122)
			(size 0.4572 0.4572)
			(layers "F.Cu" "F.Mask" "F.Paste")
			(net "GND")
		)
		(pad "W4" smd circle
			(at -12.500102 2.500122)
			(size 0.4572 0.4572)
			(layers "F.Cu" "F.Mask" "F.Paste")
			(net "GND")
		)
		(pad "W5" smd circle
			(at -11.500104 2.500122)
			(size 0.4572 0.4572)
			(layers "F.Cu" "F.Mask" "F.Paste")
			(net "GND")
		)
		(pad "W6" smd circle
			(at -10.500106 2.500122)
			(size 0.4572 0.4572)
			(layers "F.Cu" "F.Mask" "F.Paste")
			(net "GND")
		)
		(pad "W7" smd circle
			(at -9.500108 2.500122)
			(size 0.4572 0.4572)
			(layers "F.Cu" "F.Mask" "F.Paste")
			(net "DRIVE_13_ACT")
		)
		(pad "W8" smd circle
			(at -8.50011 2.500122)
			(size 0.4572 0.4572)
			(layers "F.Cu" "F.Mask" "F.Paste")
			(net "DRIVE_16_ACT")
		)
		(pad "W9" smd circle
			(at -7.500112 2.500122)
			(size 0.4572 0.4572)
			(layers "F.Cu" "F.Mask" "F.Paste")
			(net "DRIVE_21_ACT")
		)
		(pad "W10" smd circle
			(at -6.500114 2.500122)
			(size 0.4572 0.4572)
			(layers "F.Cu" "F.Mask" "F.Paste")
			(net "P1V8_E")
		)
		(pad "W11" smd circle
			(at -5.500116 2.500122)
			(size 0.4572 0.4572)
			(layers "F.Cu" "F.Mask" "F.Paste")
			(net "GND")
		)
		(pad "W12" smd circle
			(at -4.500118 2.500122)
			(size 0.4572 0.4572)
			(layers "F.Cu" "F.Mask" "F.Paste")
			(net "P0V9")
		)
		(pad "W13" smd circle
			(at -3.50012 2.500122)
			(size 0.4572 0.4572)
			(layers "F.Cu" "F.Mask" "F.Paste")
			(net "GND")
		)
		(pad "W14" smd circle
			(at -2.500122 2.500122)
			(size 0.4572 0.4572)
			(layers "F.Cu" "F.Mask" "F.Paste")
			(net "P0V9")
		)
		(pad "W15" smd circle
			(at -1.500124 2.500122)
			(size 0.4572 0.4572)
			(layers "F.Cu" "F.Mask" "F.Paste")
			(net "GND")
		)
		(pad "W16" smd circle
			(at -0.500126 2.500122)
			(size 0.4572 0.4572)
			(layers "F.Cu" "F.Mask" "F.Paste")
			(net "P0V9")
		)
		(pad "W17" smd circle
			(at 0.500126 2.500122)
			(size 0.4572 0.4572)
			(layers "F.Cu" "F.Mask" "F.Paste")
			(net "GND")
		)
		(pad "W18" smd circle
			(at 1.500124 2.500122)
			(size 0.4572 0.4572)
			(layers "F.Cu" "F.Mask" "F.Paste")
			(net "P0V9")
		)
		(pad "W19" smd circle
			(at 2.500122 2.500122)
			(size 0.4572 0.4572)
			(layers "F.Cu" "F.Mask" "F.Paste")
			(net "GND")
		)
		(pad "W20" smd circle
			(at 3.50012 2.500122)
			(size 0.4572 0.4572)
			(layers "F.Cu" "F.Mask" "F.Paste")
			(net "P0V9")
		)
		(pad "W21" smd circle
			(at 4.500118 2.500122)
			(size 0.4572 0.4572)
			(layers "F.Cu" "F.Mask" "F.Paste")
			(net "GND")
		)
		(pad "W22" smd circle
			(at 5.500116 2.500122)
			(size 0.4572 0.4572)
			(layers "F.Cu" "F.Mask" "F.Paste")
			(net "GB_VDDH")
		)
		(pad "W23" smd circle
			(at 6.500114 2.500122)
			(size 0.4572 0.4572)
			(layers "F.Cu" "F.Mask" "F.Paste")
			(net "GND")
		)
		(pad "W24" smd circle
			(at 7.500112 2.500122)
			(size 0.4572 0.4572)
			(layers "F.Cu" "F.Mask" "F.Paste")
			(net "GB_VDDA")
		)
		(pad "W25" smd circle
			(at 8.50011 2.500122)
			(size 0.4572 0.4572)
			(layers "F.Cu" "F.Mask" "F.Paste")
			(net "GND")
		)
		(pad "W26" smd circle
			(at 9.500108 2.500122)
			(size 0.4572 0.4572)
			(layers "F.Cu" "F.Mask" "F.Paste")
			(net "GB_VDDA")
		)
		(pad "W27" smd circle
			(at 10.500106 2.500122)
			(size 0.4572 0.4572)
			(layers "F.Cu" "F.Mask" "F.Paste")
			(net "PHY_DPB_TO_SCC_C_31_DN")
		)
		(pad "W28" smd circle
			(at 11.500104 2.500122)
			(size 0.4572 0.4572)
			(layers "F.Cu" "F.Mask" "F.Paste")
			(net "PHY_DPB_TO_SCC_C_31_DP")
		)
		(pad "W29" smd circle
			(at 12.500102 2.500122)
			(size 0.4572 0.4572)
			(layers "F.Cu" "F.Mask" "F.Paste")
			(net "GND")
		)
		(pad "W30" smd circle
			(at 13.5001 2.500122)
			(size 0.4572 0.4572)
			(layers "F.Cu" "F.Mask" "F.Paste")
			(net "GB_VDDA")
		)
		(pad "W31" smd circle
			(at 14.500098 2.500122)
			(size 0.4572 0.4572)
			(layers "F.Cu" "F.Mask" "F.Paste")
			(net "PHY_SCC_TO_DPB_31_DN")
		)
		(pad "W32" smd circle
			(at 15.500096 2.500122)
			(size 0.4572 0.4572)
			(layers "F.Cu" "F.Mask" "F.Paste")
			(net "PHY_SCC_TO_DPB_31_DP")
		)
		(pad "Y1" smd circle
			(at -15.500096 3.50012)
			(size 0.4572 0.4572)
			(layers "F.Cu" "F.Mask" "F.Paste")
			(net "DRIVE_12_ACT")
		)
		(pad "Y2" smd circle
			(at -14.500098 3.50012)
			(size 0.4572 0.4572)
			(layers "F.Cu" "F.Mask" "F.Paste")
			(net "DRIVE_14_ACT")
		)
		(pad "Y3" smd circle
			(at -13.5001 3.50012)
			(size 0.4572 0.4572)
			(layers "F.Cu" "F.Mask" "F.Paste")
			(net "GND")
		)
		(pad "Y4" smd circle
			(at -12.500102 3.50012)
			(size 0.4572 0.4572)
			(layers "F.Cu" "F.Mask" "F.Paste")
			(net "DRIVE_15_ACT")
		)
		(pad "Y5" smd circle
			(at -11.500104 3.50012)
			(size 0.4572 0.4572)
			(layers "F.Cu" "F.Mask" "F.Paste")
			(net "DRIVE_18_ACT")
		)
		(pad "Y6" smd circle
			(at -10.500106 3.50012)
			(size 0.4572 0.4572)
			(layers "F.Cu" "F.Mask" "F.Paste")
			(net "P1V8_E")
		)
		(pad "Y7" smd circle
			(at -9.500108 3.50012)
			(size 0.4572 0.4572)
			(layers "F.Cu" "F.Mask" "F.Paste")
			(net "DRIVE_17_ACT")
		)
		(pad "Y8" smd circle
			(at -8.50011 3.50012)
			(size 0.4572 0.4572)
			(layers "F.Cu" "F.Mask" "F.Paste")
			(net "DRIVE_26_ACT")
		)
		(pad "Y9" smd circle
			(at -7.500112 3.50012)
			(size 0.4572 0.4572)
			(layers "F.Cu" "F.Mask" "F.Paste")
			(net "DRIVE_31_ACT")
		)
		(pad "Y10" smd circle
			(at -6.500114 3.50012)
			(size 0.4572 0.4572)
			(layers "F.Cu" "F.Mask" "F.Paste")
			(net "XTAL_VDDA09")
		)
		(pad "Y11" smd circle
			(at -5.500116 3.50012)
			(size 0.4572 0.4572)
			(layers "F.Cu" "F.Mask" "F.Paste")
			(net "GND")
		)
		(pad "Y12" smd circle
			(at -4.500118 3.50012)
			(size 0.4572 0.4572)
			(layers "F.Cu" "F.Mask" "F.Paste")
			(net "GND")
		)
		(pad "Y13" smd circle
			(at -3.50012 3.50012)
			(size 0.4572 0.4572)
			(layers "F.Cu" "F.Mask" "F.Paste")
			(net "GND")
		)
		(pad "Y14" smd circle
			(at -2.500122 3.50012)
			(size 0.4572 0.4572)
			(layers "F.Cu" "F.Mask" "F.Paste")
			(net "GND")
		)
		(pad "Y15" smd circle
			(at -1.500124 3.50012)
			(size 0.4572 0.4572)
			(layers "F.Cu" "F.Mask" "F.Paste")
			(net "GND")
		)
		(pad "Y16" smd circle
			(at -0.500126 3.50012)
			(size 0.4572 0.4572)
			(layers "F.Cu" "F.Mask" "F.Paste")
			(net "GND")
		)
		(pad "Y17" smd circle
			(at 0.500126 3.50012)
			(size 0.4572 0.4572)
			(layers "F.Cu" "F.Mask" "F.Paste")
			(net "GND")
		)
		(pad "Y18" smd circle
			(at 1.500124 3.50012)
			(size 0.4572 0.4572)
			(layers "F.Cu" "F.Mask" "F.Paste")
			(net "GND")
		)
		(pad "Y19" smd circle
			(at 2.500122 3.50012)
			(size 0.4572 0.4572)
			(layers "F.Cu" "F.Mask" "F.Paste")
			(net "GND")
		)
		(pad "Y20" smd circle
			(at 3.50012 3.50012)
			(size 0.4572 0.4572)
			(layers "F.Cu" "F.Mask" "F.Paste")
			(net "GND")
		)
		(pad "Y21" smd circle
			(at 4.500118 3.50012)
			(size 0.4572 0.4572)
			(layers "F.Cu" "F.Mask" "F.Paste")
			(net "GND")
		)
		(pad "Y22" smd circle
			(at 5.500116 3.50012)
			(size 0.4572 0.4572)
			(layers "F.Cu" "F.Mask" "F.Paste")
			(net "GB_VDDH")
		)
		(pad "Y23" smd circle
			(at 6.500114 3.50012)
			(size 0.4572 0.4572)
			(layers "F.Cu" "F.Mask" "F.Paste")
			(net "GND")
		)
		(pad "Y24" smd circle
			(at 7.500112 3.50012)
			(size 0.4572 0.4572)
			(layers "F.Cu" "F.Mask" "F.Paste")
			(net "GND")
		)
		(pad "Y25" smd circle
			(at 8.50011 3.50012)
			(size 0.4572 0.4572)
			(layers "F.Cu" "F.Mask" "F.Paste")
			(net "GND")
		)
		(pad "Y26" smd circle
			(at 9.500108 3.50012)
			(size 0.4572 0.4572)
			(layers "F.Cu" "F.Mask" "F.Paste")
			(net "GND")
		)
		(pad "Y27" smd circle
			(at 10.500106 3.50012)
			(size 0.4572 0.4572)
			(layers "F.Cu" "F.Mask" "F.Paste")
			(net "PHY_DPB_TO_SCC_C_30_DN")
		)
		(pad "Y28" smd circle
			(at 11.500104 3.50012)
			(size 0.4572 0.4572)
			(layers "F.Cu" "F.Mask" "F.Paste")
			(net "PHY_DPB_TO_SCC_C_30_DP")
		)
		(pad "Y29" smd circle
			(at 12.500102 3.50012)
			(size 0.4572 0.4572)
			(layers "F.Cu" "F.Mask" "F.Paste")
			(net "GB_VDDA")
		)
		(pad "Y30" smd circle
			(at 13.5001 3.50012)
			(size 0.4572 0.4572)
			(layers "F.Cu" "F.Mask" "F.Paste")
			(net "PHY_SCC_TO_DPB_30_DN")
		)
		(pad "Y31" smd circle
			(at 14.500098 3.50012)
			(size 0.4572 0.4572)
			(layers "F.Cu" "F.Mask" "F.Paste")
			(net "PHY_SCC_TO_DPB_30_DP")
		)
		(pad "Y32" smd circle
			(at 15.500096 3.50012)
			(size 0.4572 0.4572)
			(layers "F.Cu" "F.Mask" "F.Paste")
			(net "GND")
		)
		(zone
			(layer "F.Cu")
			(hatch none 0.5)
			(connect_pads
				(clearance 0)
			)
			(min_thickness 0.25)
			(keepout
				(tracks allowed)
				(vias not_allowed)
				(pads allowed)
				(copperpour not_allowed)
				(footprints allowed)
			)
			(placement
				(enabled no)
				(sheetname "")
			)
			(fill
				(thermal_gap 0.5)
				(thermal_bridge_width 0.5)
				(island_removal_mode 0)
			)
			(polygon
				(pts
					(arc
						(start 99.880928 -79.500222)
						(mid 99.118928 -79.500222)
						(end 99.880928 -79.500222)
					)
				)
			)
		)
		(zone
			(layer "F.Cu")
			(hatch none 0.5)
			(connect_pads
				(clearance 0)
			)
			(min_thickness 0.25)
			(keepout
				(tracks allowed)
				(vias not_allowed)
				(pads allowed)
				(copperpour not_allowed)
				(footprints allowed)
			)
			(placement
				(enabled no)
				(sheetname "")
			)
			(fill
				(thermal_gap 0.5)
				(thermal_bridge_width 0.5)
				(island_removal_mode 0)
			)
			(polygon
				(pts
					(arc
						(start 99.880928 -78.500224)
						(mid 99.118928 -78.500224)
						(end 99.880928 -78.500224)
					)
				)
			)
		)
		(zone
			(layer "F.Cu")
			(hatch none 0.5)
			(connect_pads
				(clearance 0)
			)
			(min_thickness 0.25)
			(keepout
				(tracks allowed)
				(vias not_allowed)
				(pads allowed)
				(copperpour not_allowed)
				(footprints allowed)
			)
			(placement
				(enabled no)
				(sheetname "")
			)
			(fill
				(thermal_gap 0.5)
				(thermal_bridge_width 0.5)
				(island_removal_mode 0)
			)
			(polygon
				(pts
					(arc
						(start 99.880928 -77.500226)
						(mid 99.118928 -77.500226)
						(end 99.880928 -77.500226)
					)
				)
			)
		)
		(zone
			(layer "F.Cu")
			(hatch none 0.5)
			(connect_pads
				(clearance 0)
			)
			(min_thickness 0.25)
			(keepout
				(tracks allowed)
				(vias not_allowed)
				(pads allowed)
				(copperpour not_allowed)
				(footprints allowed)
			)
			(placement
				(enabled no)
				(sheetname "")
			)
			(fill
				(thermal_gap 0.5)
				(thermal_bridge_width 0.5)
				(island_removal_mode 0)
			)
			(polygon
				(pts
					(arc
						(start 99.880928 -76.500228)
						(mid 99.118928 -76.500228)
						(end 99.880928 -76.500228)
					)
				)
			)
		)
		(zone
			(layer "F.Cu")
			(hatch none 0.5)
			(connect_pads
				(clearance 0)
			)
			(min_thickness 0.25)
			(keepout
				(tracks allowed)
				(vias not_allowed)
				(pads allowed)
				(copperpour not_allowed)
				(footprints allowed)
			)
			(placement
				(enabled no)
				(sheetname "")
			)
			(fill
				(thermal_gap 0.5)
				(thermal_bridge_width 0.5)
				(island_removal_mode 0)
			)
			(polygon
				(pts
					(arc
						(start 99.880928 -75.50023)
						(mid 99.118928 -75.50023)
						(end 99.880928 -75.50023)
					)
				)
			)
		)
		(zone
			(layer "F.Cu")
			(hatch none 0.5)
			(connect_pads
				(clearance 0)
			)
			(min_thickness 0.25)
			(keepout
				(tracks allowed)
				(vias not_allowed)
				(pads allowed)
				(copperpour not_allowed)
				(footprints allowed)
			)
			(placement
				(enabled no)
				(sheetname "")
			)
			(fill
				(thermal_gap 0.5)
				(thermal_bridge_width 0.5)
				(island_removal_mode 0)
			)
			(polygon
				(pts
					(arc
						(start 99.880928 -74.500232)
						(mid 99.118928 -74.500232)
						(end 99.880928 -74.500232)
					)
				)
			)
		)
		(zone
			(layer "F.Cu")
			(hatch none 0.5)
			(connect_pads
				(clearance 0)
			)
			(min_thickness 0.25)
			(keepout
				(tracks allowed)
				(vias not_allowed)
				(pads allowed)
				(copperpour not_allowed)
				(footprints allowed)
			)
			(placement
				(enabled no)
				(sheetname "")
			)
			(fill
				(thermal_gap 0.5)
				(thermal_bridge_width 0.5)
				(island_removal_mode 0)
			)
			(polygon
				(pts
					(arc
						(start 99.880928 -73.500234)
						(mid 99.118928 -73.500234)
						(end 99.880928 -73.500234)
					)
				)
			)
		)
		(zone
			(layer "F.Cu")
			(hatch none 0.5)
			(connect_pads
				(clearance 0)
			)
			(min_thickness 0.25)
			(keepout
				(tracks allowed)
				(vias not_allowed)
				(pads allowed)
				(copperpour not_allowed)
				(footprints allowed)
			)
			(placement
				(enabled no)
				(sheetname "")
			)
			(fill
				(thermal_gap 0.5)
				(thermal_bridge_width 0.5)
				(island_removal_mode 0)
			)
			(polygon
				(pts
					(arc
						(start 99.880928 -72.500236)
						(mid 99.118928 -72.500236)
						(end 99.880928 -72.500236)
					)
				)
			)
		)
		(zone
			(layer "F.Cu")
			(hatch none 0.5)
			(connect_pads
				(clearance 0)
			)
			(min_thickness 0.25)
			(keepout
				(tracks allowed)
				(vias not_allowed)
				(pads allowed)
				(copperpour not_allowed)
				(footprints allowed)
			)
			(placement
				(enabled no)
				(sheetname "")
			)
			(fill
				(thermal_gap 0.5)
				(thermal_bridge_width 0.5)
				(island_removal_mode 0)
			)
			(polygon
				(pts
					(arc
						(start 99.880928 -71.500238)
						(mid 99.118928 -71.500238)
						(end 99.880928 -71.500238)
					)
				)
			)
		)
		(zone
			(layer "F.Cu")
			(hatch none 0.5)
			(connect_pads
				(clearance 0)
			)
			(min_thickness 0.25)
			(keepout
				(tracks allowed)
				(vias not_allowed)
				(pads allowed)
				(copperpour not_allowed)
				(footprints allowed)
			)
			(placement
				(enabled no)
				(sheetname "")
			)
			(fill
				(thermal_gap 0.5)
				(thermal_bridge_width 0.5)
				(island_removal_mode 0)
			)
			(polygon
				(pts
					(arc
						(start 99.880928 -70.50024)
						(mid 99.118928 -70.50024)
						(end 99.880928 -70.50024)
					)
				)
			)
		)
		(zone
			(layer "F.Cu")
			(hatch none 0.5)
			(connect_pads
				(clearance 0)
			)
			(min_thickness 0.25)
			(keepout
				(tracks allowed)
				(vias not_allowed)
				(pads allowed)
				(copperpour not_allowed)
				(footprints allowed)
			)
			(placement
				(enabled no)
				(sheetname "")
			)
			(fill
				(thermal_gap 0.5)
				(thermal_bridge_width 0.5)
				(island_removal_mode 0)
			)
			(polygon
				(pts
					(arc
						(start 99.880928 -69.500242)
						(mid 99.118928 -69.500242)
						(end 99.880928 -69.500242)
					)
				)
			)
		)
		(zone
			(layer "F.Cu")
			(hatch none 0.5)
			(connect_pads
				(clearance 0)
			)
			(min_thickness 0.25)
			(keepout
				(tracks allowed)
				(vias not_allowed)
				(pads allowed)
				(copperpour not_allowed)
				(footprints allowed)
			)
			(placement
				(enabled no)
				(sheetname "")
			)
			(fill
				(thermal_gap 0.5)
				(thermal_bridge_width 0.5)
				(island_removal_mode 0)
			)
			(polygon
				(pts
					(arc
						(start 99.880928 -68.500244)
						(mid 99.118928 -68.500244)
						(end 99.880928 -68.500244)
					)
				)
			)
		)
		(zone
			(layer "F.Cu")
			(hatch none 0.5)
			(connect_pads
				(clearance 0)
			)
			(min_thickness 0.25)
			(keepout
				(tracks allowed)
				(vias not_allowed)
				(pads allowed)
				(copperpour not_allowed)
				(footprints allowed)
			)
			(placement
				(enabled no)
				(sheetname "")
			)
			(fill
				(thermal_gap 0.5)
				(thermal_bridge_width 0.5)
				(island_removal_mode 0)
			)
			(polygon
				(pts
					(arc
						(start 99.880928 -67.500246)
						(mid 99.118928 -67.500246)
						(end 99.880928 -67.500246)
					)
				)
			)
		)
		(zone
			(layer "F.Cu")
			(hatch none 0.5)
			(connect_pads
				(clearance 0)
			)
			(min_thickness 0.25)
			(keepout
				(tracks allowed)
				(vias not_allowed)
				(pads allowed)
				(copperpour not_allowed)
				(footprints allowed)
			)
			(placement
				(enabled no)
				(sheetname "")
			)
			(fill
				(thermal_gap 0.5)
				(thermal_bridge_width 0.5)
				(island_removal_mode 0)
			)
			(polygon
				(pts
					(arc
						(start 99.880928 -66.499994)
						(mid 99.118928 -66.499994)
						(end 99.880928 -66.499994)
					)
				)
			)
		)
		(zone
			(layer "F.Cu")
			(hatch none 0.5)
			(connect_pads
				(clearance 0)
			)
			(min_thickness 0.25)
			(keepout
				(tracks allowed)
				(vias not_allowed)
				(pads allowed)
				(copperpour not_allowed)
				(footprints allowed)
			)
			(placement
				(enabled no)
				(sheetname "")
			)
			(fill
				(thermal_gap 0.5)
				(thermal_bridge_width 0.5)
				(island_removal_mode 0)
			)
			(polygon
				(pts
					(arc
						(start 99.880928 -65.499996)
						(mid 99.118928 -65.499996)
						(end 99.880928 -65.499996)
					)
				)
			)
		)
		(zone
			(layer "F.Cu")
			(hatch none 0.5)
			(connect_pads
				(clearance 0)
			)
			(min_thickness 0.25)
			(keepout
				(tracks allowed)
				(vias not_allowed)
				(pads allowed)
				(copperpour not_allowed)
				(footprints allowed)
			)
			(placement
				(enabled no)
				(sheetname "")
			)
			(fill
				(thermal_gap 0.5)
				(thermal_bridge_width 0.5)
				(island_removal_mode 0)
			)
			(polygon
				(pts
					(arc
						(start 99.880928 -64.499998)
						(mid 99.118928 -64.499998)
						(end 99.880928 -64.499998)
					)
				)
			)
		)
		(zone
			(layer "F.Cu")
			(hatch none 0.5)
			(connect_pads
				(clearance 0)
			)
			(min_thickness 0.25)
			(keepout
				(tracks allowed)
				(vias not_allowed)
				(pads allowed)
				(copperpour not_allowed)
				(footprints allowed)
			)
			(placement
				(enabled no)
				(sheetname "")
			)
			(fill
				(thermal_gap 0.5)
				(thermal_bridge_width 0.5)
				(island_removal_mode 0)
			)
			(polygon
				(pts
					(arc
						(start 99.880928 -63.5)
						(mid 99.118928 -63.5)
						(end 99.880928 -63.5)
					)
				)
			)
		)
		(zone
			(layer "F.Cu")
			(hatch none 0.5)
			(connect_pads
				(clearance 0)
			)
			(min_thickness 0.25)
			(keepout
				(tracks allowed)
				(vias not_allowed)
				(pads allowed)
				(copperpour not_allowed)
				(footprints allowed)
			)
			(placement
				(enabled no)
				(sheetname "")
			)
			(fill
				(thermal_gap 0.5)
				(thermal_bridge_width 0.5)
				(island_removal_mode 0)
			)
			(polygon
				(pts
					(arc
						(start 99.880928 -62.500002)
						(mid 99.118928 -62.500002)
						(end 99.880928 -62.500002)
					)
				)
			)
		)
		(zone
			(layer "F.Cu")
			(hatch none 0.5)
			(connect_pads
				(clearance 0)
			)
			(min_thickness 0.25)
			(keepout
				(tracks allowed)
				(vias not_allowed)
				(pads allowed)
				(copperpour not_allowed)
				(footprints allowed)
			)
			(placement
				(enabled no)
				(sheetname "")
			)
			(fill
				(thermal_gap 0.5)
				(thermal_bridge_width 0.5)
				(island_removal_mode 0)
			)
			(polygon
				(pts
					(arc
						(start 99.880928 -61.500004)
						(mid 99.118928 -61.500004)
						(end 99.880928 -61.500004)
					)
				)
			)
		)
		(zone
			(layer "F.Cu")
			(hatch none 0.5)
			(connect_pads
				(clearance 0)
			)
			(min_thickness 0.25)
			(keepout
				(tracks allowed)
				(vias not_allowed)
				(pads allowed)
				(copperpour not_allowed)
				(footprints allowed)
			)
			(placement
				(enabled no)
				(sheetname "")
			)
			(fill
				(thermal_gap 0.5)
				(thermal_bridge_width 0.5)
				(island_removal_mode 0)
			)
			(polygon
				(pts
					(arc
						(start 99.880928 -60.500006)
						(mid 99.118928 -60.500006)
						(end 99.880928 -60.500006)
					)
				)
			)
		)
		(zone
			(layer "F.Cu")
			(hatch none 0.5)
			(connect_pads
				(clearance 0)
			)
			(min_thickness 0.25)
			(keepout
				(tracks allowed)
				(vias not_allowed)
				(pads allowed)
				(copperpour not_allowed)
				(footprints allowed)
			)
			(placement
				(enabled no)
				(sheetname "")
			)
			(fill
				(thermal_gap 0.5)
				(thermal_bridge_width 0.5)
				(island_removal_mode 0)
			)
			(polygon
				(pts
					(arc
						(start 99.880928 -59.500008)
						(mid 99.118928 -59.500008)
						(end 99.880928 -59.500008)
					)
				)
			)
		)
		(zone
			(layer "F.Cu")
			(hatch none 0.5)
			(connect_pads
				(clearance 0)
			)
			(min_thickness 0.25)
			(keepout
				(tracks allowed)
				(vias not_allowed)
				(pads allowed)
				(copperpour not_allowed)
				(footprints allowed)
			)
			(placement
				(enabled no)
				(sheetname "")
			)
			(fill
				(thermal_gap 0.5)
				(thermal_bridge_width 0.5)
				(island_removal_mode 0)
			)
			(polygon
				(pts
					(arc
						(start 99.880928 -58.50001)
						(mid 99.118928 -58.50001)
						(end 99.880928 -58.50001)
					)
				)
			)
		)
		(zone
			(layer "F.Cu")
			(hatch none 0.5)
			(connect_pads
				(clearance 0)
			)
			(min_thickness 0.25)
			(keepout
				(tracks allowed)
				(vias not_allowed)
				(pads allowed)
				(copperpour not_allowed)
				(footprints allowed)
			)
			(placement
				(enabled no)
				(sheetname "")
			)
			(fill
				(thermal_gap 0.5)
				(thermal_bridge_width 0.5)
				(island_removal_mode 0)
			)
			(polygon
				(pts
					(arc
						(start 99.880928 -57.500012)
						(mid 99.118928 -57.500012)
						(end 99.880928 -57.500012)
					)
				)
			)
		)
		(zone
			(layer "F.Cu")
			(hatch none 0.5)
			(connect_pads
				(clearance 0)
			)
			(min_thickness 0.25)
			(keepout
				(tracks allowed)
				(vias not_allowed)
				(pads allowed)
				(copperpour not_allowed)
				(footprints allowed)
			)
			(placement
				(enabled no)
				(sheetname "")
			)
			(fill
				(thermal_gap 0.5)
				(thermal_bridge_width 0.5)
				(island_removal_mode 0)
			)
			(polygon
				(pts
					(arc
						(start 99.880928 -56.500014)
						(mid 99.118928 -56.500014)
						(end 99.880928 -56.500014)
					)
				)
			)
		)
		(zone
			(layer "F.Cu")
			(hatch none 0.5)
			(connect_pads
				(clearance 0)
			)
			(min_thickness 0.25)
			(keepout
				(tracks allowed)
				(vias not_allowed)
				(pads allowed)
				(copperpour not_allowed)
				(footprints allowed)
			)
			(placement
				(enabled no)
				(sheetname "")
			)
			(fill
				(thermal_gap 0.5)
				(thermal_bridge_width 0.5)
				(island_removal_mode 0)
			)
			(polygon
				(pts
					(arc
						(start 99.880928 -55.500016)
						(mid 99.118928 -55.500016)
						(end 99.880928 -55.500016)
					)
				)
			)
		)
		(zone
			(layer "F.Cu")
			(hatch none 0.5)
			(connect_pads
				(clearance 0)
			)
			(min_thickness 0.25)
			(keepout
				(tracks allowed)
				(vias not_allowed)
				(pads allowed)
				(copperpour not_allowed)
				(footprints allowed)
			)
			(placement
				(enabled no)
				(sheetname "")
			)
			(fill
				(thermal_gap 0.5)
				(thermal_bridge_width 0.5)
				(island_removal_mode 0)
			)
			(polygon
				(pts
					(arc
						(start 99.880928 -54.500018)
						(mid 99.118928 -54.500018)
						(end 99.880928 -54.500018)
					)
				)
			)
		)
		(zone
			(layer "F.Cu")
			(hatch none 0.5)
			(connect_pads
				(clearance 0)
			)
			(min_thickness 0.25)
			(keepout
				(tracks allowed)
				(vias not_allowed)
				(pads allowed)
				(copperpour not_allowed)
				(footprints allowed)
			)
			(placement
				(enabled no)
				(sheetname "")
			)
			(fill
				(thermal_gap 0.5)
				(thermal_bridge_width 0.5)
				(island_removal_mode 0)
			)
			(polygon
				(pts
					(arc
						(start 100.880926 -79.500222)
						(mid 100.118926 -79.500222)
						(end 100.880926 -79.500222)
					)
				)
			)
		)
		(zone
			(layer "F.Cu")
			(hatch none 0.5)
			(connect_pads
				(clearance 0)
			)
			(min_thickness 0.25)
			(keepout
				(tracks allowed)
				(vias not_allowed)
				(pads allowed)
				(copperpour not_allowed)
				(footprints allowed)
			)
			(placement
				(enabled no)
				(sheetname "")
			)
			(fill
				(thermal_gap 0.5)
				(thermal_bridge_width 0.5)
				(island_removal_mode 0)
			)
			(polygon
				(pts
					(arc
						(start 100.880926 -78.500224)
						(mid 100.118926 -78.500224)
						(end 100.880926 -78.500224)
					)
				)
			)
		)
		(zone
			(layer "F.Cu")
			(hatch none 0.5)
			(connect_pads
				(clearance 0)
			)
			(min_thickness 0.25)
			(keepout
				(tracks allowed)
				(vias not_allowed)
				(pads allowed)
				(copperpour not_allowed)
				(footprints allowed)
			)
			(placement
				(enabled no)
				(sheetname "")
			)
			(fill
				(thermal_gap 0.5)
				(thermal_bridge_width 0.5)
				(island_removal_mode 0)
			)
			(polygon
				(pts
					(arc
						(start 100.880926 -77.500226)
						(mid 100.118926 -77.500226)
						(end 100.880926 -77.500226)
					)
				)
			)
		)
		(zone
			(layer "F.Cu")
			(hatch none 0.5)
			(connect_pads
				(clearance 0)
			)
			(min_thickness 0.25)
			(keepout
				(tracks allowed)
				(vias not_allowed)
				(pads allowed)
				(copperpour not_allowed)
				(footprints allowed)
			)
			(placement
				(enabled no)
				(sheetname "")
			)
			(fill
				(thermal_gap 0.5)
				(thermal_bridge_width 0.5)
				(island_removal_mode 0)
			)
			(polygon
				(pts
					(arc
						(start 100.880926 -76.500228)
						(mid 100.118926 -76.500228)
						(end 100.880926 -76.500228)
					)
				)
			)
		)
		(zone
			(layer "F.Cu")
			(hatch none 0.5)
			(connect_pads
				(clearance 0)
			)
			(min_thickness 0.25)
			(keepout
				(tracks allowed)
				(vias not_allowed)
				(pads allowed)
				(copperpour not_allowed)
				(footprints allowed)
			)
			(placement
				(enabled no)
				(sheetname "")
			)
			(fill
				(thermal_gap 0.5)
				(thermal_bridge_width 0.5)
				(island_removal_mode 0)
			)
			(polygon
				(pts
					(arc
						(start 100.880926 -75.50023)
						(mid 100.118926 -75.50023)
						(end 100.880926 -75.50023)
					)
				)
			)
		)
		(zone
			(layer "F.Cu")
			(hatch none 0.5)
			(connect_pads
				(clearance 0)
			)
			(min_thickness 0.25)
			(keepout
				(tracks allowed)
				(vias not_allowed)
				(pads allowed)
				(copperpour not_allowed)
				(footprints allowed)
			)
			(placement
				(enabled no)
				(sheetname "")
			)
			(fill
				(thermal_gap 0.5)
				(thermal_bridge_width 0.5)
				(island_removal_mode 0)
			)
			(polygon
				(pts
					(arc
						(start 100.880926 -74.500232)
						(mid 100.118926 -74.500232)
						(end 100.880926 -74.500232)
					)
				)
			)
		)
		(zone
			(layer "F.Cu")
			(hatch none 0.5)
			(connect_pads
				(clearance 0)
			)
			(min_thickness 0.25)
			(keepout
				(tracks allowed)
				(vias not_allowed)
				(pads allowed)
				(copperpour not_allowed)
				(footprints allowed)
			)
			(placement
				(enabled no)
				(sheetname "")
			)
			(fill
				(thermal_gap 0.5)
				(thermal_bridge_width 0.5)
				(island_removal_mode 0)
			)
			(polygon
				(pts
					(arc
						(start 100.880926 -73.500234)
						(mid 100.118926 -73.500234)
						(end 100.880926 -73.500234)
					)
				)
			)
		)
		(zone
			(layer "F.Cu")
			(hatch none 0.5)
			(connect_pads
				(clearance 0)
			)
			(min_thickness 0.25)
			(keepout
				(tracks allowed)
				(vias not_allowed)
				(pads allowed)
				(copperpour not_allowed)
				(footprints allowed)
			)
			(placement
				(enabled no)
				(sheetname "")
			)
			(fill
				(thermal_gap 0.5)
				(thermal_bridge_width 0.5)
				(island_removal_mode 0)
			)
			(polygon
				(pts
					(arc
						(start 100.880926 -72.500236)
						(mid 100.118926 -72.500236)
						(end 100.880926 -72.500236)
					)
				)
			)
		)
		(zone
			(layer "F.Cu")
			(hatch none 0.5)
			(connect_pads
				(clearance 0)
			)
			(min_thickness 0.25)
			(keepout
				(tracks allowed)
				(vias not_allowed)
				(pads allowed)
				(copperpour not_allowed)
				(footprints allowed)
			)
			(placement
				(enabled no)
				(sheetname "")
			)
			(fill
				(thermal_gap 0.5)
				(thermal_bridge_width 0.5)
				(island_removal_mode 0)
			)
			(polygon
				(pts
					(arc
						(start 100.880926 -71.500238)
						(mid 100.118926 -71.500238)
						(end 100.880926 -71.500238)
					)
				)
			)
		)
		(zone
			(layer "F.Cu")
			(hatch none 0.5)
			(connect_pads
				(clearance 0)
			)
			(min_thickness 0.25)
			(keepout
				(tracks allowed)
				(vias not_allowed)
				(pads allowed)
				(copperpour not_allowed)
				(footprints allowed)
			)
			(placement
				(enabled no)
				(sheetname "")
			)
			(fill
				(thermal_gap 0.5)
				(thermal_bridge_width 0.5)
				(island_removal_mode 0)
			)
			(polygon
				(pts
					(arc
						(start 100.880926 -70.50024)
						(mid 100.118926 -70.50024)
						(end 100.880926 -70.50024)
					)
				)
			)
		)
		(zone
			(layer "F.Cu")
			(hatch none 0.5)
			(connect_pads
				(clearance 0)
			)
			(min_thickness 0.25)
			(keepout
				(tracks allowed)
				(vias not_allowed)
				(pads allowed)
				(copperpour not_allowed)
				(footprints allowed)
			)
			(placement
				(enabled no)
				(sheetname "")
			)
			(fill
				(thermal_gap 0.5)
				(thermal_bridge_width 0.5)
				(island_removal_mode 0)
			)
			(polygon
				(pts
					(arc
						(start 100.880926 -69.500242)
						(mid 100.118926 -69.500242)
						(end 100.880926 -69.500242)
					)
				)
			)
		)
		(zone
			(layer "F.Cu")
			(hatch none 0.5)
			(connect_pads
				(clearance 0)
			)
			(min_thickness 0.25)
			(keepout
				(tracks allowed)
				(vias not_allowed)
				(pads allowed)
				(copperpour not_allowed)
				(footprints allowed)
			)
			(placement
				(enabled no)
				(sheetname "")
			)
			(fill
				(thermal_gap 0.5)
				(thermal_bridge_width 0.5)
				(island_removal_mode 0)
			)
			(polygon
				(pts
					(arc
						(start 100.880926 -68.500244)
						(mid 100.118926 -68.500244)
						(end 100.880926 -68.500244)
					)
				)
			)
		)
		(zone
			(layer "F.Cu")
			(hatch none 0.5)
			(connect_pads
				(clearance 0)
			)
			(min_thickness 0.25)
			(keepout
				(tracks allowed)
				(vias not_allowed)
				(pads allowed)
				(copperpour not_allowed)
				(footprints allowed)
			)
			(placement
				(enabled no)
				(sheetname "")
			)
			(fill
				(thermal_gap 0.5)
				(thermal_bridge_width 0.5)
				(island_removal_mode 0)
			)
			(polygon
				(pts
					(arc
						(start 100.880926 -67.500246)
						(mid 100.118926 -67.500246)
						(end 100.880926 -67.500246)
					)
				)
			)
		)
		(zone
			(layer "F.Cu")
			(hatch none 0.5)
			(connect_pads
				(clearance 0)
			)
			(min_thickness 0.25)
			(keepout
				(tracks allowed)
				(vias not_allowed)
				(pads allowed)
				(copperpour not_allowed)
				(footprints allowed)
			)
			(placement
				(enabled no)
				(sheetname "")
			)
			(fill
				(thermal_gap 0.5)
				(thermal_bridge_width 0.5)
				(island_removal_mode 0)
			)
			(polygon
				(pts
					(arc
						(start 100.880926 -66.499994)
						(mid 100.118926 -66.499994)
						(end 100.880926 -66.499994)
					)
				)
			)
		)
		(zone
			(layer "F.Cu")
			(hatch none 0.5)
			(connect_pads
				(clearance 0)
			)
			(min_thickness 0.25)
			(keepout
				(tracks allowed)
				(vias not_allowed)
				(pads allowed)
				(copperpour not_allowed)
				(footprints allowed)
			)
			(placement
				(enabled no)
				(sheetname "")
			)
			(fill
				(thermal_gap 0.5)
				(thermal_bridge_width 0.5)
				(island_removal_mode 0)
			)
			(polygon
				(pts
					(arc
						(start 100.880926 -65.499996)
						(mid 100.118926 -65.499996)
						(end 100.880926 -65.499996)
					)
				)
			)
		)
		(zone
			(layer "F.Cu")
			(hatch none 0.5)
			(connect_pads
				(clearance 0)
			)
			(min_thickness 0.25)
			(keepout
				(tracks allowed)
				(vias not_allowed)
				(pads allowed)
				(copperpour not_allowed)
				(footprints allowed)
			)
			(placement
				(enabled no)
				(sheetname "")
			)
			(fill
				(thermal_gap 0.5)
				(thermal_bridge_width 0.5)
				(island_removal_mode 0)
			)
			(polygon
				(pts
					(arc
						(start 100.880926 -64.499998)
						(mid 100.118926 -64.499998)
						(end 100.880926 -64.499998)
					)
				)
			)
		)
		(zone
			(layer "F.Cu")
			(hatch none 0.5)
			(connect_pads
				(clearance 0)
			)
			(min_thickness 0.25)
			(keepout
				(tracks allowed)
				(vias not_allowed)
				(pads allowed)
				(copperpour not_allowed)
				(footprints allowed)
			)
			(placement
				(enabled no)
				(sheetname "")
			)
			(fill
				(thermal_gap 0.5)
				(thermal_bridge_width 0.5)
				(island_removal_mode 0)
			)
			(polygon
				(pts
					(arc
						(start 100.880926 -63.5)
						(mid 100.118926 -63.5)
						(end 100.880926 -63.5)
					)
				)
			)
		)
		(zone
			(layer "F.Cu")
			(hatch none 0.5)
			(connect_pads
				(clearance 0)
			)
			(min_thickness 0.25)
			(keepout
				(tracks allowed)
				(vias not_allowed)
				(pads allowed)
				(copperpour not_allowed)
				(footprints allowed)
			)
			(placement
				(enabled no)
				(sheetname "")
			)
			(fill
				(thermal_gap 0.5)
				(thermal_bridge_width 0.5)
				(island_removal_mode 0)
			)
			(polygon
				(pts
					(arc
						(start 100.880926 -62.500002)
						(mid 100.118926 -62.500002)
						(end 100.880926 -62.500002)
					)
				)
			)
		)
		(zone
			(layer "F.Cu")
			(hatch none 0.5)
			(connect_pads
				(clearance 0)
			)
			(min_thickness 0.25)
			(keepout
				(tracks allowed)
				(vias not_allowed)
				(pads allowed)
				(copperpour not_allowed)
				(footprints allowed)
			)
			(placement
				(enabled no)
				(sheetname "")
			)
			(fill
				(thermal_gap 0.5)
				(thermal_bridge_width 0.5)
				(island_removal_mode 0)
			)
			(polygon
				(pts
					(arc
						(start 100.880926 -61.500004)
						(mid 100.118926 -61.500004)
						(end 100.880926 -61.500004)
					)
				)
			)
		)
		(zone
			(layer "F.Cu")
			(hatch none 0.5)
			(connect_pads
				(clearance 0)
			)
			(min_thickness 0.25)
			(keepout
				(tracks allowed)
				(vias not_allowed)
				(pads allowed)
				(copperpour not_allowed)
				(footprints allowed)
			)
			(placement
				(enabled no)
				(sheetname "")
			)
			(fill
				(thermal_gap 0.5)
				(thermal_bridge_width 0.5)
				(island_removal_mode 0)
			)
			(polygon
				(pts
					(arc
						(start 100.880926 -60.500006)
						(mid 100.118926 -60.500006)
						(end 100.880926 -60.500006)
					)
				)
			)
		)
		(zone
			(layer "F.Cu")
			(hatch none 0.5)
			(connect_pads
				(clearance 0)
			)
			(min_thickness 0.25)
			(keepout
				(tracks allowed)
				(vias not_allowed)
				(pads allowed)
				(copperpour not_allowed)
				(footprints allowed)
			)
			(placement
				(enabled no)
				(sheetname "")
			)
			(fill
				(thermal_gap 0.5)
				(thermal_bridge_width 0.5)
				(island_removal_mode 0)
			)
			(polygon
				(pts
					(arc
						(start 100.880926 -59.500008)
						(mid 100.118926 -59.500008)
						(end 100.880926 -59.500008)
					)
				)
			)
		)
		(zone
			(layer "F.Cu")
			(hatch none 0.5)
			(connect_pads
				(clearance 0)
			)
			(min_thickness 0.25)
			(keepout
				(tracks allowed)
				(vias not_allowed)
				(pads allowed)
				(copperpour not_allowed)
				(footprints allowed)
			)
			(placement
				(enabled no)
				(sheetname "")
			)
			(fill
				(thermal_gap 0.5)
				(thermal_bridge_width 0.5)
				(island_removal_mode 0)
			)
			(polygon
				(pts
					(arc
						(start 100.880926 -58.50001)
						(mid 100.118926 -58.50001)
						(end 100.880926 -58.50001)
					)
				)
			)
		)
		(zone
			(layer "F.Cu")
			(hatch none 0.5)
			(connect_pads
				(clearance 0)
			)
			(min_thickness 0.25)
			(keepout
				(tracks allowed)
				(vias not_allowed)
				(pads allowed)
				(copperpour not_allowed)
				(footprints allowed)
			)
			(placement
				(enabled no)
				(sheetname "")
			)
			(fill
				(thermal_gap 0.5)
				(thermal_bridge_width 0.5)
				(island_removal_mode 0)
			)
			(polygon
				(pts
					(arc
						(start 100.880926 -57.500012)
						(mid 100.118926 -57.500012)
						(end 100.880926 -57.500012)
					)
				)
			)
		)
		(zone
			(layer "F.Cu")
			(hatch none 0.5)
			(connect_pads
				(clearance 0)
			)
			(min_thickness 0.25)
			(keepout
				(tracks allowed)
				(vias not_allowed)
				(pads allowed)
				(copperpour not_allowed)
				(footprints allowed)
			)
			(placement
				(enabled no)
				(sheetname "")
			)
			(fill
				(thermal_gap 0.5)
				(thermal_bridge_width 0.5)
				(island_removal_mode 0)
			)
			(polygon
				(pts
					(arc
						(start 100.880926 -56.500014)
						(mid 100.118926 -56.500014)
						(end 100.880926 -56.500014)
					)
				)
			)
		)
		(zone
			(layer "F.Cu")
			(hatch none 0.5)
			(connect_pads
				(clearance 0)
			)
			(min_thickness 0.25)
			(keepout
				(tracks allowed)
				(vias not_allowed)
				(pads allowed)
				(copperpour not_allowed)
				(footprints allowed)
			)
			(placement
				(enabled no)
				(sheetname "")
			)
			(fill
				(thermal_gap 0.5)
				(thermal_bridge_width 0.5)
				(island_removal_mode 0)
			)
			(polygon
				(pts
					(arc
						(start 100.880926 -55.500016)
						(mid 100.118926 -55.500016)
						(end 100.880926 -55.500016)
					)
				)
			)
		)
		(zone
			(layer "F.Cu")
			(hatch none 0.5)
			(connect_pads
				(clearance 0)
			)
			(min_thickness 0.25)
			(keepout
				(tracks allowed)
				(vias not_allowed)
				(pads allowed)
				(copperpour not_allowed)
				(footprints allowed)
			)
			(placement
				(enabled no)
				(sheetname "")
			)
			(fill
				(thermal_gap 0.5)
				(thermal_bridge_width 0.5)
				(island_removal_mode 0)
			)
			(polygon
				(pts
					(arc
						(start 100.880926 -54.500018)
						(mid 100.118926 -54.500018)
						(end 100.880926 -54.500018)
					)
				)
			)
		)
		(zone
			(layer "F.Cu")
			(hatch none 0.5)
			(connect_pads
				(clearance 0)
			)
			(min_thickness 0.25)
			(keepout
				(tracks allowed)
				(vias not_allowed)
				(pads allowed)
				(copperpour not_allowed)
				(footprints allowed)
			)
			(placement
				(enabled no)
				(sheetname "")
			)
			(fill
				(thermal_gap 0.5)
				(thermal_bridge_width 0.5)
				(island_removal_mode 0)
			)
			(polygon
				(pts
					(arc
						(start 101.880924 -79.500222)
						(mid 101.118924 -79.500222)
						(end 101.880924 -79.500222)
					)
				)
			)
		)
		(zone
			(layer "F.Cu")
			(hatch none 0.5)
			(connect_pads
				(clearance 0)
			)
			(min_thickness 0.25)
			(keepout
				(tracks allowed)
				(vias not_allowed)
				(pads allowed)
				(copperpour not_allowed)
				(footprints allowed)
			)
			(placement
				(enabled no)
				(sheetname "")
			)
			(fill
				(thermal_gap 0.5)
				(thermal_bridge_width 0.5)
				(island_removal_mode 0)
			)
			(polygon
				(pts
					(arc
						(start 101.880924 -78.500224)
						(mid 101.118924 -78.500224)
						(end 101.880924 -78.500224)
					)
				)
			)
		)
		(zone
			(layer "F.Cu")
			(hatch none 0.5)
			(connect_pads
				(clearance 0)
			)
			(min_thickness 0.25)
			(keepout
				(tracks allowed)
				(vias not_allowed)
				(pads allowed)
				(copperpour not_allowed)
				(footprints allowed)
			)
			(placement
				(enabled no)
				(sheetname "")
			)
			(fill
				(thermal_gap 0.5)
				(thermal_bridge_width 0.5)
				(island_removal_mode 0)
			)
			(polygon
				(pts
					(arc
						(start 101.880924 -77.500226)
						(mid 101.118924 -77.500226)
						(end 101.880924 -77.500226)
					)
				)
			)
		)
		(zone
			(layer "F.Cu")
			(hatch none 0.5)
			(connect_pads
				(clearance 0)
			)
			(min_thickness 0.25)
			(keepout
				(tracks allowed)
				(vias not_allowed)
				(pads allowed)
				(copperpour not_allowed)
				(footprints allowed)
			)
			(placement
				(enabled no)
				(sheetname "")
			)
			(fill
				(thermal_gap 0.5)
				(thermal_bridge_width 0.5)
				(island_removal_mode 0)
			)
			(polygon
				(pts
					(arc
						(start 101.880924 -76.500228)
						(mid 101.118924 -76.500228)
						(end 101.880924 -76.500228)
					)
				)
			)
		)
		(zone
			(layer "F.Cu")
			(hatch none 0.5)
			(connect_pads
				(clearance 0)
			)
			(min_thickness 0.25)
			(keepout
				(tracks allowed)
				(vias not_allowed)
				(pads allowed)
				(copperpour not_allowed)
				(footprints allowed)
			)
			(placement
				(enabled no)
				(sheetname "")
			)
			(fill
				(thermal_gap 0.5)
				(thermal_bridge_width 0.5)
				(island_removal_mode 0)
			)
			(polygon
				(pts
					(arc
						(start 101.880924 -75.50023)
						(mid 101.118924 -75.50023)
						(end 101.880924 -75.50023)
					)
				)
			)
		)
		(zone
			(layer "F.Cu")
			(hatch none 0.5)
			(connect_pads
				(clearance 0)
			)
			(min_thickness 0.25)
			(keepout
				(tracks allowed)
				(vias not_allowed)
				(pads allowed)
				(copperpour not_allowed)
				(footprints allowed)
			)
			(placement
				(enabled no)
				(sheetname "")
			)
			(fill
				(thermal_gap 0.5)
				(thermal_bridge_width 0.5)
				(island_removal_mode 0)
			)
			(polygon
				(pts
					(arc
						(start 101.880924 -74.500232)
						(mid 101.118924 -74.500232)
						(end 101.880924 -74.500232)
					)
				)
			)
		)
		(zone
			(layer "F.Cu")
			(hatch none 0.5)
			(connect_pads
				(clearance 0)
			)
			(min_thickness 0.25)
			(keepout
				(tracks allowed)
				(vias not_allowed)
				(pads allowed)
				(copperpour not_allowed)
				(footprints allowed)
			)
			(placement
				(enabled no)
				(sheetname "")
			)
			(fill
				(thermal_gap 0.5)
				(thermal_bridge_width 0.5)
				(island_removal_mode 0)
			)
			(polygon
				(pts
					(arc
						(start 101.880924 -73.500234)
						(mid 101.118924 -73.500234)
						(end 101.880924 -73.500234)
					)
				)
			)
		)
		(zone
			(layer "F.Cu")
			(hatch none 0.5)
			(connect_pads
				(clearance 0)
			)
			(min_thickness 0.25)
			(keepout
				(tracks allowed)
				(vias not_allowed)
				(pads allowed)
				(copperpour not_allowed)
				(footprints allowed)
			)
			(placement
				(enabled no)
				(sheetname "")
			)
			(fill
				(thermal_gap 0.5)
				(thermal_bridge_width 0.5)
				(island_removal_mode 0)
			)
			(polygon
				(pts
					(arc
						(start 101.880924 -72.500236)
						(mid 101.118924 -72.500236)
						(end 101.880924 -72.500236)
					)
				)
			)
		)
		(zone
			(layer "F.Cu")
			(hatch none 0.5)
			(connect_pads
				(clearance 0)
			)
			(min_thickness 0.25)
			(keepout
				(tracks allowed)
				(vias not_allowed)
				(pads allowed)
				(copperpour not_allowed)
				(footprints allowed)
			)
			(placement
				(enabled no)
				(sheetname "")
			)
			(fill
				(thermal_gap 0.5)
				(thermal_bridge_width 0.5)
				(island_removal_mode 0)
			)
			(polygon
				(pts
					(arc
						(start 101.880924 -71.500238)
						(mid 101.118924 -71.500238)
						(end 101.880924 -71.500238)
					)
				)
			)
		)
		(zone
			(layer "F.Cu")
			(hatch none 0.5)
			(connect_pads
				(clearance 0)
			)
			(min_thickness 0.25)
			(keepout
				(tracks allowed)
				(vias not_allowed)
				(pads allowed)
				(copperpour not_allowed)
				(footprints allowed)
			)
			(placement
				(enabled no)
				(sheetname "")
			)
			(fill
				(thermal_gap 0.5)
				(thermal_bridge_width 0.5)
				(island_removal_mode 0)
			)
			(polygon
				(pts
					(arc
						(start 101.880924 -70.50024)
						(mid 101.118924 -70.50024)
						(end 101.880924 -70.50024)
					)
				)
			)
		)
		(zone
			(layer "F.Cu")
			(hatch none 0.5)
			(connect_pads
				(clearance 0)
			)
			(min_thickness 0.25)
			(keepout
				(tracks allowed)
				(vias not_allowed)
				(pads allowed)
				(copperpour not_allowed)
				(footprints allowed)
			)
			(placement
				(enabled no)
				(sheetname "")
			)
			(fill
				(thermal_gap 0.5)
				(thermal_bridge_width 0.5)
				(island_removal_mode 0)
			)
			(polygon
				(pts
					(arc
						(start 101.880924 -69.500242)
						(mid 101.118924 -69.500242)
						(end 101.880924 -69.500242)
					)
				)
			)
		)
		(zone
			(layer "F.Cu")
			(hatch none 0.5)
			(connect_pads
				(clearance 0)
			)
			(min_thickness 0.25)
			(keepout
				(tracks allowed)
				(vias not_allowed)
				(pads allowed)
				(copperpour not_allowed)
				(footprints allowed)
			)
			(placement
				(enabled no)
				(sheetname "")
			)
			(fill
				(thermal_gap 0.5)
				(thermal_bridge_width 0.5)
				(island_removal_mode 0)
			)
			(polygon
				(pts
					(arc
						(start 101.880924 -68.500244)
						(mid 101.118924 -68.500244)
						(end 101.880924 -68.500244)
					)
				)
			)
		)
		(zone
			(layer "F.Cu")
			(hatch none 0.5)
			(connect_pads
				(clearance 0)
			)
			(min_thickness 0.25)
			(keepout
				(tracks allowed)
				(vias not_allowed)
				(pads allowed)
				(copperpour not_allowed)
				(footprints allowed)
			)
			(placement
				(enabled no)
				(sheetname "")
			)
			(fill
				(thermal_gap 0.5)
				(thermal_bridge_width 0.5)
				(island_removal_mode 0)
			)
			(polygon
				(pts
					(arc
						(start 101.880924 -67.500246)
						(mid 101.118924 -67.500246)
						(end 101.880924 -67.500246)
					)
				)
			)
		)
		(zone
			(layer "F.Cu")
			(hatch none 0.5)
			(connect_pads
				(clearance 0)
			)
			(min_thickness 0.25)
			(keepout
				(tracks allowed)
				(vias not_allowed)
				(pads allowed)
				(copperpour not_allowed)
				(footprints allowed)
			)
			(placement
				(enabled no)
				(sheetname "")
			)
			(fill
				(thermal_gap 0.5)
				(thermal_bridge_width 0.5)
				(island_removal_mode 0)
			)
			(polygon
				(pts
					(arc
						(start 101.880924 -66.499994)
						(mid 101.118924 -66.499994)
						(end 101.880924 -66.499994)
					)
				)
			)
		)
		(zone
			(layer "F.Cu")
			(hatch none 0.5)
			(connect_pads
				(clearance 0)
			)
			(min_thickness 0.25)
			(keepout
				(tracks allowed)
				(vias not_allowed)
				(pads allowed)
				(copperpour not_allowed)
				(footprints allowed)
			)
			(placement
				(enabled no)
				(sheetname "")
			)
			(fill
				(thermal_gap 0.5)
				(thermal_bridge_width 0.5)
				(island_removal_mode 0)
			)
			(polygon
				(pts
					(arc
						(start 101.880924 -65.499996)
						(mid 101.118924 -65.499996)
						(end 101.880924 -65.499996)
					)
				)
			)
		)
		(zone
			(layer "F.Cu")
			(hatch none 0.5)
			(connect_pads
				(clearance 0)
			)
			(min_thickness 0.25)
			(keepout
				(tracks allowed)
				(vias not_allowed)
				(pads allowed)
				(copperpour not_allowed)
				(footprints allowed)
			)
			(placement
				(enabled no)
				(sheetname "")
			)
			(fill
				(thermal_gap 0.5)
				(thermal_bridge_width 0.5)
				(island_removal_mode 0)
			)
			(polygon
				(pts
					(arc
						(start 101.880924 -64.499998)
						(mid 101.118924 -64.499998)
						(end 101.880924 -64.499998)
					)
				)
			)
		)
		(zone
			(layer "F.Cu")
			(hatch none 0.5)
			(connect_pads
				(clearance 0)
			)
			(min_thickness 0.25)
			(keepout
				(tracks allowed)
				(vias not_allowed)
				(pads allowed)
				(copperpour not_allowed)
				(footprints allowed)
			)
			(placement
				(enabled no)
				(sheetname "")
			)
			(fill
				(thermal_gap 0.5)
				(thermal_bridge_width 0.5)
				(island_removal_mode 0)
			)
			(polygon
				(pts
					(arc
						(start 101.880924 -63.5)
						(mid 101.118924 -63.5)
						(end 101.880924 -63.5)
					)
				)
			)
		)
		(zone
			(layer "F.Cu")
			(hatch none 0.5)
			(connect_pads
				(clearance 0)
			)
			(min_thickness 0.25)
			(keepout
				(tracks allowed)
				(vias not_allowed)
				(pads allowed)
				(copperpour not_allowed)
				(footprints allowed)
			)
			(placement
				(enabled no)
				(sheetname "")
			)
			(fill
				(thermal_gap 0.5)
				(thermal_bridge_width 0.5)
				(island_removal_mode 0)
			)
			(polygon
				(pts
					(arc
						(start 101.880924 -62.500002)
						(mid 101.118924 -62.500002)
						(end 101.880924 -62.500002)
					)
				)
			)
		)
		(zone
			(layer "F.Cu")
			(hatch none 0.5)
			(connect_pads
				(clearance 0)
			)
			(min_thickness 0.25)
			(keepout
				(tracks allowed)
				(vias not_allowed)
				(pads allowed)
				(copperpour not_allowed)
				(footprints allowed)
			)
			(placement
				(enabled no)
				(sheetname "")
			)
			(fill
				(thermal_gap 0.5)
				(thermal_bridge_width 0.5)
				(island_removal_mode 0)
			)
			(polygon
				(pts
					(arc
						(start 101.880924 -61.500004)
						(mid 101.118924 -61.500004)
						(end 101.880924 -61.500004)
					)
				)
			)
		)
		(zone
			(layer "F.Cu")
			(hatch none 0.5)
			(connect_pads
				(clearance 0)
			)
			(min_thickness 0.25)
			(keepout
				(tracks allowed)
				(vias not_allowed)
				(pads allowed)
				(copperpour not_allowed)
				(footprints allowed)
			)
			(placement
				(enabled no)
				(sheetname "")
			)
			(fill
				(thermal_gap 0.5)
				(thermal_bridge_width 0.5)
				(island_removal_mode 0)
			)
			(polygon
				(pts
					(arc
						(start 101.880924 -60.500006)
						(mid 101.118924 -60.500006)
						(end 101.880924 -60.500006)
					)
				)
			)
		)
		(zone
			(layer "F.Cu")
			(hatch none 0.5)
			(connect_pads
				(clearance 0)
			)
			(min_thickness 0.25)
			(keepout
				(tracks allowed)
				(vias not_allowed)
				(pads allowed)
				(copperpour not_allowed)
				(footprints allowed)
			)
			(placement
				(enabled no)
				(sheetname "")
			)
			(fill
				(thermal_gap 0.5)
				(thermal_bridge_width 0.5)
				(island_removal_mode 0)
			)
			(polygon
				(pts
					(arc
						(start 101.880924 -59.500008)
						(mid 101.118924 -59.500008)
						(end 101.880924 -59.500008)
					)
				)
			)
		)
		(zone
			(layer "F.Cu")
			(hatch none 0.5)
			(connect_pads
				(clearance 0)
			)
			(min_thickness 0.25)
			(keepout
				(tracks allowed)
				(vias not_allowed)
				(pads allowed)
				(copperpour not_allowed)
				(footprints allowed)
			)
			(placement
				(enabled no)
				(sheetname "")
			)
			(fill
				(thermal_gap 0.5)
				(thermal_bridge_width 0.5)
				(island_removal_mode 0)
			)
			(polygon
				(pts
					(arc
						(start 101.880924 -58.50001)
						(mid 101.118924 -58.50001)
						(end 101.880924 -58.50001)
					)
				)
			)
		)
		(zone
			(layer "F.Cu")
			(hatch none 0.5)
			(connect_pads
				(clearance 0)
			)
			(min_thickness 0.25)
			(keepout
				(tracks allowed)
				(vias not_allowed)
				(pads allowed)
				(copperpour not_allowed)
				(footprints allowed)
			)
			(placement
				(enabled no)
				(sheetname "")
			)
			(fill
				(thermal_gap 0.5)
				(thermal_bridge_width 0.5)
				(island_removal_mode 0)
			)
			(polygon
				(pts
					(arc
						(start 101.880924 -57.500012)
						(mid 101.118924 -57.500012)
						(end 101.880924 -57.500012)
					)
				)
			)
		)
		(zone
			(layer "F.Cu")
			(hatch none 0.5)
			(connect_pads
				(clearance 0)
			)
			(min_thickness 0.25)
			(keepout
				(tracks allowed)
				(vias not_allowed)
				(pads allowed)
				(copperpour not_allowed)
				(footprints allowed)
			)
			(placement
				(enabled no)
				(sheetname "")
			)
			(fill
				(thermal_gap 0.5)
				(thermal_bridge_width 0.5)
				(island_removal_mode 0)
			)
			(polygon
				(pts
					(arc
						(start 101.880924 -56.500014)
						(mid 101.118924 -56.500014)
						(end 101.880924 -56.500014)
					)
				)
			)
		)
		(zone
			(layer "F.Cu")
			(hatch none 0.5)
			(connect_pads
				(clearance 0)
			)
			(min_thickness 0.25)
			(keepout
				(tracks allowed)
				(vias not_allowed)
				(pads allowed)
				(copperpour not_allowed)
				(footprints allowed)
			)
			(placement
				(enabled no)
				(sheetname "")
			)
			(fill
				(thermal_gap 0.5)
				(thermal_bridge_width 0.5)
				(island_removal_mode 0)
			)
			(polygon
				(pts
					(arc
						(start 101.880924 -55.500016)
						(mid 101.118924 -55.500016)
						(end 101.880924 -55.500016)
					)
				)
			)
		)
		(zone
			(layer "F.Cu")
			(hatch none 0.5)
			(connect_pads
				(clearance 0)
			)
			(min_thickness 0.25)
			(keepout
				(tracks allowed)
				(vias not_allowed)
				(pads allowed)
				(copperpour not_allowed)
				(footprints allowed)
			)
			(placement
				(enabled no)
				(sheetname "")
			)
			(fill
				(thermal_gap 0.5)
				(thermal_bridge_width 0.5)
				(island_removal_mode 0)
			)
			(polygon
				(pts
					(arc
						(start 101.880924 -54.500018)
						(mid 101.118924 -54.500018)
						(end 101.880924 -54.500018)
					)
				)
			)
		)
		(zone
			(layer "F.Cu")
			(hatch none 0.5)
			(connect_pads
				(clearance 0)
			)
			(min_thickness 0.25)
			(keepout
				(tracks allowed)
				(vias not_allowed)
				(pads allowed)
				(copperpour not_allowed)
				(footprints allowed)
			)
			(placement
				(enabled no)
				(sheetname "")
			)
			(fill
				(thermal_gap 0.5)
				(thermal_bridge_width 0.5)
				(island_removal_mode 0)
			)
			(polygon
				(pts
					(arc
						(start 102.880922 -82.500216)
						(mid 102.118922 -82.500216)
						(end 102.880922 -82.500216)
					)
				)
			)
		)
		(zone
			(layer "F.Cu")
			(hatch none 0.5)
			(connect_pads
				(clearance 0)
			)
			(min_thickness 0.25)
			(keepout
				(tracks allowed)
				(vias not_allowed)
				(pads allowed)
				(copperpour not_allowed)
				(footprints allowed)
			)
			(placement
				(enabled no)
				(sheetname "")
			)
			(fill
				(thermal_gap 0.5)
				(thermal_bridge_width 0.5)
				(island_removal_mode 0)
			)
			(polygon
				(pts
					(arc
						(start 102.880922 -81.500218)
						(mid 102.118922 -81.500218)
						(end 102.880922 -81.500218)
					)
				)
			)
		)
		(zone
			(layer "F.Cu")
			(hatch none 0.5)
			(connect_pads
				(clearance 0)
			)
			(min_thickness 0.25)
			(keepout
				(tracks allowed)
				(vias not_allowed)
				(pads allowed)
				(copperpour not_allowed)
				(footprints allowed)
			)
			(placement
				(enabled no)
				(sheetname "")
			)
			(fill
				(thermal_gap 0.5)
				(thermal_bridge_width 0.5)
				(island_removal_mode 0)
			)
			(polygon
				(pts
					(arc
						(start 102.880922 -80.50022)
						(mid 102.118922 -80.50022)
						(end 102.880922 -80.50022)
					)
				)
			)
		)
		(zone
			(layer "F.Cu")
			(hatch none 0.5)
			(connect_pads
				(clearance 0)
			)
			(min_thickness 0.25)
			(keepout
				(tracks allowed)
				(vias not_allowed)
				(pads allowed)
				(copperpour not_allowed)
				(footprints allowed)
			)
			(placement
				(enabled no)
				(sheetname "")
			)
			(fill
				(thermal_gap 0.5)
				(thermal_bridge_width 0.5)
				(island_removal_mode 0)
			)
			(polygon
				(pts
					(arc
						(start 102.880922 -79.500222)
						(mid 102.118922 -79.500222)
						(end 102.880922 -79.500222)
					)
				)
			)
		)
		(zone
			(layer "F.Cu")
			(hatch none 0.5)
			(connect_pads
				(clearance 0)
			)
			(min_thickness 0.25)
			(keepout
				(tracks allowed)
				(vias not_allowed)
				(pads allowed)
				(copperpour not_allowed)
				(footprints allowed)
			)
			(placement
				(enabled no)
				(sheetname "")
			)
			(fill
				(thermal_gap 0.5)
				(thermal_bridge_width 0.5)
				(island_removal_mode 0)
			)
			(polygon
				(pts
					(arc
						(start 102.880922 -78.500224)
						(mid 102.118922 -78.500224)
						(end 102.880922 -78.500224)
					)
				)
			)
		)
		(zone
			(layer "F.Cu")
			(hatch none 0.5)
			(connect_pads
				(clearance 0)
			)
			(min_thickness 0.25)
			(keepout
				(tracks allowed)
				(vias not_allowed)
				(pads allowed)
				(copperpour not_allowed)
				(footprints allowed)
			)
			(placement
				(enabled no)
				(sheetname "")
			)
			(fill
				(thermal_gap 0.5)
				(thermal_bridge_width 0.5)
				(island_removal_mode 0)
			)
			(polygon
				(pts
					(arc
						(start 102.880922 -77.500226)
						(mid 102.118922 -77.500226)
						(end 102.880922 -77.500226)
					)
				)
			)
		)
		(zone
			(layer "F.Cu")
			(hatch none 0.5)
			(connect_pads
				(clearance 0)
			)
			(min_thickness 0.25)
			(keepout
				(tracks allowed)
				(vias not_allowed)
				(pads allowed)
				(copperpour not_allowed)
				(footprints allowed)
			)
			(placement
				(enabled no)
				(sheetname "")
			)
			(fill
				(thermal_gap 0.5)
				(thermal_bridge_width 0.5)
				(island_removal_mode 0)
			)
			(polygon
				(pts
					(arc
						(start 102.880922 -76.500228)
						(mid 102.118922 -76.500228)
						(end 102.880922 -76.500228)
					)
				)
			)
		)
		(zone
			(layer "F.Cu")
			(hatch none 0.5)
			(connect_pads
				(clearance 0)
			)
			(min_thickness 0.25)
			(keepout
				(tracks allowed)
				(vias not_allowed)
				(pads allowed)
				(copperpour not_allowed)
				(footprints allowed)
			)
			(placement
				(enabled no)
				(sheetname "")
			)
			(fill
				(thermal_gap 0.5)
				(thermal_bridge_width 0.5)
				(island_removal_mode 0)
			)
			(polygon
				(pts
					(arc
						(start 102.880922 -75.50023)
						(mid 102.118922 -75.50023)
						(end 102.880922 -75.50023)
					)
				)
			)
		)
		(zone
			(layer "F.Cu")
			(hatch none 0.5)
			(connect_pads
				(clearance 0)
			)
			(min_thickness 0.25)
			(keepout
				(tracks allowed)
				(vias not_allowed)
				(pads allowed)
				(copperpour not_allowed)
				(footprints allowed)
			)
			(placement
				(enabled no)
				(sheetname "")
			)
			(fill
				(thermal_gap 0.5)
				(thermal_bridge_width 0.5)
				(island_removal_mode 0)
			)
			(polygon
				(pts
					(arc
						(start 102.880922 -74.500232)
						(mid 102.118922 -74.500232)
						(end 102.880922 -74.500232)
					)
				)
			)
		)
		(zone
			(layer "F.Cu")
			(hatch none 0.5)
			(connect_pads
				(clearance 0)
			)
			(min_thickness 0.25)
			(keepout
				(tracks allowed)
				(vias not_allowed)
				(pads allowed)
				(copperpour not_allowed)
				(footprints allowed)
			)
			(placement
				(enabled no)
				(sheetname "")
			)
			(fill
				(thermal_gap 0.5)
				(thermal_bridge_width 0.5)
				(island_removal_mode 0)
			)
			(polygon
				(pts
					(arc
						(start 102.880922 -73.500234)
						(mid 102.118922 -73.500234)
						(end 102.880922 -73.500234)
					)
				)
			)
		)
		(zone
			(layer "F.Cu")
			(hatch none 0.5)
			(connect_pads
				(clearance 0)
			)
			(min_thickness 0.25)
			(keepout
				(tracks allowed)
				(vias not_allowed)
				(pads allowed)
				(copperpour not_allowed)
				(footprints allowed)
			)
			(placement
				(enabled no)
				(sheetname "")
			)
			(fill
				(thermal_gap 0.5)
				(thermal_bridge_width 0.5)
				(island_removal_mode 0)
			)
			(polygon
				(pts
					(arc
						(start 102.880922 -72.500236)
						(mid 102.118922 -72.500236)
						(end 102.880922 -72.500236)
					)
				)
			)
		)
		(zone
			(layer "F.Cu")
			(hatch none 0.5)
			(connect_pads
				(clearance 0)
			)
			(min_thickness 0.25)
			(keepout
				(tracks allowed)
				(vias not_allowed)
				(pads allowed)
				(copperpour not_allowed)
				(footprints allowed)
			)
			(placement
				(enabled no)
				(sheetname "")
			)
			(fill
				(thermal_gap 0.5)
				(thermal_bridge_width 0.5)
				(island_removal_mode 0)
			)
			(polygon
				(pts
					(arc
						(start 102.880922 -71.500238)
						(mid 102.118922 -71.500238)
						(end 102.880922 -71.500238)
					)
				)
			)
		)
		(zone
			(layer "F.Cu")
			(hatch none 0.5)
			(connect_pads
				(clearance 0)
			)
			(min_thickness 0.25)
			(keepout
				(tracks allowed)
				(vias not_allowed)
				(pads allowed)
				(copperpour not_allowed)
				(footprints allowed)
			)
			(placement
				(enabled no)
				(sheetname "")
			)
			(fill
				(thermal_gap 0.5)
				(thermal_bridge_width 0.5)
				(island_removal_mode 0)
			)
			(polygon
				(pts
					(arc
						(start 102.880922 -70.50024)
						(mid 102.118922 -70.50024)
						(end 102.880922 -70.50024)
					)
				)
			)
		)
		(zone
			(layer "F.Cu")
			(hatch none 0.5)
			(connect_pads
				(clearance 0)
			)
			(min_thickness 0.25)
			(keepout
				(tracks allowed)
				(vias not_allowed)
				(pads allowed)
				(copperpour not_allowed)
				(footprints allowed)
			)
			(placement
				(enabled no)
				(sheetname "")
			)
			(fill
				(thermal_gap 0.5)
				(thermal_bridge_width 0.5)
				(island_removal_mode 0)
			)
			(polygon
				(pts
					(arc
						(start 102.880922 -69.500242)
						(mid 102.118922 -69.500242)
						(end 102.880922 -69.500242)
					)
				)
			)
		)
		(zone
			(layer "F.Cu")
			(hatch none 0.5)
			(connect_pads
				(clearance 0)
			)
			(min_thickness 0.25)
			(keepout
				(tracks allowed)
				(vias not_allowed)
				(pads allowed)
				(copperpour not_allowed)
				(footprints allowed)
			)
			(placement
				(enabled no)
				(sheetname "")
			)
			(fill
				(thermal_gap 0.5)
				(thermal_bridge_width 0.5)
				(island_removal_mode 0)
			)
			(polygon
				(pts
					(arc
						(start 102.880922 -68.500244)
						(mid 102.118922 -68.500244)
						(end 102.880922 -68.500244)
					)
				)
			)
		)
		(zone
			(layer "F.Cu")
			(hatch none 0.5)
			(connect_pads
				(clearance 0)
			)
			(min_thickness 0.25)
			(keepout
				(tracks allowed)
				(vias not_allowed)
				(pads allowed)
				(copperpour not_allowed)
				(footprints allowed)
			)
			(placement
				(enabled no)
				(sheetname "")
			)
			(fill
				(thermal_gap 0.5)
				(thermal_bridge_width 0.5)
				(island_removal_mode 0)
			)
			(polygon
				(pts
					(arc
						(start 102.880922 -67.500246)
						(mid 102.118922 -67.500246)
						(end 102.880922 -67.500246)
					)
				)
			)
		)
		(zone
			(layer "F.Cu")
			(hatch none 0.5)
			(connect_pads
				(clearance 0)
			)
			(min_thickness 0.25)
			(keepout
				(tracks allowed)
				(vias not_allowed)
				(pads allowed)
				(copperpour not_allowed)
				(footprints allowed)
			)
			(placement
				(enabled no)
				(sheetname "")
			)
			(fill
				(thermal_gap 0.5)
				(thermal_bridge_width 0.5)
				(island_removal_mode 0)
			)
			(polygon
				(pts
					(arc
						(start 102.880922 -66.499994)
						(mid 102.118922 -66.499994)
						(end 102.880922 -66.499994)
					)
				)
			)
		)
		(zone
			(layer "F.Cu")
			(hatch none 0.5)
			(connect_pads
				(clearance 0)
			)
			(min_thickness 0.25)
			(keepout
				(tracks allowed)
				(vias not_allowed)
				(pads allowed)
				(copperpour not_allowed)
				(footprints allowed)
			)
			(placement
				(enabled no)
				(sheetname "")
			)
			(fill
				(thermal_gap 0.5)
				(thermal_bridge_width 0.5)
				(island_removal_mode 0)
			)
			(polygon
				(pts
					(arc
						(start 102.880922 -65.499996)
						(mid 102.118922 -65.499996)
						(end 102.880922 -65.499996)
					)
				)
			)
		)
		(zone
			(layer "F.Cu")
			(hatch none 0.5)
			(connect_pads
				(clearance 0)
			)
			(min_thickness 0.25)
			(keepout
				(tracks allowed)
				(vias not_allowed)
				(pads allowed)
				(copperpour not_allowed)
				(footprints allowed)
			)
			(placement
				(enabled no)
				(sheetname "")
			)
			(fill
				(thermal_gap 0.5)
				(thermal_bridge_width 0.5)
				(island_removal_mode 0)
			)
			(polygon
				(pts
					(arc
						(start 102.880922 -64.499998)
						(mid 102.118922 -64.499998)
						(end 102.880922 -64.499998)
					)
				)
			)
		)
		(zone
			(layer "F.Cu")
			(hatch none 0.5)
			(connect_pads
				(clearance 0)
			)
			(min_thickness 0.25)
			(keepout
				(tracks allowed)
				(vias not_allowed)
				(pads allowed)
				(copperpour not_allowed)
				(footprints allowed)
			)
			(placement
				(enabled no)
				(sheetname "")
			)
			(fill
				(thermal_gap 0.5)
				(thermal_bridge_width 0.5)
				(island_removal_mode 0)
			)
			(polygon
				(pts
					(arc
						(start 102.880922 -63.5)
						(mid 102.118922 -63.5)
						(end 102.880922 -63.5)
					)
				)
			)
		)
		(zone
			(layer "F.Cu")
			(hatch none 0.5)
			(connect_pads
				(clearance 0)
			)
			(min_thickness 0.25)
			(keepout
				(tracks allowed)
				(vias not_allowed)
				(pads allowed)
				(copperpour not_allowed)
				(footprints allowed)
			)
			(placement
				(enabled no)
				(sheetname "")
			)
			(fill
				(thermal_gap 0.5)
				(thermal_bridge_width 0.5)
				(island_removal_mode 0)
			)
			(polygon
				(pts
					(arc
						(start 102.880922 -62.500002)
						(mid 102.118922 -62.500002)
						(end 102.880922 -62.500002)
					)
				)
			)
		)
		(zone
			(layer "F.Cu")
			(hatch none 0.5)
			(connect_pads
				(clearance 0)
			)
			(min_thickness 0.25)
			(keepout
				(tracks allowed)
				(vias not_allowed)
				(pads allowed)
				(copperpour not_allowed)
				(footprints allowed)
			)
			(placement
				(enabled no)
				(sheetname "")
			)
			(fill
				(thermal_gap 0.5)
				(thermal_bridge_width 0.5)
				(island_removal_mode 0)
			)
			(polygon
				(pts
					(arc
						(start 102.880922 -61.500004)
						(mid 102.118922 -61.500004)
						(end 102.880922 -61.500004)
					)
				)
			)
		)
		(zone
			(layer "F.Cu")
			(hatch none 0.5)
			(connect_pads
				(clearance 0)
			)
			(min_thickness 0.25)
			(keepout
				(tracks allowed)
				(vias not_allowed)
				(pads allowed)
				(copperpour not_allowed)
				(footprints allowed)
			)
			(placement
				(enabled no)
				(sheetname "")
			)
			(fill
				(thermal_gap 0.5)
				(thermal_bridge_width 0.5)
				(island_removal_mode 0)
			)
			(polygon
				(pts
					(arc
						(start 102.880922 -60.500006)
						(mid 102.118922 -60.500006)
						(end 102.880922 -60.500006)
					)
				)
			)
		)
		(zone
			(layer "F.Cu")
			(hatch none 0.5)
			(connect_pads
				(clearance 0)
			)
			(min_thickness 0.25)
			(keepout
				(tracks allowed)
				(vias not_allowed)
				(pads allowed)
				(copperpour not_allowed)
				(footprints allowed)
			)
			(placement
				(enabled no)
				(sheetname "")
			)
			(fill
				(thermal_gap 0.5)
				(thermal_bridge_width 0.5)
				(island_removal_mode 0)
			)
			(polygon
				(pts
					(arc
						(start 102.880922 -59.500008)
						(mid 102.118922 -59.500008)
						(end 102.880922 -59.500008)
					)
				)
			)
		)
		(zone
			(layer "F.Cu")
			(hatch none 0.5)
			(connect_pads
				(clearance 0)
			)
			(min_thickness 0.25)
			(keepout
				(tracks allowed)
				(vias not_allowed)
				(pads allowed)
				(copperpour not_allowed)
				(footprints allowed)
			)
			(placement
				(enabled no)
				(sheetname "")
			)
			(fill
				(thermal_gap 0.5)
				(thermal_bridge_width 0.5)
				(island_removal_mode 0)
			)
			(polygon
				(pts
					(arc
						(start 102.880922 -58.50001)
						(mid 102.118922 -58.50001)
						(end 102.880922 -58.50001)
					)
				)
			)
		)
		(zone
			(layer "F.Cu")
			(hatch none 0.5)
			(connect_pads
				(clearance 0)
			)
			(min_thickness 0.25)
			(keepout
				(tracks allowed)
				(vias not_allowed)
				(pads allowed)
				(copperpour not_allowed)
				(footprints allowed)
			)
			(placement
				(enabled no)
				(sheetname "")
			)
			(fill
				(thermal_gap 0.5)
				(thermal_bridge_width 0.5)
				(island_removal_mode 0)
			)
			(polygon
				(pts
					(arc
						(start 102.880922 -57.500012)
						(mid 102.118922 -57.500012)
						(end 102.880922 -57.500012)
					)
				)
			)
		)
		(zone
			(layer "F.Cu")
			(hatch none 0.5)
			(connect_pads
				(clearance 0)
			)
			(min_thickness 0.25)
			(keepout
				(tracks allowed)
				(vias not_allowed)
				(pads allowed)
				(copperpour not_allowed)
				(footprints allowed)
			)
			(placement
				(enabled no)
				(sheetname "")
			)
			(fill
				(thermal_gap 0.5)
				(thermal_bridge_width 0.5)
				(island_removal_mode 0)
			)
			(polygon
				(pts
					(arc
						(start 102.880922 -56.500014)
						(mid 102.118922 -56.500014)
						(end 102.880922 -56.500014)
					)
				)
			)
		)
		(zone
			(layer "F.Cu")
			(hatch none 0.5)
			(connect_pads
				(clearance 0)
			)
			(min_thickness 0.25)
			(keepout
				(tracks allowed)
				(vias not_allowed)
				(pads allowed)
				(copperpour not_allowed)
				(footprints allowed)
			)
			(placement
				(enabled no)
				(sheetname "")
			)
			(fill
				(thermal_gap 0.5)
				(thermal_bridge_width 0.5)
				(island_removal_mode 0)
			)
			(polygon
				(pts
					(arc
						(start 102.880922 -55.500016)
						(mid 102.118922 -55.500016)
						(end 102.880922 -55.500016)
					)
				)
			)
		)
		(zone
			(layer "F.Cu")
			(hatch none 0.5)
			(connect_pads
				(clearance 0)
			)
			(min_thickness 0.25)
			(keepout
				(tracks allowed)
				(vias not_allowed)
				(pads allowed)
				(copperpour not_allowed)
				(footprints allowed)
			)
			(placement
				(enabled no)
				(sheetname "")
			)
			(fill
				(thermal_gap 0.5)
				(thermal_bridge_width 0.5)
				(island_removal_mode 0)
			)
			(polygon
				(pts
					(arc
						(start 102.880922 -54.500018)
						(mid 102.118922 -54.500018)
						(end 102.880922 -54.500018)
					)
				)
			)
		)
		(zone
			(layer "F.Cu")
			(hatch none 0.5)
			(connect_pads
				(clearance 0)
			)
			(min_thickness 0.25)
			(keepout
				(tracks allowed)
				(vias not_allowed)
				(pads allowed)
				(copperpour not_allowed)
				(footprints allowed)
			)
			(placement
				(enabled no)
				(sheetname "")
			)
			(fill
				(thermal_gap 0.5)
				(thermal_bridge_width 0.5)
				(island_removal_mode 0)
			)
			(polygon
				(pts
					(arc
						(start 102.880922 -53.50002)
						(mid 102.118922 -53.50002)
						(end 102.880922 -53.50002)
					)
				)
			)
		)
		(zone
			(layer "F.Cu")
			(hatch none 0.5)
			(connect_pads
				(clearance 0)
			)
			(min_thickness 0.25)
			(keepout
				(tracks allowed)
				(vias not_allowed)
				(pads allowed)
				(copperpour not_allowed)
				(footprints allowed)
			)
			(placement
				(enabled no)
				(sheetname "")
			)
			(fill
				(thermal_gap 0.5)
				(thermal_bridge_width 0.5)
				(island_removal_mode 0)
			)
			(polygon
				(pts
					(arc
						(start 102.880922 -52.500022)
						(mid 102.118922 -52.500022)
						(end 102.880922 -52.500022)
					)
				)
			)
		)
		(zone
			(layer "F.Cu")
			(hatch none 0.5)
			(connect_pads
				(clearance 0)
			)
			(min_thickness 0.25)
			(keepout
				(tracks allowed)
				(vias not_allowed)
				(pads allowed)
				(copperpour not_allowed)
				(footprints allowed)
			)
			(placement
				(enabled no)
				(sheetname "")
			)
			(fill
				(thermal_gap 0.5)
				(thermal_bridge_width 0.5)
				(island_removal_mode 0)
			)
			(polygon
				(pts
					(arc
						(start 102.880922 -51.500024)
						(mid 102.118922 -51.500024)
						(end 102.880922 -51.500024)
					)
				)
			)
		)
		(zone
			(layer "F.Cu")
			(hatch none 0.5)
			(connect_pads
				(clearance 0)
			)
			(min_thickness 0.25)
			(keepout
				(tracks allowed)
				(vias not_allowed)
				(pads allowed)
				(copperpour not_allowed)
				(footprints allowed)
			)
			(placement
				(enabled no)
				(sheetname "")
			)
			(fill
				(thermal_gap 0.5)
				(thermal_bridge_width 0.5)
				(island_removal_mode 0)
			)
			(polygon
				(pts
					(arc
						(start 103.88092 -82.500216)
						(mid 103.11892 -82.500216)
						(end 103.88092 -82.500216)
					)
				)
			)
		)
		(zone
			(layer "F.Cu")
			(hatch none 0.5)
			(connect_pads
				(clearance 0)
			)
			(min_thickness 0.25)
			(keepout
				(tracks allowed)
				(vias not_allowed)
				(pads allowed)
				(copperpour not_allowed)
				(footprints allowed)
			)
			(placement
				(enabled no)
				(sheetname "")
			)
			(fill
				(thermal_gap 0.5)
				(thermal_bridge_width 0.5)
				(island_removal_mode 0)
			)
			(polygon
				(pts
					(arc
						(start 103.88092 -81.500218)
						(mid 103.11892 -81.500218)
						(end 103.88092 -81.500218)
					)
				)
			)
		)
		(zone
			(layer "F.Cu")
			(hatch none 0.5)
			(connect_pads
				(clearance 0)
			)
			(min_thickness 0.25)
			(keepout
				(tracks allowed)
				(vias not_allowed)
				(pads allowed)
				(copperpour not_allowed)
				(footprints allowed)
			)
			(placement
				(enabled no)
				(sheetname "")
			)
			(fill
				(thermal_gap 0.5)
				(thermal_bridge_width 0.5)
				(island_removal_mode 0)
			)
			(polygon
				(pts
					(arc
						(start 103.88092 -80.50022)
						(mid 103.11892 -80.50022)
						(end 103.88092 -80.50022)
					)
				)
			)
		)
		(zone
			(layer "F.Cu")
			(hatch none 0.5)
			(connect_pads
				(clearance 0)
			)
			(min_thickness 0.25)
			(keepout
				(tracks allowed)
				(vias not_allowed)
				(pads allowed)
				(copperpour not_allowed)
				(footprints allowed)
			)
			(placement
				(enabled no)
				(sheetname "")
			)
			(fill
				(thermal_gap 0.5)
				(thermal_bridge_width 0.5)
				(island_removal_mode 0)
			)
			(polygon
				(pts
					(arc
						(start 103.88092 -79.500222)
						(mid 103.11892 -79.500222)
						(end 103.88092 -79.500222)
					)
				)
			)
		)
		(zone
			(layer "F.Cu")
			(hatch none 0.5)
			(connect_pads
				(clearance 0)
			)
			(min_thickness 0.25)
			(keepout
				(tracks allowed)
				(vias not_allowed)
				(pads allowed)
				(copperpour not_allowed)
				(footprints allowed)
			)
			(placement
				(enabled no)
				(sheetname "")
			)
			(fill
				(thermal_gap 0.5)
				(thermal_bridge_width 0.5)
				(island_removal_mode 0)
			)
			(polygon
				(pts
					(arc
						(start 103.88092 -78.500224)
						(mid 103.11892 -78.500224)
						(end 103.88092 -78.500224)
					)
				)
			)
		)
		(zone
			(layer "F.Cu")
			(hatch none 0.5)
			(connect_pads
				(clearance 0)
			)
			(min_thickness 0.25)
			(keepout
				(tracks allowed)
				(vias not_allowed)
				(pads allowed)
				(copperpour not_allowed)
				(footprints allowed)
			)
			(placement
				(enabled no)
				(sheetname "")
			)
			(fill
				(thermal_gap 0.5)
				(thermal_bridge_width 0.5)
				(island_removal_mode 0)
			)
			(polygon
				(pts
					(arc
						(start 103.88092 -77.500226)
						(mid 103.11892 -77.500226)
						(end 103.88092 -77.500226)
					)
				)
			)
		)
		(zone
			(layer "F.Cu")
			(hatch none 0.5)
			(connect_pads
				(clearance 0)
			)
			(min_thickness 0.25)
			(keepout
				(tracks allowed)
				(vias not_allowed)
				(pads allowed)
				(copperpour not_allowed)
				(footprints allowed)
			)
			(placement
				(enabled no)
				(sheetname "")
			)
			(fill
				(thermal_gap 0.5)
				(thermal_bridge_width 0.5)
				(island_removal_mode 0)
			)
			(polygon
				(pts
					(arc
						(start 103.88092 -76.500228)
						(mid 103.11892 -76.500228)
						(end 103.88092 -76.500228)
					)
				)
			)
		)
		(zone
			(layer "F.Cu")
			(hatch none 0.5)
			(connect_pads
				(clearance 0)
			)
			(min_thickness 0.25)
			(keepout
				(tracks allowed)
				(vias not_allowed)
				(pads allowed)
				(copperpour not_allowed)
				(footprints allowed)
			)
			(placement
				(enabled no)
				(sheetname "")
			)
			(fill
				(thermal_gap 0.5)
				(thermal_bridge_width 0.5)
				(island_removal_mode 0)
			)
			(polygon
				(pts
					(arc
						(start 103.88092 -75.50023)
						(mid 103.11892 -75.50023)
						(end 103.88092 -75.50023)
					)
				)
			)
		)
		(zone
			(layer "F.Cu")
			(hatch none 0.5)
			(connect_pads
				(clearance 0)
			)
			(min_thickness 0.25)
			(keepout
				(tracks allowed)
				(vias not_allowed)
				(pads allowed)
				(copperpour not_allowed)
				(footprints allowed)
			)
			(placement
				(enabled no)
				(sheetname "")
			)
			(fill
				(thermal_gap 0.5)
				(thermal_bridge_width 0.5)
				(island_removal_mode 0)
			)
			(polygon
				(pts
					(arc
						(start 103.88092 -74.500232)
						(mid 103.11892 -74.500232)
						(end 103.88092 -74.500232)
					)
				)
			)
		)
		(zone
			(layer "F.Cu")
			(hatch none 0.5)
			(connect_pads
				(clearance 0)
			)
			(min_thickness 0.25)
			(keepout
				(tracks allowed)
				(vias not_allowed)
				(pads allowed)
				(copperpour not_allowed)
				(footprints allowed)
			)
			(placement
				(enabled no)
				(sheetname "")
			)
			(fill
				(thermal_gap 0.5)
				(thermal_bridge_width 0.5)
				(island_removal_mode 0)
			)
			(polygon
				(pts
					(arc
						(start 103.88092 -73.500234)
						(mid 103.11892 -73.500234)
						(end 103.88092 -73.500234)
					)
				)
			)
		)
		(zone
			(layer "F.Cu")
			(hatch none 0.5)
			(connect_pads
				(clearance 0)
			)
			(min_thickness 0.25)
			(keepout
				(tracks allowed)
				(vias not_allowed)
				(pads allowed)
				(copperpour not_allowed)
				(footprints allowed)
			)
			(placement
				(enabled no)
				(sheetname "")
			)
			(fill
				(thermal_gap 0.5)
				(thermal_bridge_width 0.5)
				(island_removal_mode 0)
			)
			(polygon
				(pts
					(arc
						(start 103.88092 -72.500236)
						(mid 103.11892 -72.500236)
						(end 103.88092 -72.500236)
					)
				)
			)
		)
		(zone
			(layer "F.Cu")
			(hatch none 0.5)
			(connect_pads
				(clearance 0)
			)
			(min_thickness 0.25)
			(keepout
				(tracks allowed)
				(vias not_allowed)
				(pads allowed)
				(copperpour not_allowed)
				(footprints allowed)
			)
			(placement
				(enabled no)
				(sheetname "")
			)
			(fill
				(thermal_gap 0.5)
				(thermal_bridge_width 0.5)
				(island_removal_mode 0)
			)
			(polygon
				(pts
					(arc
						(start 103.88092 -71.500238)
						(mid 103.11892 -71.500238)
						(end 103.88092 -71.500238)
					)
				)
			)
		)
		(zone
			(layer "F.Cu")
			(hatch none 0.5)
			(connect_pads
				(clearance 0)
			)
			(min_thickness 0.25)
			(keepout
				(tracks allowed)
				(vias not_allowed)
				(pads allowed)
				(copperpour not_allowed)
				(footprints allowed)
			)
			(placement
				(enabled no)
				(sheetname "")
			)
			(fill
				(thermal_gap 0.5)
				(thermal_bridge_width 0.5)
				(island_removal_mode 0)
			)
			(polygon
				(pts
					(arc
						(start 103.88092 -70.50024)
						(mid 103.11892 -70.50024)
						(end 103.88092 -70.50024)
					)
				)
			)
		)
		(zone
			(layer "F.Cu")
			(hatch none 0.5)
			(connect_pads
				(clearance 0)
			)
			(min_thickness 0.25)
			(keepout
				(tracks allowed)
				(vias not_allowed)
				(pads allowed)
				(copperpour not_allowed)
				(footprints allowed)
			)
			(placement
				(enabled no)
				(sheetname "")
			)
			(fill
				(thermal_gap 0.5)
				(thermal_bridge_width 0.5)
				(island_removal_mode 0)
			)
			(polygon
				(pts
					(arc
						(start 103.88092 -69.500242)
						(mid 103.11892 -69.500242)
						(end 103.88092 -69.500242)
					)
				)
			)
		)
		(zone
			(layer "F.Cu")
			(hatch none 0.5)
			(connect_pads
				(clearance 0)
			)
			(min_thickness 0.25)
			(keepout
				(tracks allowed)
				(vias not_allowed)
				(pads allowed)
				(copperpour not_allowed)
				(footprints allowed)
			)
			(placement
				(enabled no)
				(sheetname "")
			)
			(fill
				(thermal_gap 0.5)
				(thermal_bridge_width 0.5)
				(island_removal_mode 0)
			)
			(polygon
				(pts
					(arc
						(start 103.88092 -68.500244)
						(mid 103.11892 -68.500244)
						(end 103.88092 -68.500244)
					)
				)
			)
		)
		(zone
			(layer "F.Cu")
			(hatch none 0.5)
			(connect_pads
				(clearance 0)
			)
			(min_thickness 0.25)
			(keepout
				(tracks allowed)
				(vias not_allowed)
				(pads allowed)
				(copperpour not_allowed)
				(footprints allowed)
			)
			(placement
				(enabled no)
				(sheetname "")
			)
			(fill
				(thermal_gap 0.5)
				(thermal_bridge_width 0.5)
				(island_removal_mode 0)
			)
			(polygon
				(pts
					(arc
						(start 103.88092 -67.500246)
						(mid 103.11892 -67.500246)
						(end 103.88092 -67.500246)
					)
				)
			)
		)
		(zone
			(layer "F.Cu")
			(hatch none 0.5)
			(connect_pads
				(clearance 0)
			)
			(min_thickness 0.25)
			(keepout
				(tracks allowed)
				(vias not_allowed)
				(pads allowed)
				(copperpour not_allowed)
				(footprints allowed)
			)
			(placement
				(enabled no)
				(sheetname "")
			)
			(fill
				(thermal_gap 0.5)
				(thermal_bridge_width 0.5)
				(island_removal_mode 0)
			)
			(polygon
				(pts
					(arc
						(start 103.88092 -66.499994)
						(mid 103.11892 -66.499994)
						(end 103.88092 -66.499994)
					)
				)
			)
		)
		(zone
			(layer "F.Cu")
			(hatch none 0.5)
			(connect_pads
				(clearance 0)
			)
			(min_thickness 0.25)
			(keepout
				(tracks allowed)
				(vias not_allowed)
				(pads allowed)
				(copperpour not_allowed)
				(footprints allowed)
			)
			(placement
				(enabled no)
				(sheetname "")
			)
			(fill
				(thermal_gap 0.5)
				(thermal_bridge_width 0.5)
				(island_removal_mode 0)
			)
			(polygon
				(pts
					(arc
						(start 103.88092 -65.499996)
						(mid 103.11892 -65.499996)
						(end 103.88092 -65.499996)
					)
				)
			)
		)
		(zone
			(layer "F.Cu")
			(hatch none 0.5)
			(connect_pads
				(clearance 0)
			)
			(min_thickness 0.25)
			(keepout
				(tracks allowed)
				(vias not_allowed)
				(pads allowed)
				(copperpour not_allowed)
				(footprints allowed)
			)
			(placement
				(enabled no)
				(sheetname "")
			)
			(fill
				(thermal_gap 0.5)
				(thermal_bridge_width 0.5)
				(island_removal_mode 0)
			)
			(polygon
				(pts
					(arc
						(start 103.88092 -64.499998)
						(mid 103.11892 -64.499998)
						(end 103.88092 -64.499998)
					)
				)
			)
		)
		(zone
			(layer "F.Cu")
			(hatch none 0.5)
			(connect_pads
				(clearance 0)
			)
			(min_thickness 0.25)
			(keepout
				(tracks allowed)
				(vias not_allowed)
				(pads allowed)
				(copperpour not_allowed)
				(footprints allowed)
			)
			(placement
				(enabled no)
				(sheetname "")
			)
			(fill
				(thermal_gap 0.5)
				(thermal_bridge_width 0.5)
				(island_removal_mode 0)
			)
			(polygon
				(pts
					(arc
						(start 103.88092 -63.5)
						(mid 103.11892 -63.5)
						(end 103.88092 -63.5)
					)
				)
			)
		)
		(zone
			(layer "F.Cu")
			(hatch none 0.5)
			(connect_pads
				(clearance 0)
			)
			(min_thickness 0.25)
			(keepout
				(tracks allowed)
				(vias not_allowed)
				(pads allowed)
				(copperpour not_allowed)
				(footprints allowed)
			)
			(placement
				(enabled no)
				(sheetname "")
			)
			(fill
				(thermal_gap 0.5)
				(thermal_bridge_width 0.5)
				(island_removal_mode 0)
			)
			(polygon
				(pts
					(arc
						(start 103.88092 -62.500002)
						(mid 103.11892 -62.500002)
						(end 103.88092 -62.500002)
					)
				)
			)
		)
		(zone
			(layer "F.Cu")
			(hatch none 0.5)
			(connect_pads
				(clearance 0)
			)
			(min_thickness 0.25)
			(keepout
				(tracks allowed)
				(vias not_allowed)
				(pads allowed)
				(copperpour not_allowed)
				(footprints allowed)
			)
			(placement
				(enabled no)
				(sheetname "")
			)
			(fill
				(thermal_gap 0.5)
				(thermal_bridge_width 0.5)
				(island_removal_mode 0)
			)
			(polygon
				(pts
					(arc
						(start 103.88092 -61.500004)
						(mid 103.11892 -61.500004)
						(end 103.88092 -61.500004)
					)
				)
			)
		)
		(zone
			(layer "F.Cu")
			(hatch none 0.5)
			(connect_pads
				(clearance 0)
			)
			(min_thickness 0.25)
			(keepout
				(tracks allowed)
				(vias not_allowed)
				(pads allowed)
				(copperpour not_allowed)
				(footprints allowed)
			)
			(placement
				(enabled no)
				(sheetname "")
			)
			(fill
				(thermal_gap 0.5)
				(thermal_bridge_width 0.5)
				(island_removal_mode 0)
			)
			(polygon
				(pts
					(arc
						(start 103.88092 -60.500006)
						(mid 103.11892 -60.500006)
						(end 103.88092 -60.500006)
					)
				)
			)
		)
		(zone
			(layer "F.Cu")
			(hatch none 0.5)
			(connect_pads
				(clearance 0)
			)
			(min_thickness 0.25)
			(keepout
				(tracks allowed)
				(vias not_allowed)
				(pads allowed)
				(copperpour not_allowed)
				(footprints allowed)
			)
			(placement
				(enabled no)
				(sheetname "")
			)
			(fill
				(thermal_gap 0.5)
				(thermal_bridge_width 0.5)
				(island_removal_mode 0)
			)
			(polygon
				(pts
					(arc
						(start 103.88092 -59.500008)
						(mid 103.11892 -59.500008)
						(end 103.88092 -59.500008)
					)
				)
			)
		)
		(zone
			(layer "F.Cu")
			(hatch none 0.5)
			(connect_pads
				(clearance 0)
			)
			(min_thickness 0.25)
			(keepout
				(tracks allowed)
				(vias not_allowed)
				(pads allowed)
				(copperpour not_allowed)
				(footprints allowed)
			)
			(placement
				(enabled no)
				(sheetname "")
			)
			(fill
				(thermal_gap 0.5)
				(thermal_bridge_width 0.5)
				(island_removal_mode 0)
			)
			(polygon
				(pts
					(arc
						(start 103.88092 -58.50001)
						(mid 103.11892 -58.50001)
						(end 103.88092 -58.50001)
					)
				)
			)
		)
		(zone
			(layer "F.Cu")
			(hatch none 0.5)
			(connect_pads
				(clearance 0)
			)
			(min_thickness 0.25)
			(keepout
				(tracks allowed)
				(vias not_allowed)
				(pads allowed)
				(copperpour not_allowed)
				(footprints allowed)
			)
			(placement
				(enabled no)
				(sheetname "")
			)
			(fill
				(thermal_gap 0.5)
				(thermal_bridge_width 0.5)
				(island_removal_mode 0)
			)
			(polygon
				(pts
					(arc
						(start 103.88092 -57.500012)
						(mid 103.11892 -57.500012)
						(end 103.88092 -57.500012)
					)
				)
			)
		)
		(zone
			(layer "F.Cu")
			(hatch none 0.5)
			(connect_pads
				(clearance 0)
			)
			(min_thickness 0.25)
			(keepout
				(tracks allowed)
				(vias not_allowed)
				(pads allowed)
				(copperpour not_allowed)
				(footprints allowed)
			)
			(placement
				(enabled no)
				(sheetname "")
			)
			(fill
				(thermal_gap 0.5)
				(thermal_bridge_width 0.5)
				(island_removal_mode 0)
			)
			(polygon
				(pts
					(arc
						(start 103.88092 -56.500014)
						(mid 103.11892 -56.500014)
						(end 103.88092 -56.500014)
					)
				)
			)
		)
		(zone
			(layer "F.Cu")
			(hatch none 0.5)
			(connect_pads
				(clearance 0)
			)
			(min_thickness 0.25)
			(keepout
				(tracks allowed)
				(vias not_allowed)
				(pads allowed)
				(copperpour not_allowed)
				(footprints allowed)
			)
			(placement
				(enabled no)
				(sheetname "")
			)
			(fill
				(thermal_gap 0.5)
				(thermal_bridge_width 0.5)
				(island_removal_mode 0)
			)
			(polygon
				(pts
					(arc
						(start 103.88092 -55.500016)
						(mid 103.11892 -55.500016)
						(end 103.88092 -55.500016)
					)
				)
			)
		)
		(zone
			(layer "F.Cu")
			(hatch none 0.5)
			(connect_pads
				(clearance 0)
			)
			(min_thickness 0.25)
			(keepout
				(tracks allowed)
				(vias not_allowed)
				(pads allowed)
				(copperpour not_allowed)
				(footprints allowed)
			)
			(placement
				(enabled no)
				(sheetname "")
			)
			(fill
				(thermal_gap 0.5)
				(thermal_bridge_width 0.5)
				(island_removal_mode 0)
			)
			(polygon
				(pts
					(arc
						(start 103.88092 -54.500018)
						(mid 103.11892 -54.500018)
						(end 103.88092 -54.500018)
					)
				)
			)
		)
		(zone
			(layer "F.Cu")
			(hatch none 0.5)
			(connect_pads
				(clearance 0)
			)
			(min_thickness 0.25)
			(keepout
				(tracks allowed)
				(vias not_allowed)
				(pads allowed)
				(copperpour not_allowed)
				(footprints allowed)
			)
			(placement
				(enabled no)
				(sheetname "")
			)
			(fill
				(thermal_gap 0.5)
				(thermal_bridge_width 0.5)
				(island_removal_mode 0)
			)
			(polygon
				(pts
					(arc
						(start 103.88092 -53.50002)
						(mid 103.11892 -53.50002)
						(end 103.88092 -53.50002)
					)
				)
			)
		)
		(zone
			(layer "F.Cu")
			(hatch none 0.5)
			(connect_pads
				(clearance 0)
			)
			(min_thickness 0.25)
			(keepout
				(tracks allowed)
				(vias not_allowed)
				(pads allowed)
				(copperpour not_allowed)
				(footprints allowed)
			)
			(placement
				(enabled no)
				(sheetname "")
			)
			(fill
				(thermal_gap 0.5)
				(thermal_bridge_width 0.5)
				(island_removal_mode 0)
			)
			(polygon
				(pts
					(arc
						(start 103.88092 -52.500022)
						(mid 103.11892 -52.500022)
						(end 103.88092 -52.500022)
					)
				)
			)
		)
		(zone
			(layer "F.Cu")
			(hatch none 0.5)
			(connect_pads
				(clearance 0)
			)
			(min_thickness 0.25)
			(keepout
				(tracks allowed)
				(vias not_allowed)
				(pads allowed)
				(copperpour not_allowed)
				(footprints allowed)
			)
			(placement
				(enabled no)
				(sheetname "")
			)
			(fill
				(thermal_gap 0.5)
				(thermal_bridge_width 0.5)
				(island_removal_mode 0)
			)
			(polygon
				(pts
					(arc
						(start 103.88092 -51.500024)
						(mid 103.11892 -51.500024)
						(end 103.88092 -51.500024)
					)
				)
			)
		)
		(zone
			(layer "F.Cu")
			(hatch none 0.5)
			(connect_pads
				(clearance 0)
			)
			(min_thickness 0.25)
			(keepout
				(tracks allowed)
				(vias not_allowed)
				(pads allowed)
				(copperpour not_allowed)
				(footprints allowed)
			)
			(placement
				(enabled no)
				(sheetname "")
			)
			(fill
				(thermal_gap 0.5)
				(thermal_bridge_width 0.5)
				(island_removal_mode 0)
			)
			(polygon
				(pts
					(arc
						(start 104.880918 -82.500216)
						(mid 104.118918 -82.500216)
						(end 104.880918 -82.500216)
					)
				)
			)
		)
		(zone
			(layer "F.Cu")
			(hatch none 0.5)
			(connect_pads
				(clearance 0)
			)
			(min_thickness 0.25)
			(keepout
				(tracks allowed)
				(vias not_allowed)
				(pads allowed)
				(copperpour not_allowed)
				(footprints allowed)
			)
			(placement
				(enabled no)
				(sheetname "")
			)
			(fill
				(thermal_gap 0.5)
				(thermal_bridge_width 0.5)
				(island_removal_mode 0)
			)
			(polygon
				(pts
					(arc
						(start 104.880918 -81.500218)
						(mid 104.118918 -81.500218)
						(end 104.880918 -81.500218)
					)
				)
			)
		)
		(zone
			(layer "F.Cu")
			(hatch none 0.5)
			(connect_pads
				(clearance 0)
			)
			(min_thickness 0.25)
			(keepout
				(tracks allowed)
				(vias not_allowed)
				(pads allowed)
				(copperpour not_allowed)
				(footprints allowed)
			)
			(placement
				(enabled no)
				(sheetname "")
			)
			(fill
				(thermal_gap 0.5)
				(thermal_bridge_width 0.5)
				(island_removal_mode 0)
			)
			(polygon
				(pts
					(arc
						(start 104.880918 -80.50022)
						(mid 104.118918 -80.50022)
						(end 104.880918 -80.50022)
					)
				)
			)
		)
		(zone
			(layer "F.Cu")
			(hatch none 0.5)
			(connect_pads
				(clearance 0)
			)
			(min_thickness 0.25)
			(keepout
				(tracks allowed)
				(vias not_allowed)
				(pads allowed)
				(copperpour not_allowed)
				(footprints allowed)
			)
			(placement
				(enabled no)
				(sheetname "")
			)
			(fill
				(thermal_gap 0.5)
				(thermal_bridge_width 0.5)
				(island_removal_mode 0)
			)
			(polygon
				(pts
					(arc
						(start 104.880918 -79.500222)
						(mid 104.118918 -79.500222)
						(end 104.880918 -79.500222)
					)
				)
			)
		)
		(zone
			(layer "F.Cu")
			(hatch none 0.5)
			(connect_pads
				(clearance 0)
			)
			(min_thickness 0.25)
			(keepout
				(tracks allowed)
				(vias not_allowed)
				(pads allowed)
				(copperpour not_allowed)
				(footprints allowed)
			)
			(placement
				(enabled no)
				(sheetname "")
			)
			(fill
				(thermal_gap 0.5)
				(thermal_bridge_width 0.5)
				(island_removal_mode 0)
			)
			(polygon
				(pts
					(arc
						(start 104.880918 -78.500224)
						(mid 104.118918 -78.500224)
						(end 104.880918 -78.500224)
					)
				)
			)
		)
		(zone
			(layer "F.Cu")
			(hatch none 0.5)
			(connect_pads
				(clearance 0)
			)
			(min_thickness 0.25)
			(keepout
				(tracks allowed)
				(vias not_allowed)
				(pads allowed)
				(copperpour not_allowed)
				(footprints allowed)
			)
			(placement
				(enabled no)
				(sheetname "")
			)
			(fill
				(thermal_gap 0.5)
				(thermal_bridge_width 0.5)
				(island_removal_mode 0)
			)
			(polygon
				(pts
					(arc
						(start 104.880918 -77.500226)
						(mid 104.118918 -77.500226)
						(end 104.880918 -77.500226)
					)
				)
			)
		)
		(zone
			(layer "F.Cu")
			(hatch none 0.5)
			(connect_pads
				(clearance 0)
			)
			(min_thickness 0.25)
			(keepout
				(tracks allowed)
				(vias not_allowed)
				(pads allowed)
				(copperpour not_allowed)
				(footprints allowed)
			)
			(placement
				(enabled no)
				(sheetname "")
			)
			(fill
				(thermal_gap 0.5)
				(thermal_bridge_width 0.5)
				(island_removal_mode 0)
			)
			(polygon
				(pts
					(arc
						(start 104.880918 -76.500228)
						(mid 104.118918 -76.500228)
						(end 104.880918 -76.500228)
					)
				)
			)
		)
		(zone
			(layer "F.Cu")
			(hatch none 0.5)
			(connect_pads
				(clearance 0)
			)
			(min_thickness 0.25)
			(keepout
				(tracks allowed)
				(vias not_allowed)
				(pads allowed)
				(copperpour not_allowed)
				(footprints allowed)
			)
			(placement
				(enabled no)
				(sheetname "")
			)
			(fill
				(thermal_gap 0.5)
				(thermal_bridge_width 0.5)
				(island_removal_mode 0)
			)
			(polygon
				(pts
					(arc
						(start 104.880918 -75.50023)
						(mid 104.118918 -75.50023)
						(end 104.880918 -75.50023)
					)
				)
			)
		)
		(zone
			(layer "F.Cu")
			(hatch none 0.5)
			(connect_pads
				(clearance 0)
			)
			(min_thickness 0.25)
			(keepout
				(tracks allowed)
				(vias not_allowed)
				(pads allowed)
				(copperpour not_allowed)
				(footprints allowed)
			)
			(placement
				(enabled no)
				(sheetname "")
			)
			(fill
				(thermal_gap 0.5)
				(thermal_bridge_width 0.5)
				(island_removal_mode 0)
			)
			(polygon
				(pts
					(arc
						(start 104.880918 -74.500232)
						(mid 104.118918 -74.500232)
						(end 104.880918 -74.500232)
					)
				)
			)
		)
		(zone
			(layer "F.Cu")
			(hatch none 0.5)
			(connect_pads
				(clearance 0)
			)
			(min_thickness 0.25)
			(keepout
				(tracks allowed)
				(vias not_allowed)
				(pads allowed)
				(copperpour not_allowed)
				(footprints allowed)
			)
			(placement
				(enabled no)
				(sheetname "")
			)
			(fill
				(thermal_gap 0.5)
				(thermal_bridge_width 0.5)
				(island_removal_mode 0)
			)
			(polygon
				(pts
					(arc
						(start 104.880918 -73.500234)
						(mid 104.118918 -73.500234)
						(end 104.880918 -73.500234)
					)
				)
			)
		)
		(zone
			(layer "F.Cu")
			(hatch none 0.5)
			(connect_pads
				(clearance 0)
			)
			(min_thickness 0.25)
			(keepout
				(tracks allowed)
				(vias not_allowed)
				(pads allowed)
				(copperpour not_allowed)
				(footprints allowed)
			)
			(placement
				(enabled no)
				(sheetname "")
			)
			(fill
				(thermal_gap 0.5)
				(thermal_bridge_width 0.5)
				(island_removal_mode 0)
			)
			(polygon
				(pts
					(arc
						(start 104.880918 -72.500236)
						(mid 104.118918 -72.500236)
						(end 104.880918 -72.500236)
					)
				)
			)
		)
		(zone
			(layer "F.Cu")
			(hatch none 0.5)
			(connect_pads
				(clearance 0)
			)
			(min_thickness 0.25)
			(keepout
				(tracks allowed)
				(vias not_allowed)
				(pads allowed)
				(copperpour not_allowed)
				(footprints allowed)
			)
			(placement
				(enabled no)
				(sheetname "")
			)
			(fill
				(thermal_gap 0.5)
				(thermal_bridge_width 0.5)
				(island_removal_mode 0)
			)
			(polygon
				(pts
					(arc
						(start 104.880918 -71.500238)
						(mid 104.118918 -71.500238)
						(end 104.880918 -71.500238)
					)
				)
			)
		)
		(zone
			(layer "F.Cu")
			(hatch none 0.5)
			(connect_pads
				(clearance 0)
			)
			(min_thickness 0.25)
			(keepout
				(tracks allowed)
				(vias not_allowed)
				(pads allowed)
				(copperpour not_allowed)
				(footprints allowed)
			)
			(placement
				(enabled no)
				(sheetname "")
			)
			(fill
				(thermal_gap 0.5)
				(thermal_bridge_width 0.5)
				(island_removal_mode 0)
			)
			(polygon
				(pts
					(arc
						(start 104.880918 -70.50024)
						(mid 104.118918 -70.50024)
						(end 104.880918 -70.50024)
					)
				)
			)
		)
		(zone
			(layer "F.Cu")
			(hatch none 0.5)
			(connect_pads
				(clearance 0)
			)
			(min_thickness 0.25)
			(keepout
				(tracks allowed)
				(vias not_allowed)
				(pads allowed)
				(copperpour not_allowed)
				(footprints allowed)
			)
			(placement
				(enabled no)
				(sheetname "")
			)
			(fill
				(thermal_gap 0.5)
				(thermal_bridge_width 0.5)
				(island_removal_mode 0)
			)
			(polygon
				(pts
					(arc
						(start 104.880918 -69.500242)
						(mid 104.118918 -69.500242)
						(end 104.880918 -69.500242)
					)
				)
			)
		)
		(zone
			(layer "F.Cu")
			(hatch none 0.5)
			(connect_pads
				(clearance 0)
			)
			(min_thickness 0.25)
			(keepout
				(tracks allowed)
				(vias not_allowed)
				(pads allowed)
				(copperpour not_allowed)
				(footprints allowed)
			)
			(placement
				(enabled no)
				(sheetname "")
			)
			(fill
				(thermal_gap 0.5)
				(thermal_bridge_width 0.5)
				(island_removal_mode 0)
			)
			(polygon
				(pts
					(arc
						(start 104.880918 -68.500244)
						(mid 104.118918 -68.500244)
						(end 104.880918 -68.500244)
					)
				)
			)
		)
		(zone
			(layer "F.Cu")
			(hatch none 0.5)
			(connect_pads
				(clearance 0)
			)
			(min_thickness 0.25)
			(keepout
				(tracks allowed)
				(vias not_allowed)
				(pads allowed)
				(copperpour not_allowed)
				(footprints allowed)
			)
			(placement
				(enabled no)
				(sheetname "")
			)
			(fill
				(thermal_gap 0.5)
				(thermal_bridge_width 0.5)
				(island_removal_mode 0)
			)
			(polygon
				(pts
					(arc
						(start 104.880918 -67.500246)
						(mid 104.118918 -67.500246)
						(end 104.880918 -67.500246)
					)
				)
			)
		)
		(zone
			(layer "F.Cu")
			(hatch none 0.5)
			(connect_pads
				(clearance 0)
			)
			(min_thickness 0.25)
			(keepout
				(tracks allowed)
				(vias not_allowed)
				(pads allowed)
				(copperpour not_allowed)
				(footprints allowed)
			)
			(placement
				(enabled no)
				(sheetname "")
			)
			(fill
				(thermal_gap 0.5)
				(thermal_bridge_width 0.5)
				(island_removal_mode 0)
			)
			(polygon
				(pts
					(arc
						(start 104.880918 -66.499994)
						(mid 104.118918 -66.499994)
						(end 104.880918 -66.499994)
					)
				)
			)
		)
		(zone
			(layer "F.Cu")
			(hatch none 0.5)
			(connect_pads
				(clearance 0)
			)
			(min_thickness 0.25)
			(keepout
				(tracks allowed)
				(vias not_allowed)
				(pads allowed)
				(copperpour not_allowed)
				(footprints allowed)
			)
			(placement
				(enabled no)
				(sheetname "")
			)
			(fill
				(thermal_gap 0.5)
				(thermal_bridge_width 0.5)
				(island_removal_mode 0)
			)
			(polygon
				(pts
					(arc
						(start 104.880918 -65.499996)
						(mid 104.118918 -65.499996)
						(end 104.880918 -65.499996)
					)
				)
			)
		)
		(zone
			(layer "F.Cu")
			(hatch none 0.5)
			(connect_pads
				(clearance 0)
			)
			(min_thickness 0.25)
			(keepout
				(tracks allowed)
				(vias not_allowed)
				(pads allowed)
				(copperpour not_allowed)
				(footprints allowed)
			)
			(placement
				(enabled no)
				(sheetname "")
			)
			(fill
				(thermal_gap 0.5)
				(thermal_bridge_width 0.5)
				(island_removal_mode 0)
			)
			(polygon
				(pts
					(arc
						(start 104.880918 -64.499998)
						(mid 104.118918 -64.499998)
						(end 104.880918 -64.499998)
					)
				)
			)
		)
		(zone
			(layer "F.Cu")
			(hatch none 0.5)
			(connect_pads
				(clearance 0)
			)
			(min_thickness 0.25)
			(keepout
				(tracks allowed)
				(vias not_allowed)
				(pads allowed)
				(copperpour not_allowed)
				(footprints allowed)
			)
			(placement
				(enabled no)
				(sheetname "")
			)
			(fill
				(thermal_gap 0.5)
				(thermal_bridge_width 0.5)
				(island_removal_mode 0)
			)
			(polygon
				(pts
					(arc
						(start 104.880918 -63.5)
						(mid 104.118918 -63.5)
						(end 104.880918 -63.5)
					)
				)
			)
		)
		(zone
			(layer "F.Cu")
			(hatch none 0.5)
			(connect_pads
				(clearance 0)
			)
			(min_thickness 0.25)
			(keepout
				(tracks allowed)
				(vias not_allowed)
				(pads allowed)
				(copperpour not_allowed)
				(footprints allowed)
			)
			(placement
				(enabled no)
				(sheetname "")
			)
			(fill
				(thermal_gap 0.5)
				(thermal_bridge_width 0.5)
				(island_removal_mode 0)
			)
			(polygon
				(pts
					(arc
						(start 104.880918 -62.500002)
						(mid 104.118918 -62.500002)
						(end 104.880918 -62.500002)
					)
				)
			)
		)
		(zone
			(layer "F.Cu")
			(hatch none 0.5)
			(connect_pads
				(clearance 0)
			)
			(min_thickness 0.25)
			(keepout
				(tracks allowed)
				(vias not_allowed)
				(pads allowed)
				(copperpour not_allowed)
				(footprints allowed)
			)
			(placement
				(enabled no)
				(sheetname "")
			)
			(fill
				(thermal_gap 0.5)
				(thermal_bridge_width 0.5)
				(island_removal_mode 0)
			)
			(polygon
				(pts
					(arc
						(start 104.880918 -61.500004)
						(mid 104.118918 -61.500004)
						(end 104.880918 -61.500004)
					)
				)
			)
		)
		(zone
			(layer "F.Cu")
			(hatch none 0.5)
			(connect_pads
				(clearance 0)
			)
			(min_thickness 0.25)
			(keepout
				(tracks allowed)
				(vias not_allowed)
				(pads allowed)
				(copperpour not_allowed)
				(footprints allowed)
			)
			(placement
				(enabled no)
				(sheetname "")
			)
			(fill
				(thermal_gap 0.5)
				(thermal_bridge_width 0.5)
				(island_removal_mode 0)
			)
			(polygon
				(pts
					(arc
						(start 104.880918 -60.500006)
						(mid 104.118918 -60.500006)
						(end 104.880918 -60.500006)
					)
				)
			)
		)
		(zone
			(layer "F.Cu")
			(hatch none 0.5)
			(connect_pads
				(clearance 0)
			)
			(min_thickness 0.25)
			(keepout
				(tracks allowed)
				(vias not_allowed)
				(pads allowed)
				(copperpour not_allowed)
				(footprints allowed)
			)
			(placement
				(enabled no)
				(sheetname "")
			)
			(fill
				(thermal_gap 0.5)
				(thermal_bridge_width 0.5)
				(island_removal_mode 0)
			)
			(polygon
				(pts
					(arc
						(start 104.880918 -59.500008)
						(mid 104.118918 -59.500008)
						(end 104.880918 -59.500008)
					)
				)
			)
		)
		(zone
			(layer "F.Cu")
			(hatch none 0.5)
			(connect_pads
				(clearance 0)
			)
			(min_thickness 0.25)
			(keepout
				(tracks allowed)
				(vias not_allowed)
				(pads allowed)
				(copperpour not_allowed)
				(footprints allowed)
			)
			(placement
				(enabled no)
				(sheetname "")
			)
			(fill
				(thermal_gap 0.5)
				(thermal_bridge_width 0.5)
				(island_removal_mode 0)
			)
			(polygon
				(pts
					(arc
						(start 104.880918 -58.50001)
						(mid 104.118918 -58.50001)
						(end 104.880918 -58.50001)
					)
				)
			)
		)
		(zone
			(layer "F.Cu")
			(hatch none 0.5)
			(connect_pads
				(clearance 0)
			)
			(min_thickness 0.25)
			(keepout
				(tracks allowed)
				(vias not_allowed)
				(pads allowed)
				(copperpour not_allowed)
				(footprints allowed)
			)
			(placement
				(enabled no)
				(sheetname "")
			)
			(fill
				(thermal_gap 0.5)
				(thermal_bridge_width 0.5)
				(island_removal_mode 0)
			)
			(polygon
				(pts
					(arc
						(start 104.880918 -57.500012)
						(mid 104.118918 -57.500012)
						(end 104.880918 -57.500012)
					)
				)
			)
		)
		(zone
			(layer "F.Cu")
			(hatch none 0.5)
			(connect_pads
				(clearance 0)
			)
			(min_thickness 0.25)
			(keepout
				(tracks allowed)
				(vias not_allowed)
				(pads allowed)
				(copperpour not_allowed)
				(footprints allowed)
			)
			(placement
				(enabled no)
				(sheetname "")
			)
			(fill
				(thermal_gap 0.5)
				(thermal_bridge_width 0.5)
				(island_removal_mode 0)
			)
			(polygon
				(pts
					(arc
						(start 104.880918 -56.500014)
						(mid 104.118918 -56.500014)
						(end 104.880918 -56.500014)
					)
				)
			)
		)
		(zone
			(layer "F.Cu")
			(hatch none 0.5)
			(connect_pads
				(clearance 0)
			)
			(min_thickness 0.25)
			(keepout
				(tracks allowed)
				(vias not_allowed)
				(pads allowed)
				(copperpour not_allowed)
				(footprints allowed)
			)
			(placement
				(enabled no)
				(sheetname "")
			)
			(fill
				(thermal_gap 0.5)
				(thermal_bridge_width 0.5)
				(island_removal_mode 0)
			)
			(polygon
				(pts
					(arc
						(start 104.880918 -55.500016)
						(mid 104.118918 -55.500016)
						(end 104.880918 -55.500016)
					)
				)
			)
		)
		(zone
			(layer "F.Cu")
			(hatch none 0.5)
			(connect_pads
				(clearance 0)
			)
			(min_thickness 0.25)
			(keepout
				(tracks allowed)
				(vias not_allowed)
				(pads allowed)
				(copperpour not_allowed)
				(footprints allowed)
			)
			(placement
				(enabled no)
				(sheetname "")
			)
			(fill
				(thermal_gap 0.5)
				(thermal_bridge_width 0.5)
				(island_removal_mode 0)
			)
			(polygon
				(pts
					(arc
						(start 104.880918 -54.500018)
						(mid 104.118918 -54.500018)
						(end 104.880918 -54.500018)
					)
				)
			)
		)
		(zone
			(layer "F.Cu")
			(hatch none 0.5)
			(connect_pads
				(clearance 0)
			)
			(min_thickness 0.25)
			(keepout
				(tracks allowed)
				(vias not_allowed)
				(pads allowed)
				(copperpour not_allowed)
				(footprints allowed)
			)
			(placement
				(enabled no)
				(sheetname "")
			)
			(fill
				(thermal_gap 0.5)
				(thermal_bridge_width 0.5)
				(island_removal_mode 0)
			)
			(polygon
				(pts
					(arc
						(start 104.880918 -53.50002)
						(mid 104.118918 -53.50002)
						(end 104.880918 -53.50002)
					)
				)
			)
		)
		(zone
			(layer "F.Cu")
			(hatch none 0.5)
			(connect_pads
				(clearance 0)
			)
			(min_thickness 0.25)
			(keepout
				(tracks allowed)
				(vias not_allowed)
				(pads allowed)
				(copperpour not_allowed)
				(footprints allowed)
			)
			(placement
				(enabled no)
				(sheetname "")
			)
			(fill
				(thermal_gap 0.5)
				(thermal_bridge_width 0.5)
				(island_removal_mode 0)
			)
			(polygon
				(pts
					(arc
						(start 104.880918 -52.500022)
						(mid 104.118918 -52.500022)
						(end 104.880918 -52.500022)
					)
				)
			)
		)
		(zone
			(layer "F.Cu")
			(hatch none 0.5)
			(connect_pads
				(clearance 0)
			)
			(min_thickness 0.25)
			(keepout
				(tracks allowed)
				(vias not_allowed)
				(pads allowed)
				(copperpour not_allowed)
				(footprints allowed)
			)
			(placement
				(enabled no)
				(sheetname "")
			)
			(fill
				(thermal_gap 0.5)
				(thermal_bridge_width 0.5)
				(island_removal_mode 0)
			)
			(polygon
				(pts
					(arc
						(start 104.880918 -51.500024)
						(mid 104.118918 -51.500024)
						(end 104.880918 -51.500024)
					)
				)
			)
		)
		(zone
			(layer "F.Cu")
			(hatch none 0.5)
			(connect_pads
				(clearance 0)
			)
			(min_thickness 0.25)
			(keepout
				(tracks allowed)
				(vias not_allowed)
				(pads allowed)
				(copperpour not_allowed)
				(footprints allowed)
			)
			(placement
				(enabled no)
				(sheetname "")
			)
			(fill
				(thermal_gap 0.5)
				(thermal_bridge_width 0.5)
				(island_removal_mode 0)
			)
			(polygon
				(pts
					(arc
						(start 105.880916 -82.500216)
						(mid 105.118916 -82.500216)
						(end 105.880916 -82.500216)
					)
				)
			)
		)
		(zone
			(layer "F.Cu")
			(hatch none 0.5)
			(connect_pads
				(clearance 0)
			)
			(min_thickness 0.25)
			(keepout
				(tracks allowed)
				(vias not_allowed)
				(pads allowed)
				(copperpour not_allowed)
				(footprints allowed)
			)
			(placement
				(enabled no)
				(sheetname "")
			)
			(fill
				(thermal_gap 0.5)
				(thermal_bridge_width 0.5)
				(island_removal_mode 0)
			)
			(polygon
				(pts
					(arc
						(start 105.880916 -81.500218)
						(mid 105.118916 -81.500218)
						(end 105.880916 -81.500218)
					)
				)
			)
		)
		(zone
			(layer "F.Cu")
			(hatch none 0.5)
			(connect_pads
				(clearance 0)
			)
			(min_thickness 0.25)
			(keepout
				(tracks allowed)
				(vias not_allowed)
				(pads allowed)
				(copperpour not_allowed)
				(footprints allowed)
			)
			(placement
				(enabled no)
				(sheetname "")
			)
			(fill
				(thermal_gap 0.5)
				(thermal_bridge_width 0.5)
				(island_removal_mode 0)
			)
			(polygon
				(pts
					(arc
						(start 105.880916 -80.50022)
						(mid 105.118916 -80.50022)
						(end 105.880916 -80.50022)
					)
				)
			)
		)
		(zone
			(layer "F.Cu")
			(hatch none 0.5)
			(connect_pads
				(clearance 0)
			)
			(min_thickness 0.25)
			(keepout
				(tracks allowed)
				(vias not_allowed)
				(pads allowed)
				(copperpour not_allowed)
				(footprints allowed)
			)
			(placement
				(enabled no)
				(sheetname "")
			)
			(fill
				(thermal_gap 0.5)
				(thermal_bridge_width 0.5)
				(island_removal_mode 0)
			)
			(polygon
				(pts
					(arc
						(start 105.880916 -79.500222)
						(mid 105.118916 -79.500222)
						(end 105.880916 -79.500222)
					)
				)
			)
		)
		(zone
			(layer "F.Cu")
			(hatch none 0.5)
			(connect_pads
				(clearance 0)
			)
			(min_thickness 0.25)
			(keepout
				(tracks allowed)
				(vias not_allowed)
				(pads allowed)
				(copperpour not_allowed)
				(footprints allowed)
			)
			(placement
				(enabled no)
				(sheetname "")
			)
			(fill
				(thermal_gap 0.5)
				(thermal_bridge_width 0.5)
				(island_removal_mode 0)
			)
			(polygon
				(pts
					(arc
						(start 105.880916 -78.500224)
						(mid 105.118916 -78.500224)
						(end 105.880916 -78.500224)
					)
				)
			)
		)
		(zone
			(layer "F.Cu")
			(hatch none 0.5)
			(connect_pads
				(clearance 0)
			)
			(min_thickness 0.25)
			(keepout
				(tracks allowed)
				(vias not_allowed)
				(pads allowed)
				(copperpour not_allowed)
				(footprints allowed)
			)
			(placement
				(enabled no)
				(sheetname "")
			)
			(fill
				(thermal_gap 0.5)
				(thermal_bridge_width 0.5)
				(island_removal_mode 0)
			)
			(polygon
				(pts
					(arc
						(start 105.880916 -77.500226)
						(mid 105.118916 -77.500226)
						(end 105.880916 -77.500226)
					)
				)
			)
		)
		(zone
			(layer "F.Cu")
			(hatch none 0.5)
			(connect_pads
				(clearance 0)
			)
			(min_thickness 0.25)
			(keepout
				(tracks allowed)
				(vias not_allowed)
				(pads allowed)
				(copperpour not_allowed)
				(footprints allowed)
			)
			(placement
				(enabled no)
				(sheetname "")
			)
			(fill
				(thermal_gap 0.5)
				(thermal_bridge_width 0.5)
				(island_removal_mode 0)
			)
			(polygon
				(pts
					(arc
						(start 105.880916 -76.500228)
						(mid 105.118916 -76.500228)
						(end 105.880916 -76.500228)
					)
				)
			)
		)
		(zone
			(layer "F.Cu")
			(hatch none 0.5)
			(connect_pads
				(clearance 0)
			)
			(min_thickness 0.25)
			(keepout
				(tracks allowed)
				(vias not_allowed)
				(pads allowed)
				(copperpour not_allowed)
				(footprints allowed)
			)
			(placement
				(enabled no)
				(sheetname "")
			)
			(fill
				(thermal_gap 0.5)
				(thermal_bridge_width 0.5)
				(island_removal_mode 0)
			)
			(polygon
				(pts
					(arc
						(start 105.880916 -75.50023)
						(mid 105.118916 -75.50023)
						(end 105.880916 -75.50023)
					)
				)
			)
		)
		(zone
			(layer "F.Cu")
			(hatch none 0.5)
			(connect_pads
				(clearance 0)
			)
			(min_thickness 0.25)
			(keepout
				(tracks allowed)
				(vias not_allowed)
				(pads allowed)
				(copperpour not_allowed)
				(footprints allowed)
			)
			(placement
				(enabled no)
				(sheetname "")
			)
			(fill
				(thermal_gap 0.5)
				(thermal_bridge_width 0.5)
				(island_removal_mode 0)
			)
			(polygon
				(pts
					(arc
						(start 105.880916 -74.500232)
						(mid 105.118916 -74.500232)
						(end 105.880916 -74.500232)
					)
				)
			)
		)
		(zone
			(layer "F.Cu")
			(hatch none 0.5)
			(connect_pads
				(clearance 0)
			)
			(min_thickness 0.25)
			(keepout
				(tracks allowed)
				(vias not_allowed)
				(pads allowed)
				(copperpour not_allowed)
				(footprints allowed)
			)
			(placement
				(enabled no)
				(sheetname "")
			)
			(fill
				(thermal_gap 0.5)
				(thermal_bridge_width 0.5)
				(island_removal_mode 0)
			)
			(polygon
				(pts
					(arc
						(start 105.880916 -73.500234)
						(mid 105.118916 -73.500234)
						(end 105.880916 -73.500234)
					)
				)
			)
		)
		(zone
			(layer "F.Cu")
			(hatch none 0.5)
			(connect_pads
				(clearance 0)
			)
			(min_thickness 0.25)
			(keepout
				(tracks allowed)
				(vias not_allowed)
				(pads allowed)
				(copperpour not_allowed)
				(footprints allowed)
			)
			(placement
				(enabled no)
				(sheetname "")
			)
			(fill
				(thermal_gap 0.5)
				(thermal_bridge_width 0.5)
				(island_removal_mode 0)
			)
			(polygon
				(pts
					(arc
						(start 105.880916 -72.500236)
						(mid 105.118916 -72.500236)
						(end 105.880916 -72.500236)
					)
				)
			)
		)
		(zone
			(layer "F.Cu")
			(hatch none 0.5)
			(connect_pads
				(clearance 0)
			)
			(min_thickness 0.25)
			(keepout
				(tracks allowed)
				(vias not_allowed)
				(pads allowed)
				(copperpour not_allowed)
				(footprints allowed)
			)
			(placement
				(enabled no)
				(sheetname "")
			)
			(fill
				(thermal_gap 0.5)
				(thermal_bridge_width 0.5)
				(island_removal_mode 0)
			)
			(polygon
				(pts
					(arc
						(start 105.880916 -71.500238)
						(mid 105.118916 -71.500238)
						(end 105.880916 -71.500238)
					)
				)
			)
		)
		(zone
			(layer "F.Cu")
			(hatch none 0.5)
			(connect_pads
				(clearance 0)
			)
			(min_thickness 0.25)
			(keepout
				(tracks allowed)
				(vias not_allowed)
				(pads allowed)
				(copperpour not_allowed)
				(footprints allowed)
			)
			(placement
				(enabled no)
				(sheetname "")
			)
			(fill
				(thermal_gap 0.5)
				(thermal_bridge_width 0.5)
				(island_removal_mode 0)
			)
			(polygon
				(pts
					(arc
						(start 105.880916 -70.50024)
						(mid 105.118916 -70.50024)
						(end 105.880916 -70.50024)
					)
				)
			)
		)
		(zone
			(layer "F.Cu")
			(hatch none 0.5)
			(connect_pads
				(clearance 0)
			)
			(min_thickness 0.25)
			(keepout
				(tracks allowed)
				(vias not_allowed)
				(pads allowed)
				(copperpour not_allowed)
				(footprints allowed)
			)
			(placement
				(enabled no)
				(sheetname "")
			)
			(fill
				(thermal_gap 0.5)
				(thermal_bridge_width 0.5)
				(island_removal_mode 0)
			)
			(polygon
				(pts
					(arc
						(start 105.880916 -69.500242)
						(mid 105.118916 -69.500242)
						(end 105.880916 -69.500242)
					)
				)
			)
		)
		(zone
			(layer "F.Cu")
			(hatch none 0.5)
			(connect_pads
				(clearance 0)
			)
			(min_thickness 0.25)
			(keepout
				(tracks allowed)
				(vias not_allowed)
				(pads allowed)
				(copperpour not_allowed)
				(footprints allowed)
			)
			(placement
				(enabled no)
				(sheetname "")
			)
			(fill
				(thermal_gap 0.5)
				(thermal_bridge_width 0.5)
				(island_removal_mode 0)
			)
			(polygon
				(pts
					(arc
						(start 105.880916 -68.500244)
						(mid 105.118916 -68.500244)
						(end 105.880916 -68.500244)
					)
				)
			)
		)
		(zone
			(layer "F.Cu")
			(hatch none 0.5)
			(connect_pads
				(clearance 0)
			)
			(min_thickness 0.25)
			(keepout
				(tracks allowed)
				(vias not_allowed)
				(pads allowed)
				(copperpour not_allowed)
				(footprints allowed)
			)
			(placement
				(enabled no)
				(sheetname "")
			)
			(fill
				(thermal_gap 0.5)
				(thermal_bridge_width 0.5)
				(island_removal_mode 0)
			)
			(polygon
				(pts
					(arc
						(start 105.880916 -67.500246)
						(mid 105.118916 -67.500246)
						(end 105.880916 -67.500246)
					)
				)
			)
		)
		(zone
			(layer "F.Cu")
			(hatch none 0.5)
			(connect_pads
				(clearance 0)
			)
			(min_thickness 0.25)
			(keepout
				(tracks allowed)
				(vias not_allowed)
				(pads allowed)
				(copperpour not_allowed)
				(footprints allowed)
			)
			(placement
				(enabled no)
				(sheetname "")
			)
			(fill
				(thermal_gap 0.5)
				(thermal_bridge_width 0.5)
				(island_removal_mode 0)
			)
			(polygon
				(pts
					(arc
						(start 105.880916 -66.499994)
						(mid 105.118916 -66.499994)
						(end 105.880916 -66.499994)
					)
				)
			)
		)
		(zone
			(layer "F.Cu")
			(hatch none 0.5)
			(connect_pads
				(clearance 0)
			)
			(min_thickness 0.25)
			(keepout
				(tracks allowed)
				(vias not_allowed)
				(pads allowed)
				(copperpour not_allowed)
				(footprints allowed)
			)
			(placement
				(enabled no)
				(sheetname "")
			)
			(fill
				(thermal_gap 0.5)
				(thermal_bridge_width 0.5)
				(island_removal_mode 0)
			)
			(polygon
				(pts
					(arc
						(start 105.880916 -65.499996)
						(mid 105.118916 -65.499996)
						(end 105.880916 -65.499996)
					)
				)
			)
		)
		(zone
			(layer "F.Cu")
			(hatch none 0.5)
			(connect_pads
				(clearance 0)
			)
			(min_thickness 0.25)
			(keepout
				(tracks allowed)
				(vias not_allowed)
				(pads allowed)
				(copperpour not_allowed)
				(footprints allowed)
			)
			(placement
				(enabled no)
				(sheetname "")
			)
			(fill
				(thermal_gap 0.5)
				(thermal_bridge_width 0.5)
				(island_removal_mode 0)
			)
			(polygon
				(pts
					(arc
						(start 105.880916 -64.499998)
						(mid 105.118916 -64.499998)
						(end 105.880916 -64.499998)
					)
				)
			)
		)
		(zone
			(layer "F.Cu")
			(hatch none 0.5)
			(connect_pads
				(clearance 0)
			)
			(min_thickness 0.25)
			(keepout
				(tracks allowed)
				(vias not_allowed)
				(pads allowed)
				(copperpour not_allowed)
				(footprints allowed)
			)
			(placement
				(enabled no)
				(sheetname "")
			)
			(fill
				(thermal_gap 0.5)
				(thermal_bridge_width 0.5)
				(island_removal_mode 0)
			)
			(polygon
				(pts
					(arc
						(start 105.880916 -63.5)
						(mid 105.118916 -63.5)
						(end 105.880916 -63.5)
					)
				)
			)
		)
		(zone
			(layer "F.Cu")
			(hatch none 0.5)
			(connect_pads
				(clearance 0)
			)
			(min_thickness 0.25)
			(keepout
				(tracks allowed)
				(vias not_allowed)
				(pads allowed)
				(copperpour not_allowed)
				(footprints allowed)
			)
			(placement
				(enabled no)
				(sheetname "")
			)
			(fill
				(thermal_gap 0.5)
				(thermal_bridge_width 0.5)
				(island_removal_mode 0)
			)
			(polygon
				(pts
					(arc
						(start 105.880916 -62.500002)
						(mid 105.118916 -62.500002)
						(end 105.880916 -62.500002)
					)
				)
			)
		)
		(zone
			(layer "F.Cu")
			(hatch none 0.5)
			(connect_pads
				(clearance 0)
			)
			(min_thickness 0.25)
			(keepout
				(tracks allowed)
				(vias not_allowed)
				(pads allowed)
				(copperpour not_allowed)
				(footprints allowed)
			)
			(placement
				(enabled no)
				(sheetname "")
			)
			(fill
				(thermal_gap 0.5)
				(thermal_bridge_width 0.5)
				(island_removal_mode 0)
			)
			(polygon
				(pts
					(arc
						(start 105.880916 -61.500004)
						(mid 105.118916 -61.500004)
						(end 105.880916 -61.500004)
					)
				)
			)
		)
		(zone
			(layer "F.Cu")
			(hatch none 0.5)
			(connect_pads
				(clearance 0)
			)
			(min_thickness 0.25)
			(keepout
				(tracks allowed)
				(vias not_allowed)
				(pads allowed)
				(copperpour not_allowed)
				(footprints allowed)
			)
			(placement
				(enabled no)
				(sheetname "")
			)
			(fill
				(thermal_gap 0.5)
				(thermal_bridge_width 0.5)
				(island_removal_mode 0)
			)
			(polygon
				(pts
					(arc
						(start 105.880916 -60.500006)
						(mid 105.118916 -60.500006)
						(end 105.880916 -60.500006)
					)
				)
			)
		)
		(zone
			(layer "F.Cu")
			(hatch none 0.5)
			(connect_pads
				(clearance 0)
			)
			(min_thickness 0.25)
			(keepout
				(tracks allowed)
				(vias not_allowed)
				(pads allowed)
				(copperpour not_allowed)
				(footprints allowed)
			)
			(placement
				(enabled no)
				(sheetname "")
			)
			(fill
				(thermal_gap 0.5)
				(thermal_bridge_width 0.5)
				(island_removal_mode 0)
			)
			(polygon
				(pts
					(arc
						(start 105.880916 -59.500008)
						(mid 105.118916 -59.500008)
						(end 105.880916 -59.500008)
					)
				)
			)
		)
		(zone
			(layer "F.Cu")
			(hatch none 0.5)
			(connect_pads
				(clearance 0)
			)
			(min_thickness 0.25)
			(keepout
				(tracks allowed)
				(vias not_allowed)
				(pads allowed)
				(copperpour not_allowed)
				(footprints allowed)
			)
			(placement
				(enabled no)
				(sheetname "")
			)
			(fill
				(thermal_gap 0.5)
				(thermal_bridge_width 0.5)
				(island_removal_mode 0)
			)
			(polygon
				(pts
					(arc
						(start 105.880916 -58.50001)
						(mid 105.118916 -58.50001)
						(end 105.880916 -58.50001)
					)
				)
			)
		)
		(zone
			(layer "F.Cu")
			(hatch none 0.5)
			(connect_pads
				(clearance 0)
			)
			(min_thickness 0.25)
			(keepout
				(tracks allowed)
				(vias not_allowed)
				(pads allowed)
				(copperpour not_allowed)
				(footprints allowed)
			)
			(placement
				(enabled no)
				(sheetname "")
			)
			(fill
				(thermal_gap 0.5)
				(thermal_bridge_width 0.5)
				(island_removal_mode 0)
			)
			(polygon
				(pts
					(arc
						(start 105.880916 -57.500012)
						(mid 105.118916 -57.500012)
						(end 105.880916 -57.500012)
					)
				)
			)
		)
		(zone
			(layer "F.Cu")
			(hatch none 0.5)
			(connect_pads
				(clearance 0)
			)
			(min_thickness 0.25)
			(keepout
				(tracks allowed)
				(vias not_allowed)
				(pads allowed)
				(copperpour not_allowed)
				(footprints allowed)
			)
			(placement
				(enabled no)
				(sheetname "")
			)
			(fill
				(thermal_gap 0.5)
				(thermal_bridge_width 0.5)
				(island_removal_mode 0)
			)
			(polygon
				(pts
					(arc
						(start 105.880916 -56.500014)
						(mid 105.118916 -56.500014)
						(end 105.880916 -56.500014)
					)
				)
			)
		)
		(zone
			(layer "F.Cu")
			(hatch none 0.5)
			(connect_pads
				(clearance 0)
			)
			(min_thickness 0.25)
			(keepout
				(tracks allowed)
				(vias not_allowed)
				(pads allowed)
				(copperpour not_allowed)
				(footprints allowed)
			)
			(placement
				(enabled no)
				(sheetname "")
			)
			(fill
				(thermal_gap 0.5)
				(thermal_bridge_width 0.5)
				(island_removal_mode 0)
			)
			(polygon
				(pts
					(arc
						(start 105.880916 -55.500016)
						(mid 105.118916 -55.500016)
						(end 105.880916 -55.500016)
					)
				)
			)
		)
		(zone
			(layer "F.Cu")
			(hatch none 0.5)
			(connect_pads
				(clearance 0)
			)
			(min_thickness 0.25)
			(keepout
				(tracks allowed)
				(vias not_allowed)
				(pads allowed)
				(copperpour not_allowed)
				(footprints allowed)
			)
			(placement
				(enabled no)
				(sheetname "")
			)
			(fill
				(thermal_gap 0.5)
				(thermal_bridge_width 0.5)
				(island_removal_mode 0)
			)
			(polygon
				(pts
					(arc
						(start 105.880916 -54.500018)
						(mid 105.118916 -54.500018)
						(end 105.880916 -54.500018)
					)
				)
			)
		)
		(zone
			(layer "F.Cu")
			(hatch none 0.5)
			(connect_pads
				(clearance 0)
			)
			(min_thickness 0.25)
			(keepout
				(tracks allowed)
				(vias not_allowed)
				(pads allowed)
				(copperpour not_allowed)
				(footprints allowed)
			)
			(placement
				(enabled no)
				(sheetname "")
			)
			(fill
				(thermal_gap 0.5)
				(thermal_bridge_width 0.5)
				(island_removal_mode 0)
			)
			(polygon
				(pts
					(arc
						(start 105.880916 -53.50002)
						(mid 105.118916 -53.50002)
						(end 105.880916 -53.50002)
					)
				)
			)
		)
		(zone
			(layer "F.Cu")
			(hatch none 0.5)
			(connect_pads
				(clearance 0)
			)
			(min_thickness 0.25)
			(keepout
				(tracks allowed)
				(vias not_allowed)
				(pads allowed)
				(copperpour not_allowed)
				(footprints allowed)
			)
			(placement
				(enabled no)
				(sheetname "")
			)
			(fill
				(thermal_gap 0.5)
				(thermal_bridge_width 0.5)
				(island_removal_mode 0)
			)
			(polygon
				(pts
					(arc
						(start 105.880916 -52.500022)
						(mid 105.118916 -52.500022)
						(end 105.880916 -52.500022)
					)
				)
			)
		)
		(zone
			(layer "F.Cu")
			(hatch none 0.5)
			(connect_pads
				(clearance 0)
			)
			(min_thickness 0.25)
			(keepout
				(tracks allowed)
				(vias not_allowed)
				(pads allowed)
				(copperpour not_allowed)
				(footprints allowed)
			)
			(placement
				(enabled no)
				(sheetname "")
			)
			(fill
				(thermal_gap 0.5)
				(thermal_bridge_width 0.5)
				(island_removal_mode 0)
			)
			(polygon
				(pts
					(arc
						(start 105.880916 -51.500024)
						(mid 105.118916 -51.500024)
						(end 105.880916 -51.500024)
					)
				)
			)
		)
		(zone
			(layer "F.Cu")
			(hatch none 0.5)
			(connect_pads
				(clearance 0)
			)
			(min_thickness 0.25)
			(keepout
				(tracks allowed)
				(vias not_allowed)
				(pads allowed)
				(copperpour not_allowed)
				(footprints allowed)
			)
			(placement
				(enabled no)
				(sheetname "")
			)
			(fill
				(thermal_gap 0.5)
				(thermal_bridge_width 0.5)
				(island_removal_mode 0)
			)
			(polygon
				(pts
					(arc
						(start 106.880914 -82.500216)
						(mid 106.118914 -82.500216)
						(end 106.880914 -82.500216)
					)
				)
			)
		)
		(zone
			(layer "F.Cu")
			(hatch none 0.5)
			(connect_pads
				(clearance 0)
			)
			(min_thickness 0.25)
			(keepout
				(tracks allowed)
				(vias not_allowed)
				(pads allowed)
				(copperpour not_allowed)
				(footprints allowed)
			)
			(placement
				(enabled no)
				(sheetname "")
			)
			(fill
				(thermal_gap 0.5)
				(thermal_bridge_width 0.5)
				(island_removal_mode 0)
			)
			(polygon
				(pts
					(arc
						(start 106.880914 -81.500218)
						(mid 106.118914 -81.500218)
						(end 106.880914 -81.500218)
					)
				)
			)
		)
		(zone
			(layer "F.Cu")
			(hatch none 0.5)
			(connect_pads
				(clearance 0)
			)
			(min_thickness 0.25)
			(keepout
				(tracks allowed)
				(vias not_allowed)
				(pads allowed)
				(copperpour not_allowed)
				(footprints allowed)
			)
			(placement
				(enabled no)
				(sheetname "")
			)
			(fill
				(thermal_gap 0.5)
				(thermal_bridge_width 0.5)
				(island_removal_mode 0)
			)
			(polygon
				(pts
					(arc
						(start 106.880914 -80.50022)
						(mid 106.118914 -80.50022)
						(end 106.880914 -80.50022)
					)
				)
			)
		)
		(zone
			(layer "F.Cu")
			(hatch none 0.5)
			(connect_pads
				(clearance 0)
			)
			(min_thickness 0.25)
			(keepout
				(tracks allowed)
				(vias not_allowed)
				(pads allowed)
				(copperpour not_allowed)
				(footprints allowed)
			)
			(placement
				(enabled no)
				(sheetname "")
			)
			(fill
				(thermal_gap 0.5)
				(thermal_bridge_width 0.5)
				(island_removal_mode 0)
			)
			(polygon
				(pts
					(arc
						(start 106.880914 -79.500222)
						(mid 106.118914 -79.500222)
						(end 106.880914 -79.500222)
					)
				)
			)
		)
		(zone
			(layer "F.Cu")
			(hatch none 0.5)
			(connect_pads
				(clearance 0)
			)
			(min_thickness 0.25)
			(keepout
				(tracks allowed)
				(vias not_allowed)
				(pads allowed)
				(copperpour not_allowed)
				(footprints allowed)
			)
			(placement
				(enabled no)
				(sheetname "")
			)
			(fill
				(thermal_gap 0.5)
				(thermal_bridge_width 0.5)
				(island_removal_mode 0)
			)
			(polygon
				(pts
					(arc
						(start 106.880914 -78.500224)
						(mid 106.118914 -78.500224)
						(end 106.880914 -78.500224)
					)
				)
			)
		)
		(zone
			(layer "F.Cu")
			(hatch none 0.5)
			(connect_pads
				(clearance 0)
			)
			(min_thickness 0.25)
			(keepout
				(tracks allowed)
				(vias not_allowed)
				(pads allowed)
				(copperpour not_allowed)
				(footprints allowed)
			)
			(placement
				(enabled no)
				(sheetname "")
			)
			(fill
				(thermal_gap 0.5)
				(thermal_bridge_width 0.5)
				(island_removal_mode 0)
			)
			(polygon
				(pts
					(arc
						(start 106.880914 -77.500226)
						(mid 106.118914 -77.500226)
						(end 106.880914 -77.500226)
					)
				)
			)
		)
		(zone
			(layer "F.Cu")
			(hatch none 0.5)
			(connect_pads
				(clearance 0)
			)
			(min_thickness 0.25)
			(keepout
				(tracks allowed)
				(vias not_allowed)
				(pads allowed)
				(copperpour not_allowed)
				(footprints allowed)
			)
			(placement
				(enabled no)
				(sheetname "")
			)
			(fill
				(thermal_gap 0.5)
				(thermal_bridge_width 0.5)
				(island_removal_mode 0)
			)
			(polygon
				(pts
					(arc
						(start 106.880914 -76.500228)
						(mid 106.118914 -76.500228)
						(end 106.880914 -76.500228)
					)
				)
			)
		)
		(zone
			(layer "F.Cu")
			(hatch none 0.5)
			(connect_pads
				(clearance 0)
			)
			(min_thickness 0.25)
			(keepout
				(tracks allowed)
				(vias not_allowed)
				(pads allowed)
				(copperpour not_allowed)
				(footprints allowed)
			)
			(placement
				(enabled no)
				(sheetname "")
			)
			(fill
				(thermal_gap 0.5)
				(thermal_bridge_width 0.5)
				(island_removal_mode 0)
			)
			(polygon
				(pts
					(arc
						(start 106.880914 -75.50023)
						(mid 106.118914 -75.50023)
						(end 106.880914 -75.50023)
					)
				)
			)
		)
		(zone
			(layer "F.Cu")
			(hatch none 0.5)
			(connect_pads
				(clearance 0)
			)
			(min_thickness 0.25)
			(keepout
				(tracks allowed)
				(vias not_allowed)
				(pads allowed)
				(copperpour not_allowed)
				(footprints allowed)
			)
			(placement
				(enabled no)
				(sheetname "")
			)
			(fill
				(thermal_gap 0.5)
				(thermal_bridge_width 0.5)
				(island_removal_mode 0)
			)
			(polygon
				(pts
					(arc
						(start 106.880914 -74.500232)
						(mid 106.118914 -74.500232)
						(end 106.880914 -74.500232)
					)
				)
			)
		)
		(zone
			(layer "F.Cu")
			(hatch none 0.5)
			(connect_pads
				(clearance 0)
			)
			(min_thickness 0.25)
			(keepout
				(tracks allowed)
				(vias not_allowed)
				(pads allowed)
				(copperpour not_allowed)
				(footprints allowed)
			)
			(placement
				(enabled no)
				(sheetname "")
			)
			(fill
				(thermal_gap 0.5)
				(thermal_bridge_width 0.5)
				(island_removal_mode 0)
			)
			(polygon
				(pts
					(arc
						(start 106.880914 -73.500234)
						(mid 106.118914 -73.500234)
						(end 106.880914 -73.500234)
					)
				)
			)
		)
		(zone
			(layer "F.Cu")
			(hatch none 0.5)
			(connect_pads
				(clearance 0)
			)
			(min_thickness 0.25)
			(keepout
				(tracks allowed)
				(vias not_allowed)
				(pads allowed)
				(copperpour not_allowed)
				(footprints allowed)
			)
			(placement
				(enabled no)
				(sheetname "")
			)
			(fill
				(thermal_gap 0.5)
				(thermal_bridge_width 0.5)
				(island_removal_mode 0)
			)
			(polygon
				(pts
					(arc
						(start 106.880914 -72.500236)
						(mid 106.118914 -72.500236)
						(end 106.880914 -72.500236)
					)
				)
			)
		)
		(zone
			(layer "F.Cu")
			(hatch none 0.5)
			(connect_pads
				(clearance 0)
			)
			(min_thickness 0.25)
			(keepout
				(tracks allowed)
				(vias not_allowed)
				(pads allowed)
				(copperpour not_allowed)
				(footprints allowed)
			)
			(placement
				(enabled no)
				(sheetname "")
			)
			(fill
				(thermal_gap 0.5)
				(thermal_bridge_width 0.5)
				(island_removal_mode 0)
			)
			(polygon
				(pts
					(arc
						(start 106.880914 -71.500238)
						(mid 106.118914 -71.500238)
						(end 106.880914 -71.500238)
					)
				)
			)
		)
		(zone
			(layer "F.Cu")
			(hatch none 0.5)
			(connect_pads
				(clearance 0)
			)
			(min_thickness 0.25)
			(keepout
				(tracks allowed)
				(vias not_allowed)
				(pads allowed)
				(copperpour not_allowed)
				(footprints allowed)
			)
			(placement
				(enabled no)
				(sheetname "")
			)
			(fill
				(thermal_gap 0.5)
				(thermal_bridge_width 0.5)
				(island_removal_mode 0)
			)
			(polygon
				(pts
					(arc
						(start 106.880914 -70.50024)
						(mid 106.118914 -70.50024)
						(end 106.880914 -70.50024)
					)
				)
			)
		)
		(zone
			(layer "F.Cu")
			(hatch none 0.5)
			(connect_pads
				(clearance 0)
			)
			(min_thickness 0.25)
			(keepout
				(tracks allowed)
				(vias not_allowed)
				(pads allowed)
				(copperpour not_allowed)
				(footprints allowed)
			)
			(placement
				(enabled no)
				(sheetname "")
			)
			(fill
				(thermal_gap 0.5)
				(thermal_bridge_width 0.5)
				(island_removal_mode 0)
			)
			(polygon
				(pts
					(arc
						(start 106.880914 -69.500242)
						(mid 106.118914 -69.500242)
						(end 106.880914 -69.500242)
					)
				)
			)
		)
		(zone
			(layer "F.Cu")
			(hatch none 0.5)
			(connect_pads
				(clearance 0)
			)
			(min_thickness 0.25)
			(keepout
				(tracks allowed)
				(vias not_allowed)
				(pads allowed)
				(copperpour not_allowed)
				(footprints allowed)
			)
			(placement
				(enabled no)
				(sheetname "")
			)
			(fill
				(thermal_gap 0.5)
				(thermal_bridge_width 0.5)
				(island_removal_mode 0)
			)
			(polygon
				(pts
					(arc
						(start 106.880914 -68.500244)
						(mid 106.118914 -68.500244)
						(end 106.880914 -68.500244)
					)
				)
			)
		)
		(zone
			(layer "F.Cu")
			(hatch none 0.5)
			(connect_pads
				(clearance 0)
			)
			(min_thickness 0.25)
			(keepout
				(tracks allowed)
				(vias not_allowed)
				(pads allowed)
				(copperpour not_allowed)
				(footprints allowed)
			)
			(placement
				(enabled no)
				(sheetname "")
			)
			(fill
				(thermal_gap 0.5)
				(thermal_bridge_width 0.5)
				(island_removal_mode 0)
			)
			(polygon
				(pts
					(arc
						(start 106.880914 -67.500246)
						(mid 106.118914 -67.500246)
						(end 106.880914 -67.500246)
					)
				)
			)
		)
		(zone
			(layer "F.Cu")
			(hatch none 0.5)
			(connect_pads
				(clearance 0)
			)
			(min_thickness 0.25)
			(keepout
				(tracks allowed)
				(vias not_allowed)
				(pads allowed)
				(copperpour not_allowed)
				(footprints allowed)
			)
			(placement
				(enabled no)
				(sheetname "")
			)
			(fill
				(thermal_gap 0.5)
				(thermal_bridge_width 0.5)
				(island_removal_mode 0)
			)
			(polygon
				(pts
					(arc
						(start 106.880914 -66.499994)
						(mid 106.118914 -66.499994)
						(end 106.880914 -66.499994)
					)
				)
			)
		)
		(zone
			(layer "F.Cu")
			(hatch none 0.5)
			(connect_pads
				(clearance 0)
			)
			(min_thickness 0.25)
			(keepout
				(tracks allowed)
				(vias not_allowed)
				(pads allowed)
				(copperpour not_allowed)
				(footprints allowed)
			)
			(placement
				(enabled no)
				(sheetname "")
			)
			(fill
				(thermal_gap 0.5)
				(thermal_bridge_width 0.5)
				(island_removal_mode 0)
			)
			(polygon
				(pts
					(arc
						(start 106.880914 -65.499996)
						(mid 106.118914 -65.499996)
						(end 106.880914 -65.499996)
					)
				)
			)
		)
		(zone
			(layer "F.Cu")
			(hatch none 0.5)
			(connect_pads
				(clearance 0)
			)
			(min_thickness 0.25)
			(keepout
				(tracks allowed)
				(vias not_allowed)
				(pads allowed)
				(copperpour not_allowed)
				(footprints allowed)
			)
			(placement
				(enabled no)
				(sheetname "")
			)
			(fill
				(thermal_gap 0.5)
				(thermal_bridge_width 0.5)
				(island_removal_mode 0)
			)
			(polygon
				(pts
					(arc
						(start 106.880914 -64.499998)
						(mid 106.118914 -64.499998)
						(end 106.880914 -64.499998)
					)
				)
			)
		)
		(zone
			(layer "F.Cu")
			(hatch none 0.5)
			(connect_pads
				(clearance 0)
			)
			(min_thickness 0.25)
			(keepout
				(tracks allowed)
				(vias not_allowed)
				(pads allowed)
				(copperpour not_allowed)
				(footprints allowed)
			)
			(placement
				(enabled no)
				(sheetname "")
			)
			(fill
				(thermal_gap 0.5)
				(thermal_bridge_width 0.5)
				(island_removal_mode 0)
			)
			(polygon
				(pts
					(arc
						(start 106.880914 -63.5)
						(mid 106.118914 -63.5)
						(end 106.880914 -63.5)
					)
				)
			)
		)
		(zone
			(layer "F.Cu")
			(hatch none 0.5)
			(connect_pads
				(clearance 0)
			)
			(min_thickness 0.25)
			(keepout
				(tracks allowed)
				(vias not_allowed)
				(pads allowed)
				(copperpour not_allowed)
				(footprints allowed)
			)
			(placement
				(enabled no)
				(sheetname "")
			)
			(fill
				(thermal_gap 0.5)
				(thermal_bridge_width 0.5)
				(island_removal_mode 0)
			)
			(polygon
				(pts
					(arc
						(start 106.880914 -62.500002)
						(mid 106.118914 -62.500002)
						(end 106.880914 -62.500002)
					)
				)
			)
		)
		(zone
			(layer "F.Cu")
			(hatch none 0.5)
			(connect_pads
				(clearance 0)
			)
			(min_thickness 0.25)
			(keepout
				(tracks allowed)
				(vias not_allowed)
				(pads allowed)
				(copperpour not_allowed)
				(footprints allowed)
			)
			(placement
				(enabled no)
				(sheetname "")
			)
			(fill
				(thermal_gap 0.5)
				(thermal_bridge_width 0.5)
				(island_removal_mode 0)
			)
			(polygon
				(pts
					(arc
						(start 106.880914 -61.500004)
						(mid 106.118914 -61.500004)
						(end 106.880914 -61.500004)
					)
				)
			)
		)
		(zone
			(layer "F.Cu")
			(hatch none 0.5)
			(connect_pads
				(clearance 0)
			)
			(min_thickness 0.25)
			(keepout
				(tracks allowed)
				(vias not_allowed)
				(pads allowed)
				(copperpour not_allowed)
				(footprints allowed)
			)
			(placement
				(enabled no)
				(sheetname "")
			)
			(fill
				(thermal_gap 0.5)
				(thermal_bridge_width 0.5)
				(island_removal_mode 0)
			)
			(polygon
				(pts
					(arc
						(start 106.880914 -60.500006)
						(mid 106.118914 -60.500006)
						(end 106.880914 -60.500006)
					)
				)
			)
		)
		(zone
			(layer "F.Cu")
			(hatch none 0.5)
			(connect_pads
				(clearance 0)
			)
			(min_thickness 0.25)
			(keepout
				(tracks allowed)
				(vias not_allowed)
				(pads allowed)
				(copperpour not_allowed)
				(footprints allowed)
			)
			(placement
				(enabled no)
				(sheetname "")
			)
			(fill
				(thermal_gap 0.5)
				(thermal_bridge_width 0.5)
				(island_removal_mode 0)
			)
			(polygon
				(pts
					(arc
						(start 106.880914 -59.500008)
						(mid 106.118914 -59.500008)
						(end 106.880914 -59.500008)
					)
				)
			)
		)
		(zone
			(layer "F.Cu")
			(hatch none 0.5)
			(connect_pads
				(clearance 0)
			)
			(min_thickness 0.25)
			(keepout
				(tracks allowed)
				(vias not_allowed)
				(pads allowed)
				(copperpour not_allowed)
				(footprints allowed)
			)
			(placement
				(enabled no)
				(sheetname "")
			)
			(fill
				(thermal_gap 0.5)
				(thermal_bridge_width 0.5)
				(island_removal_mode 0)
			)
			(polygon
				(pts
					(arc
						(start 106.880914 -58.50001)
						(mid 106.118914 -58.50001)
						(end 106.880914 -58.50001)
					)
				)
			)
		)
		(zone
			(layer "F.Cu")
			(hatch none 0.5)
			(connect_pads
				(clearance 0)
			)
			(min_thickness 0.25)
			(keepout
				(tracks allowed)
				(vias not_allowed)
				(pads allowed)
				(copperpour not_allowed)
				(footprints allowed)
			)
			(placement
				(enabled no)
				(sheetname "")
			)
			(fill
				(thermal_gap 0.5)
				(thermal_bridge_width 0.5)
				(island_removal_mode 0)
			)
			(polygon
				(pts
					(arc
						(start 106.880914 -57.500012)
						(mid 106.118914 -57.500012)
						(end 106.880914 -57.500012)
					)
				)
			)
		)
		(zone
			(layer "F.Cu")
			(hatch none 0.5)
			(connect_pads
				(clearance 0)
			)
			(min_thickness 0.25)
			(keepout
				(tracks allowed)
				(vias not_allowed)
				(pads allowed)
				(copperpour not_allowed)
				(footprints allowed)
			)
			(placement
				(enabled no)
				(sheetname "")
			)
			(fill
				(thermal_gap 0.5)
				(thermal_bridge_width 0.5)
				(island_removal_mode 0)
			)
			(polygon
				(pts
					(arc
						(start 106.880914 -56.500014)
						(mid 106.118914 -56.500014)
						(end 106.880914 -56.500014)
					)
				)
			)
		)
		(zone
			(layer "F.Cu")
			(hatch none 0.5)
			(connect_pads
				(clearance 0)
			)
			(min_thickness 0.25)
			(keepout
				(tracks allowed)
				(vias not_allowed)
				(pads allowed)
				(copperpour not_allowed)
				(footprints allowed)
			)
			(placement
				(enabled no)
				(sheetname "")
			)
			(fill
				(thermal_gap 0.5)
				(thermal_bridge_width 0.5)
				(island_removal_mode 0)
			)
			(polygon
				(pts
					(arc
						(start 106.880914 -55.500016)
						(mid 106.118914 -55.500016)
						(end 106.880914 -55.500016)
					)
				)
			)
		)
		(zone
			(layer "F.Cu")
			(hatch none 0.5)
			(connect_pads
				(clearance 0)
			)
			(min_thickness 0.25)
			(keepout
				(tracks allowed)
				(vias not_allowed)
				(pads allowed)
				(copperpour not_allowed)
				(footprints allowed)
			)
			(placement
				(enabled no)
				(sheetname "")
			)
			(fill
				(thermal_gap 0.5)
				(thermal_bridge_width 0.5)
				(island_removal_mode 0)
			)
			(polygon
				(pts
					(arc
						(start 106.880914 -54.500018)
						(mid 106.118914 -54.500018)
						(end 106.880914 -54.500018)
					)
				)
			)
		)
		(zone
			(layer "F.Cu")
			(hatch none 0.5)
			(connect_pads
				(clearance 0)
			)
			(min_thickness 0.25)
			(keepout
				(tracks allowed)
				(vias not_allowed)
				(pads allowed)
				(copperpour not_allowed)
				(footprints allowed)
			)
			(placement
				(enabled no)
				(sheetname "")
			)
			(fill
				(thermal_gap 0.5)
				(thermal_bridge_width 0.5)
				(island_removal_mode 0)
			)
			(polygon
				(pts
					(arc
						(start 106.880914 -53.50002)
						(mid 106.118914 -53.50002)
						(end 106.880914 -53.50002)
					)
				)
			)
		)
		(zone
			(layer "F.Cu")
			(hatch none 0.5)
			(connect_pads
				(clearance 0)
			)
			(min_thickness 0.25)
			(keepout
				(tracks allowed)
				(vias not_allowed)
				(pads allowed)
				(copperpour not_allowed)
				(footprints allowed)
			)
			(placement
				(enabled no)
				(sheetname "")
			)
			(fill
				(thermal_gap 0.5)
				(thermal_bridge_width 0.5)
				(island_removal_mode 0)
			)
			(polygon
				(pts
					(arc
						(start 106.880914 -52.500022)
						(mid 106.118914 -52.500022)
						(end 106.880914 -52.500022)
					)
				)
			)
		)
		(zone
			(layer "F.Cu")
			(hatch none 0.5)
			(connect_pads
				(clearance 0)
			)
			(min_thickness 0.25)
			(keepout
				(tracks allowed)
				(vias not_allowed)
				(pads allowed)
				(copperpour not_allowed)
				(footprints allowed)
			)
			(placement
				(enabled no)
				(sheetname "")
			)
			(fill
				(thermal_gap 0.5)
				(thermal_bridge_width 0.5)
				(island_removal_mode 0)
			)
			(polygon
				(pts
					(arc
						(start 106.880914 -51.500024)
						(mid 106.118914 -51.500024)
						(end 106.880914 -51.500024)
					)
				)
			)
		)
		(zone
			(layer "F.Cu")
			(hatch none 0.5)
			(connect_pads
				(clearance 0)
			)
			(min_thickness 0.25)
			(keepout
				(tracks allowed)
				(vias not_allowed)
				(pads allowed)
				(copperpour not_allowed)
				(footprints allowed)
			)
			(placement
				(enabled no)
				(sheetname "")
			)
			(fill
				(thermal_gap 0.5)
				(thermal_bridge_width 0.5)
				(island_removal_mode 0)
			)
			(polygon
				(pts
					(arc
						(start 107.880912 -82.500216)
						(mid 107.118912 -82.500216)
						(end 107.880912 -82.500216)
					)
				)
			)
		)
		(zone
			(layer "F.Cu")
			(hatch none 0.5)
			(connect_pads
				(clearance 0)
			)
			(min_thickness 0.25)
			(keepout
				(tracks allowed)
				(vias not_allowed)
				(pads allowed)
				(copperpour not_allowed)
				(footprints allowed)
			)
			(placement
				(enabled no)
				(sheetname "")
			)
			(fill
				(thermal_gap 0.5)
				(thermal_bridge_width 0.5)
				(island_removal_mode 0)
			)
			(polygon
				(pts
					(arc
						(start 107.880912 -81.500218)
						(mid 107.118912 -81.500218)
						(end 107.880912 -81.500218)
					)
				)
			)
		)
		(zone
			(layer "F.Cu")
			(hatch none 0.5)
			(connect_pads
				(clearance 0)
			)
			(min_thickness 0.25)
			(keepout
				(tracks allowed)
				(vias not_allowed)
				(pads allowed)
				(copperpour not_allowed)
				(footprints allowed)
			)
			(placement
				(enabled no)
				(sheetname "")
			)
			(fill
				(thermal_gap 0.5)
				(thermal_bridge_width 0.5)
				(island_removal_mode 0)
			)
			(polygon
				(pts
					(arc
						(start 107.880912 -80.50022)
						(mid 107.118912 -80.50022)
						(end 107.880912 -80.50022)
					)
				)
			)
		)
		(zone
			(layer "F.Cu")
			(hatch none 0.5)
			(connect_pads
				(clearance 0)
			)
			(min_thickness 0.25)
			(keepout
				(tracks allowed)
				(vias not_allowed)
				(pads allowed)
				(copperpour not_allowed)
				(footprints allowed)
			)
			(placement
				(enabled no)
				(sheetname "")
			)
			(fill
				(thermal_gap 0.5)
				(thermal_bridge_width 0.5)
				(island_removal_mode 0)
			)
			(polygon
				(pts
					(arc
						(start 107.880912 -79.500222)
						(mid 107.118912 -79.500222)
						(end 107.880912 -79.500222)
					)
				)
			)
		)
		(zone
			(layer "F.Cu")
			(hatch none 0.5)
			(connect_pads
				(clearance 0)
			)
			(min_thickness 0.25)
			(keepout
				(tracks allowed)
				(vias not_allowed)
				(pads allowed)
				(copperpour not_allowed)
				(footprints allowed)
			)
			(placement
				(enabled no)
				(sheetname "")
			)
			(fill
				(thermal_gap 0.5)
				(thermal_bridge_width 0.5)
				(island_removal_mode 0)
			)
			(polygon
				(pts
					(arc
						(start 107.880912 -78.500224)
						(mid 107.118912 -78.500224)
						(end 107.880912 -78.500224)
					)
				)
			)
		)
		(zone
			(layer "F.Cu")
			(hatch none 0.5)
			(connect_pads
				(clearance 0)
			)
			(min_thickness 0.25)
			(keepout
				(tracks allowed)
				(vias not_allowed)
				(pads allowed)
				(copperpour not_allowed)
				(footprints allowed)
			)
			(placement
				(enabled no)
				(sheetname "")
			)
			(fill
				(thermal_gap 0.5)
				(thermal_bridge_width 0.5)
				(island_removal_mode 0)
			)
			(polygon
				(pts
					(arc
						(start 107.880912 -77.500226)
						(mid 107.118912 -77.500226)
						(end 107.880912 -77.500226)
					)
				)
			)
		)
		(zone
			(layer "F.Cu")
			(hatch none 0.5)
			(connect_pads
				(clearance 0)
			)
			(min_thickness 0.25)
			(keepout
				(tracks allowed)
				(vias not_allowed)
				(pads allowed)
				(copperpour not_allowed)
				(footprints allowed)
			)
			(placement
				(enabled no)
				(sheetname "")
			)
			(fill
				(thermal_gap 0.5)
				(thermal_bridge_width 0.5)
				(island_removal_mode 0)
			)
			(polygon
				(pts
					(arc
						(start 107.880912 -76.500228)
						(mid 107.118912 -76.500228)
						(end 107.880912 -76.500228)
					)
				)
			)
		)
		(zone
			(layer "F.Cu")
			(hatch none 0.5)
			(connect_pads
				(clearance 0)
			)
			(min_thickness 0.25)
			(keepout
				(tracks allowed)
				(vias not_allowed)
				(pads allowed)
				(copperpour not_allowed)
				(footprints allowed)
			)
			(placement
				(enabled no)
				(sheetname "")
			)
			(fill
				(thermal_gap 0.5)
				(thermal_bridge_width 0.5)
				(island_removal_mode 0)
			)
			(polygon
				(pts
					(arc
						(start 107.880912 -75.50023)
						(mid 107.118912 -75.50023)
						(end 107.880912 -75.50023)
					)
				)
			)
		)
		(zone
			(layer "F.Cu")
			(hatch none 0.5)
			(connect_pads
				(clearance 0)
			)
			(min_thickness 0.25)
			(keepout
				(tracks allowed)
				(vias not_allowed)
				(pads allowed)
				(copperpour not_allowed)
				(footprints allowed)
			)
			(placement
				(enabled no)
				(sheetname "")
			)
			(fill
				(thermal_gap 0.5)
				(thermal_bridge_width 0.5)
				(island_removal_mode 0)
			)
			(polygon
				(pts
					(arc
						(start 107.880912 -74.500232)
						(mid 107.118912 -74.500232)
						(end 107.880912 -74.500232)
					)
				)
			)
		)
		(zone
			(layer "F.Cu")
			(hatch none 0.5)
			(connect_pads
				(clearance 0)
			)
			(min_thickness 0.25)
			(keepout
				(tracks allowed)
				(vias not_allowed)
				(pads allowed)
				(copperpour not_allowed)
				(footprints allowed)
			)
			(placement
				(enabled no)
				(sheetname "")
			)
			(fill
				(thermal_gap 0.5)
				(thermal_bridge_width 0.5)
				(island_removal_mode 0)
			)
			(polygon
				(pts
					(arc
						(start 107.880912 -73.500234)
						(mid 107.118912 -73.500234)
						(end 107.880912 -73.500234)
					)
				)
			)
		)
		(zone
			(layer "F.Cu")
			(hatch none 0.5)
			(connect_pads
				(clearance 0)
			)
			(min_thickness 0.25)
			(keepout
				(tracks allowed)
				(vias not_allowed)
				(pads allowed)
				(copperpour not_allowed)
				(footprints allowed)
			)
			(placement
				(enabled no)
				(sheetname "")
			)
			(fill
				(thermal_gap 0.5)
				(thermal_bridge_width 0.5)
				(island_removal_mode 0)
			)
			(polygon
				(pts
					(arc
						(start 107.880912 -72.500236)
						(mid 107.118912 -72.500236)
						(end 107.880912 -72.500236)
					)
				)
			)
		)
		(zone
			(layer "F.Cu")
			(hatch none 0.5)
			(connect_pads
				(clearance 0)
			)
			(min_thickness 0.25)
			(keepout
				(tracks allowed)
				(vias not_allowed)
				(pads allowed)
				(copperpour not_allowed)
				(footprints allowed)
			)
			(placement
				(enabled no)
				(sheetname "")
			)
			(fill
				(thermal_gap 0.5)
				(thermal_bridge_width 0.5)
				(island_removal_mode 0)
			)
			(polygon
				(pts
					(arc
						(start 107.880912 -71.500238)
						(mid 107.118912 -71.500238)
						(end 107.880912 -71.500238)
					)
				)
			)
		)
		(zone
			(layer "F.Cu")
			(hatch none 0.5)
			(connect_pads
				(clearance 0)
			)
			(min_thickness 0.25)
			(keepout
				(tracks allowed)
				(vias not_allowed)
				(pads allowed)
				(copperpour not_allowed)
				(footprints allowed)
			)
			(placement
				(enabled no)
				(sheetname "")
			)
			(fill
				(thermal_gap 0.5)
				(thermal_bridge_width 0.5)
				(island_removal_mode 0)
			)
			(polygon
				(pts
					(arc
						(start 107.880912 -70.50024)
						(mid 107.118912 -70.50024)
						(end 107.880912 -70.50024)
					)
				)
			)
		)
		(zone
			(layer "F.Cu")
			(hatch none 0.5)
			(connect_pads
				(clearance 0)
			)
			(min_thickness 0.25)
			(keepout
				(tracks allowed)
				(vias not_allowed)
				(pads allowed)
				(copperpour not_allowed)
				(footprints allowed)
			)
			(placement
				(enabled no)
				(sheetname "")
			)
			(fill
				(thermal_gap 0.5)
				(thermal_bridge_width 0.5)
				(island_removal_mode 0)
			)
			(polygon
				(pts
					(arc
						(start 107.880912 -69.500242)
						(mid 107.118912 -69.500242)
						(end 107.880912 -69.500242)
					)
				)
			)
		)
		(zone
			(layer "F.Cu")
			(hatch none 0.5)
			(connect_pads
				(clearance 0)
			)
			(min_thickness 0.25)
			(keepout
				(tracks allowed)
				(vias not_allowed)
				(pads allowed)
				(copperpour not_allowed)
				(footprints allowed)
			)
			(placement
				(enabled no)
				(sheetname "")
			)
			(fill
				(thermal_gap 0.5)
				(thermal_bridge_width 0.5)
				(island_removal_mode 0)
			)
			(polygon
				(pts
					(arc
						(start 107.880912 -68.500244)
						(mid 107.118912 -68.500244)
						(end 107.880912 -68.500244)
					)
				)
			)
		)
		(zone
			(layer "F.Cu")
			(hatch none 0.5)
			(connect_pads
				(clearance 0)
			)
			(min_thickness 0.25)
			(keepout
				(tracks allowed)
				(vias not_allowed)
				(pads allowed)
				(copperpour not_allowed)
				(footprints allowed)
			)
			(placement
				(enabled no)
				(sheetname "")
			)
			(fill
				(thermal_gap 0.5)
				(thermal_bridge_width 0.5)
				(island_removal_mode 0)
			)
			(polygon
				(pts
					(arc
						(start 107.880912 -67.500246)
						(mid 107.118912 -67.500246)
						(end 107.880912 -67.500246)
					)
				)
			)
		)
		(zone
			(layer "F.Cu")
			(hatch none 0.5)
			(connect_pads
				(clearance 0)
			)
			(min_thickness 0.25)
			(keepout
				(tracks allowed)
				(vias not_allowed)
				(pads allowed)
				(copperpour not_allowed)
				(footprints allowed)
			)
			(placement
				(enabled no)
				(sheetname "")
			)
			(fill
				(thermal_gap 0.5)
				(thermal_bridge_width 0.5)
				(island_removal_mode 0)
			)
			(polygon
				(pts
					(arc
						(start 107.880912 -66.499994)
						(mid 107.118912 -66.499994)
						(end 107.880912 -66.499994)
					)
				)
			)
		)
		(zone
			(layer "F.Cu")
			(hatch none 0.5)
			(connect_pads
				(clearance 0)
			)
			(min_thickness 0.25)
			(keepout
				(tracks allowed)
				(vias not_allowed)
				(pads allowed)
				(copperpour not_allowed)
				(footprints allowed)
			)
			(placement
				(enabled no)
				(sheetname "")
			)
			(fill
				(thermal_gap 0.5)
				(thermal_bridge_width 0.5)
				(island_removal_mode 0)
			)
			(polygon
				(pts
					(arc
						(start 107.880912 -65.499996)
						(mid 107.118912 -65.499996)
						(end 107.880912 -65.499996)
					)
				)
			)
		)
		(zone
			(layer "F.Cu")
			(hatch none 0.5)
			(connect_pads
				(clearance 0)
			)
			(min_thickness 0.25)
			(keepout
				(tracks allowed)
				(vias not_allowed)
				(pads allowed)
				(copperpour not_allowed)
				(footprints allowed)
			)
			(placement
				(enabled no)
				(sheetname "")
			)
			(fill
				(thermal_gap 0.5)
				(thermal_bridge_width 0.5)
				(island_removal_mode 0)
			)
			(polygon
				(pts
					(arc
						(start 107.880912 -64.499998)
						(mid 107.118912 -64.499998)
						(end 107.880912 -64.499998)
					)
				)
			)
		)
		(zone
			(layer "F.Cu")
			(hatch none 0.5)
			(connect_pads
				(clearance 0)
			)
			(min_thickness 0.25)
			(keepout
				(tracks allowed)
				(vias not_allowed)
				(pads allowed)
				(copperpour not_allowed)
				(footprints allowed)
			)
			(placement
				(enabled no)
				(sheetname "")
			)
			(fill
				(thermal_gap 0.5)
				(thermal_bridge_width 0.5)
				(island_removal_mode 0)
			)
			(polygon
				(pts
					(arc
						(start 107.880912 -63.5)
						(mid 107.118912 -63.5)
						(end 107.880912 -63.5)
					)
				)
			)
		)
		(zone
			(layer "F.Cu")
			(hatch none 0.5)
			(connect_pads
				(clearance 0)
			)
			(min_thickness 0.25)
			(keepout
				(tracks allowed)
				(vias not_allowed)
				(pads allowed)
				(copperpour not_allowed)
				(footprints allowed)
			)
			(placement
				(enabled no)
				(sheetname "")
			)
			(fill
				(thermal_gap 0.5)
				(thermal_bridge_width 0.5)
				(island_removal_mode 0)
			)
			(polygon
				(pts
					(arc
						(start 107.880912 -62.500002)
						(mid 107.118912 -62.500002)
						(end 107.880912 -62.500002)
					)
				)
			)
		)
		(zone
			(layer "F.Cu")
			(hatch none 0.5)
			(connect_pads
				(clearance 0)
			)
			(min_thickness 0.25)
			(keepout
				(tracks allowed)
				(vias not_allowed)
				(pads allowed)
				(copperpour not_allowed)
				(footprints allowed)
			)
			(placement
				(enabled no)
				(sheetname "")
			)
			(fill
				(thermal_gap 0.5)
				(thermal_bridge_width 0.5)
				(island_removal_mode 0)
			)
			(polygon
				(pts
					(arc
						(start 107.880912 -61.500004)
						(mid 107.118912 -61.500004)
						(end 107.880912 -61.500004)
					)
				)
			)
		)
		(zone
			(layer "F.Cu")
			(hatch none 0.5)
			(connect_pads
				(clearance 0)
			)
			(min_thickness 0.25)
			(keepout
				(tracks allowed)
				(vias not_allowed)
				(pads allowed)
				(copperpour not_allowed)
				(footprints allowed)
			)
			(placement
				(enabled no)
				(sheetname "")
			)
			(fill
				(thermal_gap 0.5)
				(thermal_bridge_width 0.5)
				(island_removal_mode 0)
			)
			(polygon
				(pts
					(arc
						(start 107.880912 -60.500006)
						(mid 107.118912 -60.500006)
						(end 107.880912 -60.500006)
					)
				)
			)
		)
		(zone
			(layer "F.Cu")
			(hatch none 0.5)
			(connect_pads
				(clearance 0)
			)
			(min_thickness 0.25)
			(keepout
				(tracks allowed)
				(vias not_allowed)
				(pads allowed)
				(copperpour not_allowed)
				(footprints allowed)
			)
			(placement
				(enabled no)
				(sheetname "")
			)
			(fill
				(thermal_gap 0.5)
				(thermal_bridge_width 0.5)
				(island_removal_mode 0)
			)
			(polygon
				(pts
					(arc
						(start 107.880912 -59.500008)
						(mid 107.118912 -59.500008)
						(end 107.880912 -59.500008)
					)
				)
			)
		)
		(zone
			(layer "F.Cu")
			(hatch none 0.5)
			(connect_pads
				(clearance 0)
			)
			(min_thickness 0.25)
			(keepout
				(tracks allowed)
				(vias not_allowed)
				(pads allowed)
				(copperpour not_allowed)
				(footprints allowed)
			)
			(placement
				(enabled no)
				(sheetname "")
			)
			(fill
				(thermal_gap 0.5)
				(thermal_bridge_width 0.5)
				(island_removal_mode 0)
			)
			(polygon
				(pts
					(arc
						(start 107.880912 -58.50001)
						(mid 107.118912 -58.50001)
						(end 107.880912 -58.50001)
					)
				)
			)
		)
		(zone
			(layer "F.Cu")
			(hatch none 0.5)
			(connect_pads
				(clearance 0)
			)
			(min_thickness 0.25)
			(keepout
				(tracks allowed)
				(vias not_allowed)
				(pads allowed)
				(copperpour not_allowed)
				(footprints allowed)
			)
			(placement
				(enabled no)
				(sheetname "")
			)
			(fill
				(thermal_gap 0.5)
				(thermal_bridge_width 0.5)
				(island_removal_mode 0)
			)
			(polygon
				(pts
					(arc
						(start 107.880912 -57.500012)
						(mid 107.118912 -57.500012)
						(end 107.880912 -57.500012)
					)
				)
			)
		)
		(zone
			(layer "F.Cu")
			(hatch none 0.5)
			(connect_pads
				(clearance 0)
			)
			(min_thickness 0.25)
			(keepout
				(tracks allowed)
				(vias not_allowed)
				(pads allowed)
				(copperpour not_allowed)
				(footprints allowed)
			)
			(placement
				(enabled no)
				(sheetname "")
			)
			(fill
				(thermal_gap 0.5)
				(thermal_bridge_width 0.5)
				(island_removal_mode 0)
			)
			(polygon
				(pts
					(arc
						(start 107.880912 -56.500014)
						(mid 107.118912 -56.500014)
						(end 107.880912 -56.500014)
					)
				)
			)
		)
		(zone
			(layer "F.Cu")
			(hatch none 0.5)
			(connect_pads
				(clearance 0)
			)
			(min_thickness 0.25)
			(keepout
				(tracks allowed)
				(vias not_allowed)
				(pads allowed)
				(copperpour not_allowed)
				(footprints allowed)
			)
			(placement
				(enabled no)
				(sheetname "")
			)
			(fill
				(thermal_gap 0.5)
				(thermal_bridge_width 0.5)
				(island_removal_mode 0)
			)
			(polygon
				(pts
					(arc
						(start 107.880912 -55.500016)
						(mid 107.118912 -55.500016)
						(end 107.880912 -55.500016)
					)
				)
			)
		)
		(zone
			(layer "F.Cu")
			(hatch none 0.5)
			(connect_pads
				(clearance 0)
			)
			(min_thickness 0.25)
			(keepout
				(tracks allowed)
				(vias not_allowed)
				(pads allowed)
				(copperpour not_allowed)
				(footprints allowed)
			)
			(placement
				(enabled no)
				(sheetname "")
			)
			(fill
				(thermal_gap 0.5)
				(thermal_bridge_width 0.5)
				(island_removal_mode 0)
			)
			(polygon
				(pts
					(arc
						(start 107.880912 -54.500018)
						(mid 107.118912 -54.500018)
						(end 107.880912 -54.500018)
					)
				)
			)
		)
		(zone
			(layer "F.Cu")
			(hatch none 0.5)
			(connect_pads
				(clearance 0)
			)
			(min_thickness 0.25)
			(keepout
				(tracks allowed)
				(vias not_allowed)
				(pads allowed)
				(copperpour not_allowed)
				(footprints allowed)
			)
			(placement
				(enabled no)
				(sheetname "")
			)
			(fill
				(thermal_gap 0.5)
				(thermal_bridge_width 0.5)
				(island_removal_mode 0)
			)
			(polygon
				(pts
					(arc
						(start 107.880912 -53.50002)
						(mid 107.118912 -53.50002)
						(end 107.880912 -53.50002)
					)
				)
			)
		)
		(zone
			(layer "F.Cu")
			(hatch none 0.5)
			(connect_pads
				(clearance 0)
			)
			(min_thickness 0.25)
			(keepout
				(tracks allowed)
				(vias not_allowed)
				(pads allowed)
				(copperpour not_allowed)
				(footprints allowed)
			)
			(placement
				(enabled no)
				(sheetname "")
			)
			(fill
				(thermal_gap 0.5)
				(thermal_bridge_width 0.5)
				(island_removal_mode 0)
			)
			(polygon
				(pts
					(arc
						(start 107.880912 -52.500022)
						(mid 107.118912 -52.500022)
						(end 107.880912 -52.500022)
					)
				)
			)
		)
		(zone
			(layer "F.Cu")
			(hatch none 0.5)
			(connect_pads
				(clearance 0)
			)
			(min_thickness 0.25)
			(keepout
				(tracks allowed)
				(vias not_allowed)
				(pads allowed)
				(copperpour not_allowed)
				(footprints allowed)
			)
			(placement
				(enabled no)
				(sheetname "")
			)
			(fill
				(thermal_gap 0.5)
				(thermal_bridge_width 0.5)
				(island_removal_mode 0)
			)
			(polygon
				(pts
					(arc
						(start 107.880912 -51.500024)
						(mid 107.118912 -51.500024)
						(end 107.880912 -51.500024)
					)
				)
			)
		)
		(zone
			(layer "F.Cu")
			(hatch none 0.5)
			(connect_pads
				(clearance 0)
			)
			(min_thickness 0.25)
			(keepout
				(tracks allowed)
				(vias not_allowed)
				(pads allowed)
				(copperpour not_allowed)
				(footprints allowed)
			)
			(placement
				(enabled no)
				(sheetname "")
			)
			(fill
				(thermal_gap 0.5)
				(thermal_bridge_width 0.5)
				(island_removal_mode 0)
			)
			(polygon
				(pts
					(arc
						(start 108.88091 -82.500216)
						(mid 108.11891 -82.500216)
						(end 108.88091 -82.500216)
					)
				)
			)
		)
		(zone
			(layer "F.Cu")
			(hatch none 0.5)
			(connect_pads
				(clearance 0)
			)
			(min_thickness 0.25)
			(keepout
				(tracks allowed)
				(vias not_allowed)
				(pads allowed)
				(copperpour not_allowed)
				(footprints allowed)
			)
			(placement
				(enabled no)
				(sheetname "")
			)
			(fill
				(thermal_gap 0.5)
				(thermal_bridge_width 0.5)
				(island_removal_mode 0)
			)
			(polygon
				(pts
					(arc
						(start 108.88091 -81.500218)
						(mid 108.11891 -81.500218)
						(end 108.88091 -81.500218)
					)
				)
			)
		)
		(zone
			(layer "F.Cu")
			(hatch none 0.5)
			(connect_pads
				(clearance 0)
			)
			(min_thickness 0.25)
			(keepout
				(tracks allowed)
				(vias not_allowed)
				(pads allowed)
				(copperpour not_allowed)
				(footprints allowed)
			)
			(placement
				(enabled no)
				(sheetname "")
			)
			(fill
				(thermal_gap 0.5)
				(thermal_bridge_width 0.5)
				(island_removal_mode 0)
			)
			(polygon
				(pts
					(arc
						(start 108.88091 -80.50022)
						(mid 108.11891 -80.50022)
						(end 108.88091 -80.50022)
					)
				)
			)
		)
		(zone
			(layer "F.Cu")
			(hatch none 0.5)
			(connect_pads
				(clearance 0)
			)
			(min_thickness 0.25)
			(keepout
				(tracks allowed)
				(vias not_allowed)
				(pads allowed)
				(copperpour not_allowed)
				(footprints allowed)
			)
			(placement
				(enabled no)
				(sheetname "")
			)
			(fill
				(thermal_gap 0.5)
				(thermal_bridge_width 0.5)
				(island_removal_mode 0)
			)
			(polygon
				(pts
					(arc
						(start 108.88091 -79.500222)
						(mid 108.11891 -79.500222)
						(end 108.88091 -79.500222)
					)
				)
			)
		)
		(zone
			(layer "F.Cu")
			(hatch none 0.5)
			(connect_pads
				(clearance 0)
			)
			(min_thickness 0.25)
			(keepout
				(tracks allowed)
				(vias not_allowed)
				(pads allowed)
				(copperpour not_allowed)
				(footprints allowed)
			)
			(placement
				(enabled no)
				(sheetname "")
			)
			(fill
				(thermal_gap 0.5)
				(thermal_bridge_width 0.5)
				(island_removal_mode 0)
			)
			(polygon
				(pts
					(arc
						(start 108.88091 -78.500224)
						(mid 108.11891 -78.500224)
						(end 108.88091 -78.500224)
					)
				)
			)
		)
		(zone
			(layer "F.Cu")
			(hatch none 0.5)
			(connect_pads
				(clearance 0)
			)
			(min_thickness 0.25)
			(keepout
				(tracks allowed)
				(vias not_allowed)
				(pads allowed)
				(copperpour not_allowed)
				(footprints allowed)
			)
			(placement
				(enabled no)
				(sheetname "")
			)
			(fill
				(thermal_gap 0.5)
				(thermal_bridge_width 0.5)
				(island_removal_mode 0)
			)
			(polygon
				(pts
					(arc
						(start 108.88091 -77.500226)
						(mid 108.11891 -77.500226)
						(end 108.88091 -77.500226)
					)
				)
			)
		)
		(zone
			(layer "F.Cu")
			(hatch none 0.5)
			(connect_pads
				(clearance 0)
			)
			(min_thickness 0.25)
			(keepout
				(tracks allowed)
				(vias not_allowed)
				(pads allowed)
				(copperpour not_allowed)
				(footprints allowed)
			)
			(placement
				(enabled no)
				(sheetname "")
			)
			(fill
				(thermal_gap 0.5)
				(thermal_bridge_width 0.5)
				(island_removal_mode 0)
			)
			(polygon
				(pts
					(arc
						(start 108.88091 -76.500228)
						(mid 108.11891 -76.500228)
						(end 108.88091 -76.500228)
					)
				)
			)
		)
		(zone
			(layer "F.Cu")
			(hatch none 0.5)
			(connect_pads
				(clearance 0)
			)
			(min_thickness 0.25)
			(keepout
				(tracks allowed)
				(vias not_allowed)
				(pads allowed)
				(copperpour not_allowed)
				(footprints allowed)
			)
			(placement
				(enabled no)
				(sheetname "")
			)
			(fill
				(thermal_gap 0.5)
				(thermal_bridge_width 0.5)
				(island_removal_mode 0)
			)
			(polygon
				(pts
					(arc
						(start 108.88091 -75.50023)
						(mid 108.11891 -75.50023)
						(end 108.88091 -75.50023)
					)
				)
			)
		)
		(zone
			(layer "F.Cu")
			(hatch none 0.5)
			(connect_pads
				(clearance 0)
			)
			(min_thickness 0.25)
			(keepout
				(tracks allowed)
				(vias not_allowed)
				(pads allowed)
				(copperpour not_allowed)
				(footprints allowed)
			)
			(placement
				(enabled no)
				(sheetname "")
			)
			(fill
				(thermal_gap 0.5)
				(thermal_bridge_width 0.5)
				(island_removal_mode 0)
			)
			(polygon
				(pts
					(arc
						(start 108.88091 -74.500232)
						(mid 108.11891 -74.500232)
						(end 108.88091 -74.500232)
					)
				)
			)
		)
		(zone
			(layer "F.Cu")
			(hatch none 0.5)
			(connect_pads
				(clearance 0)
			)
			(min_thickness 0.25)
			(keepout
				(tracks allowed)
				(vias not_allowed)
				(pads allowed)
				(copperpour not_allowed)
				(footprints allowed)
			)
			(placement
				(enabled no)
				(sheetname "")
			)
			(fill
				(thermal_gap 0.5)
				(thermal_bridge_width 0.5)
				(island_removal_mode 0)
			)
			(polygon
				(pts
					(arc
						(start 108.88091 -73.500234)
						(mid 108.11891 -73.500234)
						(end 108.88091 -73.500234)
					)
				)
			)
		)
		(zone
			(layer "F.Cu")
			(hatch none 0.5)
			(connect_pads
				(clearance 0)
			)
			(min_thickness 0.25)
			(keepout
				(tracks allowed)
				(vias not_allowed)
				(pads allowed)
				(copperpour not_allowed)
				(footprints allowed)
			)
			(placement
				(enabled no)
				(sheetname "")
			)
			(fill
				(thermal_gap 0.5)
				(thermal_bridge_width 0.5)
				(island_removal_mode 0)
			)
			(polygon
				(pts
					(arc
						(start 108.88091 -72.500236)
						(mid 108.11891 -72.500236)
						(end 108.88091 -72.500236)
					)
				)
			)
		)
		(zone
			(layer "F.Cu")
			(hatch none 0.5)
			(connect_pads
				(clearance 0)
			)
			(min_thickness 0.25)
			(keepout
				(tracks allowed)
				(vias not_allowed)
				(pads allowed)
				(copperpour not_allowed)
				(footprints allowed)
			)
			(placement
				(enabled no)
				(sheetname "")
			)
			(fill
				(thermal_gap 0.5)
				(thermal_bridge_width 0.5)
				(island_removal_mode 0)
			)
			(polygon
				(pts
					(arc
						(start 108.88091 -71.500238)
						(mid 108.11891 -71.500238)
						(end 108.88091 -71.500238)
					)
				)
			)
		)
		(zone
			(layer "F.Cu")
			(hatch none 0.5)
			(connect_pads
				(clearance 0)
			)
			(min_thickness 0.25)
			(keepout
				(tracks allowed)
				(vias not_allowed)
				(pads allowed)
				(copperpour not_allowed)
				(footprints allowed)
			)
			(placement
				(enabled no)
				(sheetname "")
			)
			(fill
				(thermal_gap 0.5)
				(thermal_bridge_width 0.5)
				(island_removal_mode 0)
			)
			(polygon
				(pts
					(arc
						(start 108.88091 -70.50024)
						(mid 108.11891 -70.50024)
						(end 108.88091 -70.50024)
					)
				)
			)
		)
		(zone
			(layer "F.Cu")
			(hatch none 0.5)
			(connect_pads
				(clearance 0)
			)
			(min_thickness 0.25)
			(keepout
				(tracks allowed)
				(vias not_allowed)
				(pads allowed)
				(copperpour not_allowed)
				(footprints allowed)
			)
			(placement
				(enabled no)
				(sheetname "")
			)
			(fill
				(thermal_gap 0.5)
				(thermal_bridge_width 0.5)
				(island_removal_mode 0)
			)
			(polygon
				(pts
					(arc
						(start 108.88091 -69.500242)
						(mid 108.11891 -69.500242)
						(end 108.88091 -69.500242)
					)
				)
			)
		)
		(zone
			(layer "F.Cu")
			(hatch none 0.5)
			(connect_pads
				(clearance 0)
			)
			(min_thickness 0.25)
			(keepout
				(tracks allowed)
				(vias not_allowed)
				(pads allowed)
				(copperpour not_allowed)
				(footprints allowed)
			)
			(placement
				(enabled no)
				(sheetname "")
			)
			(fill
				(thermal_gap 0.5)
				(thermal_bridge_width 0.5)
				(island_removal_mode 0)
			)
			(polygon
				(pts
					(arc
						(start 108.88091 -68.500244)
						(mid 108.11891 -68.500244)
						(end 108.88091 -68.500244)
					)
				)
			)
		)
		(zone
			(layer "F.Cu")
			(hatch none 0.5)
			(connect_pads
				(clearance 0)
			)
			(min_thickness 0.25)
			(keepout
				(tracks allowed)
				(vias not_allowed)
				(pads allowed)
				(copperpour not_allowed)
				(footprints allowed)
			)
			(placement
				(enabled no)
				(sheetname "")
			)
			(fill
				(thermal_gap 0.5)
				(thermal_bridge_width 0.5)
				(island_removal_mode 0)
			)
			(polygon
				(pts
					(arc
						(start 108.88091 -67.500246)
						(mid 108.11891 -67.500246)
						(end 108.88091 -67.500246)
					)
				)
			)
		)
		(zone
			(layer "F.Cu")
			(hatch none 0.5)
			(connect_pads
				(clearance 0)
			)
			(min_thickness 0.25)
			(keepout
				(tracks allowed)
				(vias not_allowed)
				(pads allowed)
				(copperpour not_allowed)
				(footprints allowed)
			)
			(placement
				(enabled no)
				(sheetname "")
			)
			(fill
				(thermal_gap 0.5)
				(thermal_bridge_width 0.5)
				(island_removal_mode 0)
			)
			(polygon
				(pts
					(arc
						(start 108.88091 -66.499994)
						(mid 108.11891 -66.499994)
						(end 108.88091 -66.499994)
					)
				)
			)
		)
		(zone
			(layer "F.Cu")
			(hatch none 0.5)
			(connect_pads
				(clearance 0)
			)
			(min_thickness 0.25)
			(keepout
				(tracks allowed)
				(vias not_allowed)
				(pads allowed)
				(copperpour not_allowed)
				(footprints allowed)
			)
			(placement
				(enabled no)
				(sheetname "")
			)
			(fill
				(thermal_gap 0.5)
				(thermal_bridge_width 0.5)
				(island_removal_mode 0)
			)
			(polygon
				(pts
					(arc
						(start 108.88091 -65.499996)
						(mid 108.11891 -65.499996)
						(end 108.88091 -65.499996)
					)
				)
			)
		)
		(zone
			(layer "F.Cu")
			(hatch none 0.5)
			(connect_pads
				(clearance 0)
			)
			(min_thickness 0.25)
			(keepout
				(tracks allowed)
				(vias not_allowed)
				(pads allowed)
				(copperpour not_allowed)
				(footprints allowed)
			)
			(placement
				(enabled no)
				(sheetname "")
			)
			(fill
				(thermal_gap 0.5)
				(thermal_bridge_width 0.5)
				(island_removal_mode 0)
			)
			(polygon
				(pts
					(arc
						(start 108.88091 -64.499998)
						(mid 108.11891 -64.499998)
						(end 108.88091 -64.499998)
					)
				)
			)
		)
		(zone
			(layer "F.Cu")
			(hatch none 0.5)
			(connect_pads
				(clearance 0)
			)
			(min_thickness 0.25)
			(keepout
				(tracks allowed)
				(vias not_allowed)
				(pads allowed)
				(copperpour not_allowed)
				(footprints allowed)
			)
			(placement
				(enabled no)
				(sheetname "")
			)
			(fill
				(thermal_gap 0.5)
				(thermal_bridge_width 0.5)
				(island_removal_mode 0)
			)
			(polygon
				(pts
					(arc
						(start 108.88091 -63.5)
						(mid 108.11891 -63.5)
						(end 108.88091 -63.5)
					)
				)
			)
		)
		(zone
			(layer "F.Cu")
			(hatch none 0.5)
			(connect_pads
				(clearance 0)
			)
			(min_thickness 0.25)
			(keepout
				(tracks allowed)
				(vias not_allowed)
				(pads allowed)
				(copperpour not_allowed)
				(footprints allowed)
			)
			(placement
				(enabled no)
				(sheetname "")
			)
			(fill
				(thermal_gap 0.5)
				(thermal_bridge_width 0.5)
				(island_removal_mode 0)
			)
			(polygon
				(pts
					(arc
						(start 108.88091 -62.500002)
						(mid 108.11891 -62.500002)
						(end 108.88091 -62.500002)
					)
				)
			)
		)
		(zone
			(layer "F.Cu")
			(hatch none 0.5)
			(connect_pads
				(clearance 0)
			)
			(min_thickness 0.25)
			(keepout
				(tracks allowed)
				(vias not_allowed)
				(pads allowed)
				(copperpour not_allowed)
				(footprints allowed)
			)
			(placement
				(enabled no)
				(sheetname "")
			)
			(fill
				(thermal_gap 0.5)
				(thermal_bridge_width 0.5)
				(island_removal_mode 0)
			)
			(polygon
				(pts
					(arc
						(start 108.88091 -61.500004)
						(mid 108.11891 -61.500004)
						(end 108.88091 -61.500004)
					)
				)
			)
		)
		(zone
			(layer "F.Cu")
			(hatch none 0.5)
			(connect_pads
				(clearance 0)
			)
			(min_thickness 0.25)
			(keepout
				(tracks allowed)
				(vias not_allowed)
				(pads allowed)
				(copperpour not_allowed)
				(footprints allowed)
			)
			(placement
				(enabled no)
				(sheetname "")
			)
			(fill
				(thermal_gap 0.5)
				(thermal_bridge_width 0.5)
				(island_removal_mode 0)
			)
			(polygon
				(pts
					(arc
						(start 108.88091 -60.500006)
						(mid 108.11891 -60.500006)
						(end 108.88091 -60.500006)
					)
				)
			)
		)
		(zone
			(layer "F.Cu")
			(hatch none 0.5)
			(connect_pads
				(clearance 0)
			)
			(min_thickness 0.25)
			(keepout
				(tracks allowed)
				(vias not_allowed)
				(pads allowed)
				(copperpour not_allowed)
				(footprints allowed)
			)
			(placement
				(enabled no)
				(sheetname "")
			)
			(fill
				(thermal_gap 0.5)
				(thermal_bridge_width 0.5)
				(island_removal_mode 0)
			)
			(polygon
				(pts
					(arc
						(start 108.88091 -59.500008)
						(mid 108.11891 -59.500008)
						(end 108.88091 -59.500008)
					)
				)
			)
		)
		(zone
			(layer "F.Cu")
			(hatch none 0.5)
			(connect_pads
				(clearance 0)
			)
			(min_thickness 0.25)
			(keepout
				(tracks allowed)
				(vias not_allowed)
				(pads allowed)
				(copperpour not_allowed)
				(footprints allowed)
			)
			(placement
				(enabled no)
				(sheetname "")
			)
			(fill
				(thermal_gap 0.5)
				(thermal_bridge_width 0.5)
				(island_removal_mode 0)
			)
			(polygon
				(pts
					(arc
						(start 108.88091 -58.50001)
						(mid 108.11891 -58.50001)
						(end 108.88091 -58.50001)
					)
				)
			)
		)
		(zone
			(layer "F.Cu")
			(hatch none 0.5)
			(connect_pads
				(clearance 0)
			)
			(min_thickness 0.25)
			(keepout
				(tracks allowed)
				(vias not_allowed)
				(pads allowed)
				(copperpour not_allowed)
				(footprints allowed)
			)
			(placement
				(enabled no)
				(sheetname "")
			)
			(fill
				(thermal_gap 0.5)
				(thermal_bridge_width 0.5)
				(island_removal_mode 0)
			)
			(polygon
				(pts
					(arc
						(start 108.88091 -57.500012)
						(mid 108.11891 -57.500012)
						(end 108.88091 -57.500012)
					)
				)
			)
		)
		(zone
			(layer "F.Cu")
			(hatch none 0.5)
			(connect_pads
				(clearance 0)
			)
			(min_thickness 0.25)
			(keepout
				(tracks allowed)
				(vias not_allowed)
				(pads allowed)
				(copperpour not_allowed)
				(footprints allowed)
			)
			(placement
				(enabled no)
				(sheetname "")
			)
			(fill
				(thermal_gap 0.5)
				(thermal_bridge_width 0.5)
				(island_removal_mode 0)
			)
			(polygon
				(pts
					(arc
						(start 108.88091 -56.500014)
						(mid 108.11891 -56.500014)
						(end 108.88091 -56.500014)
					)
				)
			)
		)
		(zone
			(layer "F.Cu")
			(hatch none 0.5)
			(connect_pads
				(clearance 0)
			)
			(min_thickness 0.25)
			(keepout
				(tracks allowed)
				(vias not_allowed)
				(pads allowed)
				(copperpour not_allowed)
				(footprints allowed)
			)
			(placement
				(enabled no)
				(sheetname "")
			)
			(fill
				(thermal_gap 0.5)
				(thermal_bridge_width 0.5)
				(island_removal_mode 0)
			)
			(polygon
				(pts
					(arc
						(start 108.88091 -55.500016)
						(mid 108.11891 -55.500016)
						(end 108.88091 -55.500016)
					)
				)
			)
		)
		(zone
			(layer "F.Cu")
			(hatch none 0.5)
			(connect_pads
				(clearance 0)
			)
			(min_thickness 0.25)
			(keepout
				(tracks allowed)
				(vias not_allowed)
				(pads allowed)
				(copperpour not_allowed)
				(footprints allowed)
			)
			(placement
				(enabled no)
				(sheetname "")
			)
			(fill
				(thermal_gap 0.5)
				(thermal_bridge_width 0.5)
				(island_removal_mode 0)
			)
			(polygon
				(pts
					(arc
						(start 108.88091 -54.500018)
						(mid 108.11891 -54.500018)
						(end 108.88091 -54.500018)
					)
				)
			)
		)
		(zone
			(layer "F.Cu")
			(hatch none 0.5)
			(connect_pads
				(clearance 0)
			)
			(min_thickness 0.25)
			(keepout
				(tracks allowed)
				(vias not_allowed)
				(pads allowed)
				(copperpour not_allowed)
				(footprints allowed)
			)
			(placement
				(enabled no)
				(sheetname "")
			)
			(fill
				(thermal_gap 0.5)
				(thermal_bridge_width 0.5)
				(island_removal_mode 0)
			)
			(polygon
				(pts
					(arc
						(start 108.88091 -53.50002)
						(mid 108.11891 -53.50002)
						(end 108.88091 -53.50002)
					)
				)
			)
		)
		(zone
			(layer "F.Cu")
			(hatch none 0.5)
			(connect_pads
				(clearance 0)
			)
			(min_thickness 0.25)
			(keepout
				(tracks allowed)
				(vias not_allowed)
				(pads allowed)
				(copperpour not_allowed)
				(footprints allowed)
			)
			(placement
				(enabled no)
				(sheetname "")
			)
			(fill
				(thermal_gap 0.5)
				(thermal_bridge_width 0.5)
				(island_removal_mode 0)
			)
			(polygon
				(pts
					(arc
						(start 108.88091 -52.500022)
						(mid 108.11891 -52.500022)
						(end 108.88091 -52.500022)
					)
				)
			)
		)
		(zone
			(layer "F.Cu")
			(hatch none 0.5)
			(connect_pads
				(clearance 0)
			)
			(min_thickness 0.25)
			(keepout
				(tracks allowed)
				(vias not_allowed)
				(pads allowed)
				(copperpour not_allowed)
				(footprints allowed)
			)
			(placement
				(enabled no)
				(sheetname "")
			)
			(fill
				(thermal_gap 0.5)
				(thermal_bridge_width 0.5)
				(island_removal_mode 0)
			)
			(polygon
				(pts
					(arc
						(start 108.88091 -51.500024)
						(mid 108.11891 -51.500024)
						(end 108.88091 -51.500024)
					)
				)
			)
		)
		(zone
			(layer "F.Cu")
			(hatch none 0.5)
			(connect_pads
				(clearance 0)
			)
			(min_thickness 0.25)
			(keepout
				(tracks allowed)
				(vias not_allowed)
				(pads allowed)
				(copperpour not_allowed)
				(footprints allowed)
			)
			(placement
				(enabled no)
				(sheetname "")
			)
			(fill
				(thermal_gap 0.5)
				(thermal_bridge_width 0.5)
				(island_removal_mode 0)
			)
			(polygon
				(pts
					(arc
						(start 109.880908 -82.500216)
						(mid 109.118908 -82.500216)
						(end 109.880908 -82.500216)
					)
				)
			)
		)
		(zone
			(layer "F.Cu")
			(hatch none 0.5)
			(connect_pads
				(clearance 0)
			)
			(min_thickness 0.25)
			(keepout
				(tracks allowed)
				(vias not_allowed)
				(pads allowed)
				(copperpour not_allowed)
				(footprints allowed)
			)
			(placement
				(enabled no)
				(sheetname "")
			)
			(fill
				(thermal_gap 0.5)
				(thermal_bridge_width 0.5)
				(island_removal_mode 0)
			)
			(polygon
				(pts
					(arc
						(start 109.880908 -81.500218)
						(mid 109.118908 -81.500218)
						(end 109.880908 -81.500218)
					)
				)
			)
		)
		(zone
			(layer "F.Cu")
			(hatch none 0.5)
			(connect_pads
				(clearance 0)
			)
			(min_thickness 0.25)
			(keepout
				(tracks allowed)
				(vias not_allowed)
				(pads allowed)
				(copperpour not_allowed)
				(footprints allowed)
			)
			(placement
				(enabled no)
				(sheetname "")
			)
			(fill
				(thermal_gap 0.5)
				(thermal_bridge_width 0.5)
				(island_removal_mode 0)
			)
			(polygon
				(pts
					(arc
						(start 109.880908 -80.50022)
						(mid 109.118908 -80.50022)
						(end 109.880908 -80.50022)
					)
				)
			)
		)
		(zone
			(layer "F.Cu")
			(hatch none 0.5)
			(connect_pads
				(clearance 0)
			)
			(min_thickness 0.25)
			(keepout
				(tracks allowed)
				(vias not_allowed)
				(pads allowed)
				(copperpour not_allowed)
				(footprints allowed)
			)
			(placement
				(enabled no)
				(sheetname "")
			)
			(fill
				(thermal_gap 0.5)
				(thermal_bridge_width 0.5)
				(island_removal_mode 0)
			)
			(polygon
				(pts
					(arc
						(start 109.880908 -79.500222)
						(mid 109.118908 -79.500222)
						(end 109.880908 -79.500222)
					)
				)
			)
		)
		(zone
			(layer "F.Cu")
			(hatch none 0.5)
			(connect_pads
				(clearance 0)
			)
			(min_thickness 0.25)
			(keepout
				(tracks allowed)
				(vias not_allowed)
				(pads allowed)
				(copperpour not_allowed)
				(footprints allowed)
			)
			(placement
				(enabled no)
				(sheetname "")
			)
			(fill
				(thermal_gap 0.5)
				(thermal_bridge_width 0.5)
				(island_removal_mode 0)
			)
			(polygon
				(pts
					(arc
						(start 109.880908 -78.500224)
						(mid 109.118908 -78.500224)
						(end 109.880908 -78.500224)
					)
				)
			)
		)
		(zone
			(layer "F.Cu")
			(hatch none 0.5)
			(connect_pads
				(clearance 0)
			)
			(min_thickness 0.25)
			(keepout
				(tracks allowed)
				(vias not_allowed)
				(pads allowed)
				(copperpour not_allowed)
				(footprints allowed)
			)
			(placement
				(enabled no)
				(sheetname "")
			)
			(fill
				(thermal_gap 0.5)
				(thermal_bridge_width 0.5)
				(island_removal_mode 0)
			)
			(polygon
				(pts
					(arc
						(start 109.880908 -77.500226)
						(mid 109.118908 -77.500226)
						(end 109.880908 -77.500226)
					)
				)
			)
		)
		(zone
			(layer "F.Cu")
			(hatch none 0.5)
			(connect_pads
				(clearance 0)
			)
			(min_thickness 0.25)
			(keepout
				(tracks allowed)
				(vias not_allowed)
				(pads allowed)
				(copperpour not_allowed)
				(footprints allowed)
			)
			(placement
				(enabled no)
				(sheetname "")
			)
			(fill
				(thermal_gap 0.5)
				(thermal_bridge_width 0.5)
				(island_removal_mode 0)
			)
			(polygon
				(pts
					(arc
						(start 109.880908 -76.500228)
						(mid 109.118908 -76.500228)
						(end 109.880908 -76.500228)
					)
				)
			)
		)
		(zone
			(layer "F.Cu")
			(hatch none 0.5)
			(connect_pads
				(clearance 0)
			)
			(min_thickness 0.25)
			(keepout
				(tracks allowed)
				(vias not_allowed)
				(pads allowed)
				(copperpour not_allowed)
				(footprints allowed)
			)
			(placement
				(enabled no)
				(sheetname "")
			)
			(fill
				(thermal_gap 0.5)
				(thermal_bridge_width 0.5)
				(island_removal_mode 0)
			)
			(polygon
				(pts
					(arc
						(start 109.880908 -75.50023)
						(mid 109.118908 -75.50023)
						(end 109.880908 -75.50023)
					)
				)
			)
		)
		(zone
			(layer "F.Cu")
			(hatch none 0.5)
			(connect_pads
				(clearance 0)
			)
			(min_thickness 0.25)
			(keepout
				(tracks allowed)
				(vias not_allowed)
				(pads allowed)
				(copperpour not_allowed)
				(footprints allowed)
			)
			(placement
				(enabled no)
				(sheetname "")
			)
			(fill
				(thermal_gap 0.5)
				(thermal_bridge_width 0.5)
				(island_removal_mode 0)
			)
			(polygon
				(pts
					(arc
						(start 109.880908 -74.500232)
						(mid 109.118908 -74.500232)
						(end 109.880908 -74.500232)
					)
				)
			)
		)
		(zone
			(layer "F.Cu")
			(hatch none 0.5)
			(connect_pads
				(clearance 0)
			)
			(min_thickness 0.25)
			(keepout
				(tracks allowed)
				(vias not_allowed)
				(pads allowed)
				(copperpour not_allowed)
				(footprints allowed)
			)
			(placement
				(enabled no)
				(sheetname "")
			)
			(fill
				(thermal_gap 0.5)
				(thermal_bridge_width 0.5)
				(island_removal_mode 0)
			)
			(polygon
				(pts
					(arc
						(start 109.880908 -73.500234)
						(mid 109.118908 -73.500234)
						(end 109.880908 -73.500234)
					)
				)
			)
		)
		(zone
			(layer "F.Cu")
			(hatch none 0.5)
			(connect_pads
				(clearance 0)
			)
			(min_thickness 0.25)
			(keepout
				(tracks allowed)
				(vias not_allowed)
				(pads allowed)
				(copperpour not_allowed)
				(footprints allowed)
			)
			(placement
				(enabled no)
				(sheetname "")
			)
			(fill
				(thermal_gap 0.5)
				(thermal_bridge_width 0.5)
				(island_removal_mode 0)
			)
			(polygon
				(pts
					(arc
						(start 109.880908 -72.500236)
						(mid 109.118908 -72.500236)
						(end 109.880908 -72.500236)
					)
				)
			)
		)
		(zone
			(layer "F.Cu")
			(hatch none 0.5)
			(connect_pads
				(clearance 0)
			)
			(min_thickness 0.25)
			(keepout
				(tracks allowed)
				(vias not_allowed)
				(pads allowed)
				(copperpour not_allowed)
				(footprints allowed)
			)
			(placement
				(enabled no)
				(sheetname "")
			)
			(fill
				(thermal_gap 0.5)
				(thermal_bridge_width 0.5)
				(island_removal_mode 0)
			)
			(polygon
				(pts
					(arc
						(start 109.880908 -71.500238)
						(mid 109.118908 -71.500238)
						(end 109.880908 -71.500238)
					)
				)
			)
		)
		(zone
			(layer "F.Cu")
			(hatch none 0.5)
			(connect_pads
				(clearance 0)
			)
			(min_thickness 0.25)
			(keepout
				(tracks allowed)
				(vias not_allowed)
				(pads allowed)
				(copperpour not_allowed)
				(footprints allowed)
			)
			(placement
				(enabled no)
				(sheetname "")
			)
			(fill
				(thermal_gap 0.5)
				(thermal_bridge_width 0.5)
				(island_removal_mode 0)
			)
			(polygon
				(pts
					(arc
						(start 109.880908 -70.50024)
						(mid 109.118908 -70.50024)
						(end 109.880908 -70.50024)
					)
				)
			)
		)
		(zone
			(layer "F.Cu")
			(hatch none 0.5)
			(connect_pads
				(clearance 0)
			)
			(min_thickness 0.25)
			(keepout
				(tracks allowed)
				(vias not_allowed)
				(pads allowed)
				(copperpour not_allowed)
				(footprints allowed)
			)
			(placement
				(enabled no)
				(sheetname "")
			)
			(fill
				(thermal_gap 0.5)
				(thermal_bridge_width 0.5)
				(island_removal_mode 0)
			)
			(polygon
				(pts
					(arc
						(start 109.880908 -69.500242)
						(mid 109.118908 -69.500242)
						(end 109.880908 -69.500242)
					)
				)
			)
		)
		(zone
			(layer "F.Cu")
			(hatch none 0.5)
			(connect_pads
				(clearance 0)
			)
			(min_thickness 0.25)
			(keepout
				(tracks allowed)
				(vias not_allowed)
				(pads allowed)
				(copperpour not_allowed)
				(footprints allowed)
			)
			(placement
				(enabled no)
				(sheetname "")
			)
			(fill
				(thermal_gap 0.5)
				(thermal_bridge_width 0.5)
				(island_removal_mode 0)
			)
			(polygon
				(pts
					(arc
						(start 109.880908 -68.500244)
						(mid 109.118908 -68.500244)
						(end 109.880908 -68.500244)
					)
				)
			)
		)
		(zone
			(layer "F.Cu")
			(hatch none 0.5)
			(connect_pads
				(clearance 0)
			)
			(min_thickness 0.25)
			(keepout
				(tracks allowed)
				(vias not_allowed)
				(pads allowed)
				(copperpour not_allowed)
				(footprints allowed)
			)
			(placement
				(enabled no)
				(sheetname "")
			)
			(fill
				(thermal_gap 0.5)
				(thermal_bridge_width 0.5)
				(island_removal_mode 0)
			)
			(polygon
				(pts
					(arc
						(start 109.880908 -67.500246)
						(mid 109.118908 -67.500246)
						(end 109.880908 -67.500246)
					)
				)
			)
		)
		(zone
			(layer "F.Cu")
			(hatch none 0.5)
			(connect_pads
				(clearance 0)
			)
			(min_thickness 0.25)
			(keepout
				(tracks allowed)
				(vias not_allowed)
				(pads allowed)
				(copperpour not_allowed)
				(footprints allowed)
			)
			(placement
				(enabled no)
				(sheetname "")
			)
			(fill
				(thermal_gap 0.5)
				(thermal_bridge_width 0.5)
				(island_removal_mode 0)
			)
			(polygon
				(pts
					(arc
						(start 109.880908 -66.499994)
						(mid 109.118908 -66.499994)
						(end 109.880908 -66.499994)
					)
				)
			)
		)
		(zone
			(layer "F.Cu")
			(hatch none 0.5)
			(connect_pads
				(clearance 0)
			)
			(min_thickness 0.25)
			(keepout
				(tracks allowed)
				(vias not_allowed)
				(pads allowed)
				(copperpour not_allowed)
				(footprints allowed)
			)
			(placement
				(enabled no)
				(sheetname "")
			)
			(fill
				(thermal_gap 0.5)
				(thermal_bridge_width 0.5)
				(island_removal_mode 0)
			)
			(polygon
				(pts
					(arc
						(start 109.880908 -65.499996)
						(mid 109.118908 -65.499996)
						(end 109.880908 -65.499996)
					)
				)
			)
		)
		(zone
			(layer "F.Cu")
			(hatch none 0.5)
			(connect_pads
				(clearance 0)
			)
			(min_thickness 0.25)
			(keepout
				(tracks allowed)
				(vias not_allowed)
				(pads allowed)
				(copperpour not_allowed)
				(footprints allowed)
			)
			(placement
				(enabled no)
				(sheetname "")
			)
			(fill
				(thermal_gap 0.5)
				(thermal_bridge_width 0.5)
				(island_removal_mode 0)
			)
			(polygon
				(pts
					(arc
						(start 109.880908 -64.499998)
						(mid 109.118908 -64.499998)
						(end 109.880908 -64.499998)
					)
				)
			)
		)
		(zone
			(layer "F.Cu")
			(hatch none 0.5)
			(connect_pads
				(clearance 0)
			)
			(min_thickness 0.25)
			(keepout
				(tracks allowed)
				(vias not_allowed)
				(pads allowed)
				(copperpour not_allowed)
				(footprints allowed)
			)
			(placement
				(enabled no)
				(sheetname "")
			)
			(fill
				(thermal_gap 0.5)
				(thermal_bridge_width 0.5)
				(island_removal_mode 0)
			)
			(polygon
				(pts
					(arc
						(start 109.880908 -63.5)
						(mid 109.118908 -63.5)
						(end 109.880908 -63.5)
					)
				)
			)
		)
		(zone
			(layer "F.Cu")
			(hatch none 0.5)
			(connect_pads
				(clearance 0)
			)
			(min_thickness 0.25)
			(keepout
				(tracks allowed)
				(vias not_allowed)
				(pads allowed)
				(copperpour not_allowed)
				(footprints allowed)
			)
			(placement
				(enabled no)
				(sheetname "")
			)
			(fill
				(thermal_gap 0.5)
				(thermal_bridge_width 0.5)
				(island_removal_mode 0)
			)
			(polygon
				(pts
					(arc
						(start 109.880908 -62.500002)
						(mid 109.118908 -62.500002)
						(end 109.880908 -62.500002)
					)
				)
			)
		)
		(zone
			(layer "F.Cu")
			(hatch none 0.5)
			(connect_pads
				(clearance 0)
			)
			(min_thickness 0.25)
			(keepout
				(tracks allowed)
				(vias not_allowed)
				(pads allowed)
				(copperpour not_allowed)
				(footprints allowed)
			)
			(placement
				(enabled no)
				(sheetname "")
			)
			(fill
				(thermal_gap 0.5)
				(thermal_bridge_width 0.5)
				(island_removal_mode 0)
			)
			(polygon
				(pts
					(arc
						(start 109.880908 -61.500004)
						(mid 109.118908 -61.500004)
						(end 109.880908 -61.500004)
					)
				)
			)
		)
		(zone
			(layer "F.Cu")
			(hatch none 0.5)
			(connect_pads
				(clearance 0)
			)
			(min_thickness 0.25)
			(keepout
				(tracks allowed)
				(vias not_allowed)
				(pads allowed)
				(copperpour not_allowed)
				(footprints allowed)
			)
			(placement
				(enabled no)
				(sheetname "")
			)
			(fill
				(thermal_gap 0.5)
				(thermal_bridge_width 0.5)
				(island_removal_mode 0)
			)
			(polygon
				(pts
					(arc
						(start 109.880908 -60.500006)
						(mid 109.118908 -60.500006)
						(end 109.880908 -60.500006)
					)
				)
			)
		)
		(zone
			(layer "F.Cu")
			(hatch none 0.5)
			(connect_pads
				(clearance 0)
			)
			(min_thickness 0.25)
			(keepout
				(tracks allowed)
				(vias not_allowed)
				(pads allowed)
				(copperpour not_allowed)
				(footprints allowed)
			)
			(placement
				(enabled no)
				(sheetname "")
			)
			(fill
				(thermal_gap 0.5)
				(thermal_bridge_width 0.5)
				(island_removal_mode 0)
			)
			(polygon
				(pts
					(arc
						(start 109.880908 -59.500008)
						(mid 109.118908 -59.500008)
						(end 109.880908 -59.500008)
					)
				)
			)
		)
		(zone
			(layer "F.Cu")
			(hatch none 0.5)
			(connect_pads
				(clearance 0)
			)
			(min_thickness 0.25)
			(keepout
				(tracks allowed)
				(vias not_allowed)
				(pads allowed)
				(copperpour not_allowed)
				(footprints allowed)
			)
			(placement
				(enabled no)
				(sheetname "")
			)
			(fill
				(thermal_gap 0.5)
				(thermal_bridge_width 0.5)
				(island_removal_mode 0)
			)
			(polygon
				(pts
					(arc
						(start 109.880908 -58.50001)
						(mid 109.118908 -58.50001)
						(end 109.880908 -58.50001)
					)
				)
			)
		)
		(zone
			(layer "F.Cu")
			(hatch none 0.5)
			(connect_pads
				(clearance 0)
			)
			(min_thickness 0.25)
			(keepout
				(tracks allowed)
				(vias not_allowed)
				(pads allowed)
				(copperpour not_allowed)
				(footprints allowed)
			)
			(placement
				(enabled no)
				(sheetname "")
			)
			(fill
				(thermal_gap 0.5)
				(thermal_bridge_width 0.5)
				(island_removal_mode 0)
			)
			(polygon
				(pts
					(arc
						(start 109.880908 -57.500012)
						(mid 109.118908 -57.500012)
						(end 109.880908 -57.500012)
					)
				)
			)
		)
		(zone
			(layer "F.Cu")
			(hatch none 0.5)
			(connect_pads
				(clearance 0)
			)
			(min_thickness 0.25)
			(keepout
				(tracks allowed)
				(vias not_allowed)
				(pads allowed)
				(copperpour not_allowed)
				(footprints allowed)
			)
			(placement
				(enabled no)
				(sheetname "")
			)
			(fill
				(thermal_gap 0.5)
				(thermal_bridge_width 0.5)
				(island_removal_mode 0)
			)
			(polygon
				(pts
					(arc
						(start 109.880908 -56.500014)
						(mid 109.118908 -56.500014)
						(end 109.880908 -56.500014)
					)
				)
			)
		)
		(zone
			(layer "F.Cu")
			(hatch none 0.5)
			(connect_pads
				(clearance 0)
			)
			(min_thickness 0.25)
			(keepout
				(tracks allowed)
				(vias not_allowed)
				(pads allowed)
				(copperpour not_allowed)
				(footprints allowed)
			)
			(placement
				(enabled no)
				(sheetname "")
			)
			(fill
				(thermal_gap 0.5)
				(thermal_bridge_width 0.5)
				(island_removal_mode 0)
			)
			(polygon
				(pts
					(arc
						(start 109.880908 -55.500016)
						(mid 109.118908 -55.500016)
						(end 109.880908 -55.500016)
					)
				)
			)
		)
		(zone
			(layer "F.Cu")
			(hatch none 0.5)
			(connect_pads
				(clearance 0)
			)
			(min_thickness 0.25)
			(keepout
				(tracks allowed)
				(vias not_allowed)
				(pads allowed)
				(copperpour not_allowed)
				(footprints allowed)
			)
			(placement
				(enabled no)
				(sheetname "")
			)
			(fill
				(thermal_gap 0.5)
				(thermal_bridge_width 0.5)
				(island_removal_mode 0)
			)
			(polygon
				(pts
					(arc
						(start 109.880908 -54.500018)
						(mid 109.118908 -54.500018)
						(end 109.880908 -54.500018)
					)
				)
			)
		)
		(zone
			(layer "F.Cu")
			(hatch none 0.5)
			(connect_pads
				(clearance 0)
			)
			(min_thickness 0.25)
			(keepout
				(tracks allowed)
				(vias not_allowed)
				(pads allowed)
				(copperpour not_allowed)
				(footprints allowed)
			)
			(placement
				(enabled no)
				(sheetname "")
			)
			(fill
				(thermal_gap 0.5)
				(thermal_bridge_width 0.5)
				(island_removal_mode 0)
			)
			(polygon
				(pts
					(arc
						(start 109.880908 -53.50002)
						(mid 109.118908 -53.50002)
						(end 109.880908 -53.50002)
					)
				)
			)
		)
		(zone
			(layer "F.Cu")
			(hatch none 0.5)
			(connect_pads
				(clearance 0)
			)
			(min_thickness 0.25)
			(keepout
				(tracks allowed)
				(vias not_allowed)
				(pads allowed)
				(copperpour not_allowed)
				(footprints allowed)
			)
			(placement
				(enabled no)
				(sheetname "")
			)
			(fill
				(thermal_gap 0.5)
				(thermal_bridge_width 0.5)
				(island_removal_mode 0)
			)
			(polygon
				(pts
					(arc
						(start 109.880908 -52.500022)
						(mid 109.118908 -52.500022)
						(end 109.880908 -52.500022)
					)
				)
			)
		)
		(zone
			(layer "F.Cu")
			(hatch none 0.5)
			(connect_pads
				(clearance 0)
			)
			(min_thickness 0.25)
			(keepout
				(tracks allowed)
				(vias not_allowed)
				(pads allowed)
				(copperpour not_allowed)
				(footprints allowed)
			)
			(placement
				(enabled no)
				(sheetname "")
			)
			(fill
				(thermal_gap 0.5)
				(thermal_bridge_width 0.5)
				(island_removal_mode 0)
			)
			(polygon
				(pts
					(arc
						(start 109.880908 -51.500024)
						(mid 109.118908 -51.500024)
						(end 109.880908 -51.500024)
					)
				)
			)
		)
		(zone
			(layer "F.Cu")
			(hatch none 0.5)
			(connect_pads
				(clearance 0)
			)
			(min_thickness 0.25)
			(keepout
				(tracks allowed)
				(vias not_allowed)
				(pads allowed)
				(copperpour not_allowed)
				(footprints allowed)
			)
			(placement
				(enabled no)
				(sheetname "")
			)
			(fill
				(thermal_gap 0.5)
				(thermal_bridge_width 0.5)
				(island_removal_mode 0)
			)
			(polygon
				(pts
					(arc
						(start 110.880906 -82.500216)
						(mid 110.118906 -82.500216)
						(end 110.880906 -82.500216)
					)
				)
			)
		)
		(zone
			(layer "F.Cu")
			(hatch none 0.5)
			(connect_pads
				(clearance 0)
			)
			(min_thickness 0.25)
			(keepout
				(tracks allowed)
				(vias not_allowed)
				(pads allowed)
				(copperpour not_allowed)
				(footprints allowed)
			)
			(placement
				(enabled no)
				(sheetname "")
			)
			(fill
				(thermal_gap 0.5)
				(thermal_bridge_width 0.5)
				(island_removal_mode 0)
			)
			(polygon
				(pts
					(arc
						(start 110.880906 -81.500218)
						(mid 110.118906 -81.500218)
						(end 110.880906 -81.500218)
					)
				)
			)
		)
		(zone
			(layer "F.Cu")
			(hatch none 0.5)
			(connect_pads
				(clearance 0)
			)
			(min_thickness 0.25)
			(keepout
				(tracks allowed)
				(vias not_allowed)
				(pads allowed)
				(copperpour not_allowed)
				(footprints allowed)
			)
			(placement
				(enabled no)
				(sheetname "")
			)
			(fill
				(thermal_gap 0.5)
				(thermal_bridge_width 0.5)
				(island_removal_mode 0)
			)
			(polygon
				(pts
					(arc
						(start 110.880906 -80.50022)
						(mid 110.118906 -80.50022)
						(end 110.880906 -80.50022)
					)
				)
			)
		)
		(zone
			(layer "F.Cu")
			(hatch none 0.5)
			(connect_pads
				(clearance 0)
			)
			(min_thickness 0.25)
			(keepout
				(tracks allowed)
				(vias not_allowed)
				(pads allowed)
				(copperpour not_allowed)
				(footprints allowed)
			)
			(placement
				(enabled no)
				(sheetname "")
			)
			(fill
				(thermal_gap 0.5)
				(thermal_bridge_width 0.5)
				(island_removal_mode 0)
			)
			(polygon
				(pts
					(arc
						(start 110.880906 -79.500222)
						(mid 110.118906 -79.500222)
						(end 110.880906 -79.500222)
					)
				)
			)
		)
		(zone
			(layer "F.Cu")
			(hatch none 0.5)
			(connect_pads
				(clearance 0)
			)
			(min_thickness 0.25)
			(keepout
				(tracks allowed)
				(vias not_allowed)
				(pads allowed)
				(copperpour not_allowed)
				(footprints allowed)
			)
			(placement
				(enabled no)
				(sheetname "")
			)
			(fill
				(thermal_gap 0.5)
				(thermal_bridge_width 0.5)
				(island_removal_mode 0)
			)
			(polygon
				(pts
					(arc
						(start 110.880906 -78.500224)
						(mid 110.118906 -78.500224)
						(end 110.880906 -78.500224)
					)
				)
			)
		)
		(zone
			(layer "F.Cu")
			(hatch none 0.5)
			(connect_pads
				(clearance 0)
			)
			(min_thickness 0.25)
			(keepout
				(tracks allowed)
				(vias not_allowed)
				(pads allowed)
				(copperpour not_allowed)
				(footprints allowed)
			)
			(placement
				(enabled no)
				(sheetname "")
			)
			(fill
				(thermal_gap 0.5)
				(thermal_bridge_width 0.5)
				(island_removal_mode 0)
			)
			(polygon
				(pts
					(arc
						(start 110.880906 -77.500226)
						(mid 110.118906 -77.500226)
						(end 110.880906 -77.500226)
					)
				)
			)
		)
		(zone
			(layer "F.Cu")
			(hatch none 0.5)
			(connect_pads
				(clearance 0)
			)
			(min_thickness 0.25)
			(keepout
				(tracks allowed)
				(vias not_allowed)
				(pads allowed)
				(copperpour not_allowed)
				(footprints allowed)
			)
			(placement
				(enabled no)
				(sheetname "")
			)
			(fill
				(thermal_gap 0.5)
				(thermal_bridge_width 0.5)
				(island_removal_mode 0)
			)
			(polygon
				(pts
					(arc
						(start 110.880906 -76.500228)
						(mid 110.118906 -76.500228)
						(end 110.880906 -76.500228)
					)
				)
			)
		)
		(zone
			(layer "F.Cu")
			(hatch none 0.5)
			(connect_pads
				(clearance 0)
			)
			(min_thickness 0.25)
			(keepout
				(tracks allowed)
				(vias not_allowed)
				(pads allowed)
				(copperpour not_allowed)
				(footprints allowed)
			)
			(placement
				(enabled no)
				(sheetname "")
			)
			(fill
				(thermal_gap 0.5)
				(thermal_bridge_width 0.5)
				(island_removal_mode 0)
			)
			(polygon
				(pts
					(arc
						(start 110.880906 -75.50023)
						(mid 110.118906 -75.50023)
						(end 110.880906 -75.50023)
					)
				)
			)
		)
		(zone
			(layer "F.Cu")
			(hatch none 0.5)
			(connect_pads
				(clearance 0)
			)
			(min_thickness 0.25)
			(keepout
				(tracks allowed)
				(vias not_allowed)
				(pads allowed)
				(copperpour not_allowed)
				(footprints allowed)
			)
			(placement
				(enabled no)
				(sheetname "")
			)
			(fill
				(thermal_gap 0.5)
				(thermal_bridge_width 0.5)
				(island_removal_mode 0)
			)
			(polygon
				(pts
					(arc
						(start 110.880906 -74.500232)
						(mid 110.118906 -74.500232)
						(end 110.880906 -74.500232)
					)
				)
			)
		)
		(zone
			(layer "F.Cu")
			(hatch none 0.5)
			(connect_pads
				(clearance 0)
			)
			(min_thickness 0.25)
			(keepout
				(tracks allowed)
				(vias not_allowed)
				(pads allowed)
				(copperpour not_allowed)
				(footprints allowed)
			)
			(placement
				(enabled no)
				(sheetname "")
			)
			(fill
				(thermal_gap 0.5)
				(thermal_bridge_width 0.5)
				(island_removal_mode 0)
			)
			(polygon
				(pts
					(arc
						(start 110.880906 -73.500234)
						(mid 110.118906 -73.500234)
						(end 110.880906 -73.500234)
					)
				)
			)
		)
		(zone
			(layer "F.Cu")
			(hatch none 0.5)
			(connect_pads
				(clearance 0)
			)
			(min_thickness 0.25)
			(keepout
				(tracks allowed)
				(vias not_allowed)
				(pads allowed)
				(copperpour not_allowed)
				(footprints allowed)
			)
			(placement
				(enabled no)
				(sheetname "")
			)
			(fill
				(thermal_gap 0.5)
				(thermal_bridge_width 0.5)
				(island_removal_mode 0)
			)
			(polygon
				(pts
					(arc
						(start 110.880906 -72.500236)
						(mid 110.118906 -72.500236)
						(end 110.880906 -72.500236)
					)
				)
			)
		)
		(zone
			(layer "F.Cu")
			(hatch none 0.5)
			(connect_pads
				(clearance 0)
			)
			(min_thickness 0.25)
			(keepout
				(tracks allowed)
				(vias not_allowed)
				(pads allowed)
				(copperpour not_allowed)
				(footprints allowed)
			)
			(placement
				(enabled no)
				(sheetname "")
			)
			(fill
				(thermal_gap 0.5)
				(thermal_bridge_width 0.5)
				(island_removal_mode 0)
			)
			(polygon
				(pts
					(arc
						(start 110.880906 -71.500238)
						(mid 110.118906 -71.500238)
						(end 110.880906 -71.500238)
					)
				)
			)
		)
		(zone
			(layer "F.Cu")
			(hatch none 0.5)
			(connect_pads
				(clearance 0)
			)
			(min_thickness 0.25)
			(keepout
				(tracks allowed)
				(vias not_allowed)
				(pads allowed)
				(copperpour not_allowed)
				(footprints allowed)
			)
			(placement
				(enabled no)
				(sheetname "")
			)
			(fill
				(thermal_gap 0.5)
				(thermal_bridge_width 0.5)
				(island_removal_mode 0)
			)
			(polygon
				(pts
					(arc
						(start 110.880906 -70.50024)
						(mid 110.118906 -70.50024)
						(end 110.880906 -70.50024)
					)
				)
			)
		)
		(zone
			(layer "F.Cu")
			(hatch none 0.5)
			(connect_pads
				(clearance 0)
			)
			(min_thickness 0.25)
			(keepout
				(tracks allowed)
				(vias not_allowed)
				(pads allowed)
				(copperpour not_allowed)
				(footprints allowed)
			)
			(placement
				(enabled no)
				(sheetname "")
			)
			(fill
				(thermal_gap 0.5)
				(thermal_bridge_width 0.5)
				(island_removal_mode 0)
			)
			(polygon
				(pts
					(arc
						(start 110.880906 -69.500242)
						(mid 110.118906 -69.500242)
						(end 110.880906 -69.500242)
					)
				)
			)
		)
		(zone
			(layer "F.Cu")
			(hatch none 0.5)
			(connect_pads
				(clearance 0)
			)
			(min_thickness 0.25)
			(keepout
				(tracks allowed)
				(vias not_allowed)
				(pads allowed)
				(copperpour not_allowed)
				(footprints allowed)
			)
			(placement
				(enabled no)
				(sheetname "")
			)
			(fill
				(thermal_gap 0.5)
				(thermal_bridge_width 0.5)
				(island_removal_mode 0)
			)
			(polygon
				(pts
					(arc
						(start 110.880906 -68.500244)
						(mid 110.118906 -68.500244)
						(end 110.880906 -68.500244)
					)
				)
			)
		)
		(zone
			(layer "F.Cu")
			(hatch none 0.5)
			(connect_pads
				(clearance 0)
			)
			(min_thickness 0.25)
			(keepout
				(tracks allowed)
				(vias not_allowed)
				(pads allowed)
				(copperpour not_allowed)
				(footprints allowed)
			)
			(placement
				(enabled no)
				(sheetname "")
			)
			(fill
				(thermal_gap 0.5)
				(thermal_bridge_width 0.5)
				(island_removal_mode 0)
			)
			(polygon
				(pts
					(arc
						(start 110.880906 -67.500246)
						(mid 110.118906 -67.500246)
						(end 110.880906 -67.500246)
					)
				)
			)
		)
		(zone
			(layer "F.Cu")
			(hatch none 0.5)
			(connect_pads
				(clearance 0)
			)
			(min_thickness 0.25)
			(keepout
				(tracks allowed)
				(vias not_allowed)
				(pads allowed)
				(copperpour not_allowed)
				(footprints allowed)
			)
			(placement
				(enabled no)
				(sheetname "")
			)
			(fill
				(thermal_gap 0.5)
				(thermal_bridge_width 0.5)
				(island_removal_mode 0)
			)
			(polygon
				(pts
					(arc
						(start 110.880906 -66.499994)
						(mid 110.118906 -66.499994)
						(end 110.880906 -66.499994)
					)
				)
			)
		)
		(zone
			(layer "F.Cu")
			(hatch none 0.5)
			(connect_pads
				(clearance 0)
			)
			(min_thickness 0.25)
			(keepout
				(tracks allowed)
				(vias not_allowed)
				(pads allowed)
				(copperpour not_allowed)
				(footprints allowed)
			)
			(placement
				(enabled no)
				(sheetname "")
			)
			(fill
				(thermal_gap 0.5)
				(thermal_bridge_width 0.5)
				(island_removal_mode 0)
			)
			(polygon
				(pts
					(arc
						(start 110.880906 -65.499996)
						(mid 110.118906 -65.499996)
						(end 110.880906 -65.499996)
					)
				)
			)
		)
		(zone
			(layer "F.Cu")
			(hatch none 0.5)
			(connect_pads
				(clearance 0)
			)
			(min_thickness 0.25)
			(keepout
				(tracks allowed)
				(vias not_allowed)
				(pads allowed)
				(copperpour not_allowed)
				(footprints allowed)
			)
			(placement
				(enabled no)
				(sheetname "")
			)
			(fill
				(thermal_gap 0.5)
				(thermal_bridge_width 0.5)
				(island_removal_mode 0)
			)
			(polygon
				(pts
					(arc
						(start 110.880906 -64.499998)
						(mid 110.118906 -64.499998)
						(end 110.880906 -64.499998)
					)
				)
			)
		)
		(zone
			(layer "F.Cu")
			(hatch none 0.5)
			(connect_pads
				(clearance 0)
			)
			(min_thickness 0.25)
			(keepout
				(tracks allowed)
				(vias not_allowed)
				(pads allowed)
				(copperpour not_allowed)
				(footprints allowed)
			)
			(placement
				(enabled no)
				(sheetname "")
			)
			(fill
				(thermal_gap 0.5)
				(thermal_bridge_width 0.5)
				(island_removal_mode 0)
			)
			(polygon
				(pts
					(arc
						(start 110.880906 -63.5)
						(mid 110.118906 -63.5)
						(end 110.880906 -63.5)
					)
				)
			)
		)
		(zone
			(layer "F.Cu")
			(hatch none 0.5)
			(connect_pads
				(clearance 0)
			)
			(min_thickness 0.25)
			(keepout
				(tracks allowed)
				(vias not_allowed)
				(pads allowed)
				(copperpour not_allowed)
				(footprints allowed)
			)
			(placement
				(enabled no)
				(sheetname "")
			)
			(fill
				(thermal_gap 0.5)
				(thermal_bridge_width 0.5)
				(island_removal_mode 0)
			)
			(polygon
				(pts
					(arc
						(start 110.880906 -62.500002)
						(mid 110.118906 -62.500002)
						(end 110.880906 -62.500002)
					)
				)
			)
		)
		(zone
			(layer "F.Cu")
			(hatch none 0.5)
			(connect_pads
				(clearance 0)
			)
			(min_thickness 0.25)
			(keepout
				(tracks allowed)
				(vias not_allowed)
				(pads allowed)
				(copperpour not_allowed)
				(footprints allowed)
			)
			(placement
				(enabled no)
				(sheetname "")
			)
			(fill
				(thermal_gap 0.5)
				(thermal_bridge_width 0.5)
				(island_removal_mode 0)
			)
			(polygon
				(pts
					(arc
						(start 110.880906 -61.500004)
						(mid 110.118906 -61.500004)
						(end 110.880906 -61.500004)
					)
				)
			)
		)
		(zone
			(layer "F.Cu")
			(hatch none 0.5)
			(connect_pads
				(clearance 0)
			)
			(min_thickness 0.25)
			(keepout
				(tracks allowed)
				(vias not_allowed)
				(pads allowed)
				(copperpour not_allowed)
				(footprints allowed)
			)
			(placement
				(enabled no)
				(sheetname "")
			)
			(fill
				(thermal_gap 0.5)
				(thermal_bridge_width 0.5)
				(island_removal_mode 0)
			)
			(polygon
				(pts
					(arc
						(start 110.880906 -60.500006)
						(mid 110.118906 -60.500006)
						(end 110.880906 -60.500006)
					)
				)
			)
		)
		(zone
			(layer "F.Cu")
			(hatch none 0.5)
			(connect_pads
				(clearance 0)
			)
			(min_thickness 0.25)
			(keepout
				(tracks allowed)
				(vias not_allowed)
				(pads allowed)
				(copperpour not_allowed)
				(footprints allowed)
			)
			(placement
				(enabled no)
				(sheetname "")
			)
			(fill
				(thermal_gap 0.5)
				(thermal_bridge_width 0.5)
				(island_removal_mode 0)
			)
			(polygon
				(pts
					(arc
						(start 110.880906 -59.500008)
						(mid 110.118906 -59.500008)
						(end 110.880906 -59.500008)
					)
				)
			)
		)
		(zone
			(layer "F.Cu")
			(hatch none 0.5)
			(connect_pads
				(clearance 0)
			)
			(min_thickness 0.25)
			(keepout
				(tracks allowed)
				(vias not_allowed)
				(pads allowed)
				(copperpour not_allowed)
				(footprints allowed)
			)
			(placement
				(enabled no)
				(sheetname "")
			)
			(fill
				(thermal_gap 0.5)
				(thermal_bridge_width 0.5)
				(island_removal_mode 0)
			)
			(polygon
				(pts
					(arc
						(start 110.880906 -58.50001)
						(mid 110.118906 -58.50001)
						(end 110.880906 -58.50001)
					)
				)
			)
		)
		(zone
			(layer "F.Cu")
			(hatch none 0.5)
			(connect_pads
				(clearance 0)
			)
			(min_thickness 0.25)
			(keepout
				(tracks allowed)
				(vias not_allowed)
				(pads allowed)
				(copperpour not_allowed)
				(footprints allowed)
			)
			(placement
				(enabled no)
				(sheetname "")
			)
			(fill
				(thermal_gap 0.5)
				(thermal_bridge_width 0.5)
				(island_removal_mode 0)
			)
			(polygon
				(pts
					(arc
						(start 110.880906 -57.500012)
						(mid 110.118906 -57.500012)
						(end 110.880906 -57.500012)
					)
				)
			)
		)
		(zone
			(layer "F.Cu")
			(hatch none 0.5)
			(connect_pads
				(clearance 0)
			)
			(min_thickness 0.25)
			(keepout
				(tracks allowed)
				(vias not_allowed)
				(pads allowed)
				(copperpour not_allowed)
				(footprints allowed)
			)
			(placement
				(enabled no)
				(sheetname "")
			)
			(fill
				(thermal_gap 0.5)
				(thermal_bridge_width 0.5)
				(island_removal_mode 0)
			)
			(polygon
				(pts
					(arc
						(start 110.880906 -56.500014)
						(mid 110.118906 -56.500014)
						(end 110.880906 -56.500014)
					)
				)
			)
		)
		(zone
			(layer "F.Cu")
			(hatch none 0.5)
			(connect_pads
				(clearance 0)
			)
			(min_thickness 0.25)
			(keepout
				(tracks allowed)
				(vias not_allowed)
				(pads allowed)
				(copperpour not_allowed)
				(footprints allowed)
			)
			(placement
				(enabled no)
				(sheetname "")
			)
			(fill
				(thermal_gap 0.5)
				(thermal_bridge_width 0.5)
				(island_removal_mode 0)
			)
			(polygon
				(pts
					(arc
						(start 110.880906 -55.500016)
						(mid 110.118906 -55.500016)
						(end 110.880906 -55.500016)
					)
				)
			)
		)
		(zone
			(layer "F.Cu")
			(hatch none 0.5)
			(connect_pads
				(clearance 0)
			)
			(min_thickness 0.25)
			(keepout
				(tracks allowed)
				(vias not_allowed)
				(pads allowed)
				(copperpour not_allowed)
				(footprints allowed)
			)
			(placement
				(enabled no)
				(sheetname "")
			)
			(fill
				(thermal_gap 0.5)
				(thermal_bridge_width 0.5)
				(island_removal_mode 0)
			)
			(polygon
				(pts
					(arc
						(start 110.880906 -54.500018)
						(mid 110.118906 -54.500018)
						(end 110.880906 -54.500018)
					)
				)
			)
		)
		(zone
			(layer "F.Cu")
			(hatch none 0.5)
			(connect_pads
				(clearance 0)
			)
			(min_thickness 0.25)
			(keepout
				(tracks allowed)
				(vias not_allowed)
				(pads allowed)
				(copperpour not_allowed)
				(footprints allowed)
			)
			(placement
				(enabled no)
				(sheetname "")
			)
			(fill
				(thermal_gap 0.5)
				(thermal_bridge_width 0.5)
				(island_removal_mode 0)
			)
			(polygon
				(pts
					(arc
						(start 110.880906 -53.50002)
						(mid 110.118906 -53.50002)
						(end 110.880906 -53.50002)
					)
				)
			)
		)
		(zone
			(layer "F.Cu")
			(hatch none 0.5)
			(connect_pads
				(clearance 0)
			)
			(min_thickness 0.25)
			(keepout
				(tracks allowed)
				(vias not_allowed)
				(pads allowed)
				(copperpour not_allowed)
				(footprints allowed)
			)
			(placement
				(enabled no)
				(sheetname "")
			)
			(fill
				(thermal_gap 0.5)
				(thermal_bridge_width 0.5)
				(island_removal_mode 0)
			)
			(polygon
				(pts
					(arc
						(start 110.880906 -52.500022)
						(mid 110.118906 -52.500022)
						(end 110.880906 -52.500022)
					)
				)
			)
		)
		(zone
			(layer "F.Cu")
			(hatch none 0.5)
			(connect_pads
				(clearance 0)
			)
			(min_thickness 0.25)
			(keepout
				(tracks allowed)
				(vias not_allowed)
				(pads allowed)
				(copperpour not_allowed)
				(footprints allowed)
			)
			(placement
				(enabled no)
				(sheetname "")
			)
			(fill
				(thermal_gap 0.5)
				(thermal_bridge_width 0.5)
				(island_removal_mode 0)
			)
			(polygon
				(pts
					(arc
						(start 110.880906 -51.500024)
						(mid 110.118906 -51.500024)
						(end 110.880906 -51.500024)
					)
				)
			)
		)
		(zone
			(layer "F.Cu")
			(hatch none 0.5)
			(connect_pads
				(clearance 0)
			)
			(min_thickness 0.25)
			(keepout
				(tracks allowed)
				(vias not_allowed)
				(pads allowed)
				(copperpour not_allowed)
				(footprints allowed)
			)
			(placement
				(enabled no)
				(sheetname "")
			)
			(fill
				(thermal_gap 0.5)
				(thermal_bridge_width 0.5)
				(island_removal_mode 0)
			)
			(polygon
				(pts
					(arc
						(start 111.880904 -82.500216)
						(mid 111.118904 -82.500216)
						(end 111.880904 -82.500216)
					)
				)
			)
		)
		(zone
			(layer "F.Cu")
			(hatch none 0.5)
			(connect_pads
				(clearance 0)
			)
			(min_thickness 0.25)
			(keepout
				(tracks allowed)
				(vias not_allowed)
				(pads allowed)
				(copperpour not_allowed)
				(footprints allowed)
			)
			(placement
				(enabled no)
				(sheetname "")
			)
			(fill
				(thermal_gap 0.5)
				(thermal_bridge_width 0.5)
				(island_removal_mode 0)
			)
			(polygon
				(pts
					(arc
						(start 111.880904 -81.500218)
						(mid 111.118904 -81.500218)
						(end 111.880904 -81.500218)
					)
				)
			)
		)
		(zone
			(layer "F.Cu")
			(hatch none 0.5)
			(connect_pads
				(clearance 0)
			)
			(min_thickness 0.25)
			(keepout
				(tracks allowed)
				(vias not_allowed)
				(pads allowed)
				(copperpour not_allowed)
				(footprints allowed)
			)
			(placement
				(enabled no)
				(sheetname "")
			)
			(fill
				(thermal_gap 0.5)
				(thermal_bridge_width 0.5)
				(island_removal_mode 0)
			)
			(polygon
				(pts
					(arc
						(start 111.880904 -80.50022)
						(mid 111.118904 -80.50022)
						(end 111.880904 -80.50022)
					)
				)
			)
		)
		(zone
			(layer "F.Cu")
			(hatch none 0.5)
			(connect_pads
				(clearance 0)
			)
			(min_thickness 0.25)
			(keepout
				(tracks allowed)
				(vias not_allowed)
				(pads allowed)
				(copperpour not_allowed)
				(footprints allowed)
			)
			(placement
				(enabled no)
				(sheetname "")
			)
			(fill
				(thermal_gap 0.5)
				(thermal_bridge_width 0.5)
				(island_removal_mode 0)
			)
			(polygon
				(pts
					(arc
						(start 111.880904 -79.500222)
						(mid 111.118904 -79.500222)
						(end 111.880904 -79.500222)
					)
				)
			)
		)
		(zone
			(layer "F.Cu")
			(hatch none 0.5)
			(connect_pads
				(clearance 0)
			)
			(min_thickness 0.25)
			(keepout
				(tracks allowed)
				(vias not_allowed)
				(pads allowed)
				(copperpour not_allowed)
				(footprints allowed)
			)
			(placement
				(enabled no)
				(sheetname "")
			)
			(fill
				(thermal_gap 0.5)
				(thermal_bridge_width 0.5)
				(island_removal_mode 0)
			)
			(polygon
				(pts
					(arc
						(start 111.880904 -78.500224)
						(mid 111.118904 -78.500224)
						(end 111.880904 -78.500224)
					)
				)
			)
		)
		(zone
			(layer "F.Cu")
			(hatch none 0.5)
			(connect_pads
				(clearance 0)
			)
			(min_thickness 0.25)
			(keepout
				(tracks allowed)
				(vias not_allowed)
				(pads allowed)
				(copperpour not_allowed)
				(footprints allowed)
			)
			(placement
				(enabled no)
				(sheetname "")
			)
			(fill
				(thermal_gap 0.5)
				(thermal_bridge_width 0.5)
				(island_removal_mode 0)
			)
			(polygon
				(pts
					(arc
						(start 111.880904 -77.500226)
						(mid 111.118904 -77.500226)
						(end 111.880904 -77.500226)
					)
				)
			)
		)
		(zone
			(layer "F.Cu")
			(hatch none 0.5)
			(connect_pads
				(clearance 0)
			)
			(min_thickness 0.25)
			(keepout
				(tracks allowed)
				(vias not_allowed)
				(pads allowed)
				(copperpour not_allowed)
				(footprints allowed)
			)
			(placement
				(enabled no)
				(sheetname "")
			)
			(fill
				(thermal_gap 0.5)
				(thermal_bridge_width 0.5)
				(island_removal_mode 0)
			)
			(polygon
				(pts
					(arc
						(start 111.880904 -76.500228)
						(mid 111.118904 -76.500228)
						(end 111.880904 -76.500228)
					)
				)
			)
		)
		(zone
			(layer "F.Cu")
			(hatch none 0.5)
			(connect_pads
				(clearance 0)
			)
			(min_thickness 0.25)
			(keepout
				(tracks allowed)
				(vias not_allowed)
				(pads allowed)
				(copperpour not_allowed)
				(footprints allowed)
			)
			(placement
				(enabled no)
				(sheetname "")
			)
			(fill
				(thermal_gap 0.5)
				(thermal_bridge_width 0.5)
				(island_removal_mode 0)
			)
			(polygon
				(pts
					(arc
						(start 111.880904 -75.50023)
						(mid 111.118904 -75.50023)
						(end 111.880904 -75.50023)
					)
				)
			)
		)
		(zone
			(layer "F.Cu")
			(hatch none 0.5)
			(connect_pads
				(clearance 0)
			)
			(min_thickness 0.25)
			(keepout
				(tracks allowed)
				(vias not_allowed)
				(pads allowed)
				(copperpour not_allowed)
				(footprints allowed)
			)
			(placement
				(enabled no)
				(sheetname "")
			)
			(fill
				(thermal_gap 0.5)
				(thermal_bridge_width 0.5)
				(island_removal_mode 0)
			)
			(polygon
				(pts
					(arc
						(start 111.880904 -74.500232)
						(mid 111.118904 -74.500232)
						(end 111.880904 -74.500232)
					)
				)
			)
		)
		(zone
			(layer "F.Cu")
			(hatch none 0.5)
			(connect_pads
				(clearance 0)
			)
			(min_thickness 0.25)
			(keepout
				(tracks allowed)
				(vias not_allowed)
				(pads allowed)
				(copperpour not_allowed)
				(footprints allowed)
			)
			(placement
				(enabled no)
				(sheetname "")
			)
			(fill
				(thermal_gap 0.5)
				(thermal_bridge_width 0.5)
				(island_removal_mode 0)
			)
			(polygon
				(pts
					(arc
						(start 111.880904 -73.500234)
						(mid 111.118904 -73.500234)
						(end 111.880904 -73.500234)
					)
				)
			)
		)
		(zone
			(layer "F.Cu")
			(hatch none 0.5)
			(connect_pads
				(clearance 0)
			)
			(min_thickness 0.25)
			(keepout
				(tracks allowed)
				(vias not_allowed)
				(pads allowed)
				(copperpour not_allowed)
				(footprints allowed)
			)
			(placement
				(enabled no)
				(sheetname "")
			)
			(fill
				(thermal_gap 0.5)
				(thermal_bridge_width 0.5)
				(island_removal_mode 0)
			)
			(polygon
				(pts
					(arc
						(start 111.880904 -72.500236)
						(mid 111.118904 -72.500236)
						(end 111.880904 -72.500236)
					)
				)
			)
		)
		(zone
			(layer "F.Cu")
			(hatch none 0.5)
			(connect_pads
				(clearance 0)
			)
			(min_thickness 0.25)
			(keepout
				(tracks allowed)
				(vias not_allowed)
				(pads allowed)
				(copperpour not_allowed)
				(footprints allowed)
			)
			(placement
				(enabled no)
				(sheetname "")
			)
			(fill
				(thermal_gap 0.5)
				(thermal_bridge_width 0.5)
				(island_removal_mode 0)
			)
			(polygon
				(pts
					(arc
						(start 111.880904 -71.500238)
						(mid 111.118904 -71.500238)
						(end 111.880904 -71.500238)
					)
				)
			)
		)
		(zone
			(layer "F.Cu")
			(hatch none 0.5)
			(connect_pads
				(clearance 0)
			)
			(min_thickness 0.25)
			(keepout
				(tracks allowed)
				(vias not_allowed)
				(pads allowed)
				(copperpour not_allowed)
				(footprints allowed)
			)
			(placement
				(enabled no)
				(sheetname "")
			)
			(fill
				(thermal_gap 0.5)
				(thermal_bridge_width 0.5)
				(island_removal_mode 0)
			)
			(polygon
				(pts
					(arc
						(start 111.880904 -70.50024)
						(mid 111.118904 -70.50024)
						(end 111.880904 -70.50024)
					)
				)
			)
		)
		(zone
			(layer "F.Cu")
			(hatch none 0.5)
			(connect_pads
				(clearance 0)
			)
			(min_thickness 0.25)
			(keepout
				(tracks allowed)
				(vias not_allowed)
				(pads allowed)
				(copperpour not_allowed)
				(footprints allowed)
			)
			(placement
				(enabled no)
				(sheetname "")
			)
			(fill
				(thermal_gap 0.5)
				(thermal_bridge_width 0.5)
				(island_removal_mode 0)
			)
			(polygon
				(pts
					(arc
						(start 111.880904 -69.500242)
						(mid 111.118904 -69.500242)
						(end 111.880904 -69.500242)
					)
				)
			)
		)
		(zone
			(layer "F.Cu")
			(hatch none 0.5)
			(connect_pads
				(clearance 0)
			)
			(min_thickness 0.25)
			(keepout
				(tracks allowed)
				(vias not_allowed)
				(pads allowed)
				(copperpour not_allowed)
				(footprints allowed)
			)
			(placement
				(enabled no)
				(sheetname "")
			)
			(fill
				(thermal_gap 0.5)
				(thermal_bridge_width 0.5)
				(island_removal_mode 0)
			)
			(polygon
				(pts
					(arc
						(start 111.880904 -68.500244)
						(mid 111.118904 -68.500244)
						(end 111.880904 -68.500244)
					)
				)
			)
		)
		(zone
			(layer "F.Cu")
			(hatch none 0.5)
			(connect_pads
				(clearance 0)
			)
			(min_thickness 0.25)
			(keepout
				(tracks allowed)
				(vias not_allowed)
				(pads allowed)
				(copperpour not_allowed)
				(footprints allowed)
			)
			(placement
				(enabled no)
				(sheetname "")
			)
			(fill
				(thermal_gap 0.5)
				(thermal_bridge_width 0.5)
				(island_removal_mode 0)
			)
			(polygon
				(pts
					(arc
						(start 111.880904 -67.500246)
						(mid 111.118904 -67.500246)
						(end 111.880904 -67.500246)
					)
				)
			)
		)
		(zone
			(layer "F.Cu")
			(hatch none 0.5)
			(connect_pads
				(clearance 0)
			)
			(min_thickness 0.25)
			(keepout
				(tracks allowed)
				(vias not_allowed)
				(pads allowed)
				(copperpour not_allowed)
				(footprints allowed)
			)
			(placement
				(enabled no)
				(sheetname "")
			)
			(fill
				(thermal_gap 0.5)
				(thermal_bridge_width 0.5)
				(island_removal_mode 0)
			)
			(polygon
				(pts
					(arc
						(start 111.880904 -66.499994)
						(mid 111.118904 -66.499994)
						(end 111.880904 -66.499994)
					)
				)
			)
		)
		(zone
			(layer "F.Cu")
			(hatch none 0.5)
			(connect_pads
				(clearance 0)
			)
			(min_thickness 0.25)
			(keepout
				(tracks allowed)
				(vias not_allowed)
				(pads allowed)
				(copperpour not_allowed)
				(footprints allowed)
			)
			(placement
				(enabled no)
				(sheetname "")
			)
			(fill
				(thermal_gap 0.5)
				(thermal_bridge_width 0.5)
				(island_removal_mode 0)
			)
			(polygon
				(pts
					(arc
						(start 111.880904 -65.499996)
						(mid 111.118904 -65.499996)
						(end 111.880904 -65.499996)
					)
				)
			)
		)
		(zone
			(layer "F.Cu")
			(hatch none 0.5)
			(connect_pads
				(clearance 0)
			)
			(min_thickness 0.25)
			(keepout
				(tracks allowed)
				(vias not_allowed)
				(pads allowed)
				(copperpour not_allowed)
				(footprints allowed)
			)
			(placement
				(enabled no)
				(sheetname "")
			)
			(fill
				(thermal_gap 0.5)
				(thermal_bridge_width 0.5)
				(island_removal_mode 0)
			)
			(polygon
				(pts
					(arc
						(start 111.880904 -64.499998)
						(mid 111.118904 -64.499998)
						(end 111.880904 -64.499998)
					)
				)
			)
		)
		(zone
			(layer "F.Cu")
			(hatch none 0.5)
			(connect_pads
				(clearance 0)
			)
			(min_thickness 0.25)
			(keepout
				(tracks allowed)
				(vias not_allowed)
				(pads allowed)
				(copperpour not_allowed)
				(footprints allowed)
			)
			(placement
				(enabled no)
				(sheetname "")
			)
			(fill
				(thermal_gap 0.5)
				(thermal_bridge_width 0.5)
				(island_removal_mode 0)
			)
			(polygon
				(pts
					(arc
						(start 111.880904 -63.5)
						(mid 111.118904 -63.5)
						(end 111.880904 -63.5)
					)
				)
			)
		)
		(zone
			(layer "F.Cu")
			(hatch none 0.5)
			(connect_pads
				(clearance 0)
			)
			(min_thickness 0.25)
			(keepout
				(tracks allowed)
				(vias not_allowed)
				(pads allowed)
				(copperpour not_allowed)
				(footprints allowed)
			)
			(placement
				(enabled no)
				(sheetname "")
			)
			(fill
				(thermal_gap 0.5)
				(thermal_bridge_width 0.5)
				(island_removal_mode 0)
			)
			(polygon
				(pts
					(arc
						(start 111.880904 -62.500002)
						(mid 111.118904 -62.500002)
						(end 111.880904 -62.500002)
					)
				)
			)
		)
		(zone
			(layer "F.Cu")
			(hatch none 0.5)
			(connect_pads
				(clearance 0)
			)
			(min_thickness 0.25)
			(keepout
				(tracks allowed)
				(vias not_allowed)
				(pads allowed)
				(copperpour not_allowed)
				(footprints allowed)
			)
			(placement
				(enabled no)
				(sheetname "")
			)
			(fill
				(thermal_gap 0.5)
				(thermal_bridge_width 0.5)
				(island_removal_mode 0)
			)
			(polygon
				(pts
					(arc
						(start 111.880904 -61.500004)
						(mid 111.118904 -61.500004)
						(end 111.880904 -61.500004)
					)
				)
			)
		)
		(zone
			(layer "F.Cu")
			(hatch none 0.5)
			(connect_pads
				(clearance 0)
			)
			(min_thickness 0.25)
			(keepout
				(tracks allowed)
				(vias not_allowed)
				(pads allowed)
				(copperpour not_allowed)
				(footprints allowed)
			)
			(placement
				(enabled no)
				(sheetname "")
			)
			(fill
				(thermal_gap 0.5)
				(thermal_bridge_width 0.5)
				(island_removal_mode 0)
			)
			(polygon
				(pts
					(arc
						(start 111.880904 -60.500006)
						(mid 111.118904 -60.500006)
						(end 111.880904 -60.500006)
					)
				)
			)
		)
		(zone
			(layer "F.Cu")
			(hatch none 0.5)
			(connect_pads
				(clearance 0)
			)
			(min_thickness 0.25)
			(keepout
				(tracks allowed)
				(vias not_allowed)
				(pads allowed)
				(copperpour not_allowed)
				(footprints allowed)
			)
			(placement
				(enabled no)
				(sheetname "")
			)
			(fill
				(thermal_gap 0.5)
				(thermal_bridge_width 0.5)
				(island_removal_mode 0)
			)
			(polygon
				(pts
					(arc
						(start 111.880904 -59.500008)
						(mid 111.118904 -59.500008)
						(end 111.880904 -59.500008)
					)
				)
			)
		)
		(zone
			(layer "F.Cu")
			(hatch none 0.5)
			(connect_pads
				(clearance 0)
			)
			(min_thickness 0.25)
			(keepout
				(tracks allowed)
				(vias not_allowed)
				(pads allowed)
				(copperpour not_allowed)
				(footprints allowed)
			)
			(placement
				(enabled no)
				(sheetname "")
			)
			(fill
				(thermal_gap 0.5)
				(thermal_bridge_width 0.5)
				(island_removal_mode 0)
			)
			(polygon
				(pts
					(arc
						(start 111.880904 -58.50001)
						(mid 111.118904 -58.50001)
						(end 111.880904 -58.50001)
					)
				)
			)
		)
		(zone
			(layer "F.Cu")
			(hatch none 0.5)
			(connect_pads
				(clearance 0)
			)
			(min_thickness 0.25)
			(keepout
				(tracks allowed)
				(vias not_allowed)
				(pads allowed)
				(copperpour not_allowed)
				(footprints allowed)
			)
			(placement
				(enabled no)
				(sheetname "")
			)
			(fill
				(thermal_gap 0.5)
				(thermal_bridge_width 0.5)
				(island_removal_mode 0)
			)
			(polygon
				(pts
					(arc
						(start 111.880904 -57.500012)
						(mid 111.118904 -57.500012)
						(end 111.880904 -57.500012)
					)
				)
			)
		)
		(zone
			(layer "F.Cu")
			(hatch none 0.5)
			(connect_pads
				(clearance 0)
			)
			(min_thickness 0.25)
			(keepout
				(tracks allowed)
				(vias not_allowed)
				(pads allowed)
				(copperpour not_allowed)
				(footprints allowed)
			)
			(placement
				(enabled no)
				(sheetname "")
			)
			(fill
				(thermal_gap 0.5)
				(thermal_bridge_width 0.5)
				(island_removal_mode 0)
			)
			(polygon
				(pts
					(arc
						(start 111.880904 -56.500014)
						(mid 111.118904 -56.500014)
						(end 111.880904 -56.500014)
					)
				)
			)
		)
		(zone
			(layer "F.Cu")
			(hatch none 0.5)
			(connect_pads
				(clearance 0)
			)
			(min_thickness 0.25)
			(keepout
				(tracks allowed)
				(vias not_allowed)
				(pads allowed)
				(copperpour not_allowed)
				(footprints allowed)
			)
			(placement
				(enabled no)
				(sheetname "")
			)
			(fill
				(thermal_gap 0.5)
				(thermal_bridge_width 0.5)
				(island_removal_mode 0)
			)
			(polygon
				(pts
					(arc
						(start 111.880904 -55.500016)
						(mid 111.118904 -55.500016)
						(end 111.880904 -55.500016)
					)
				)
			)
		)
		(zone
			(layer "F.Cu")
			(hatch none 0.5)
			(connect_pads
				(clearance 0)
			)
			(min_thickness 0.25)
			(keepout
				(tracks allowed)
				(vias not_allowed)
				(pads allowed)
				(copperpour not_allowed)
				(footprints allowed)
			)
			(placement
				(enabled no)
				(sheetname "")
			)
			(fill
				(thermal_gap 0.5)
				(thermal_bridge_width 0.5)
				(island_removal_mode 0)
			)
			(polygon
				(pts
					(arc
						(start 111.880904 -54.500018)
						(mid 111.118904 -54.500018)
						(end 111.880904 -54.500018)
					)
				)
			)
		)
		(zone
			(layer "F.Cu")
			(hatch none 0.5)
			(connect_pads
				(clearance 0)
			)
			(min_thickness 0.25)
			(keepout
				(tracks allowed)
				(vias not_allowed)
				(pads allowed)
				(copperpour not_allowed)
				(footprints allowed)
			)
			(placement
				(enabled no)
				(sheetname "")
			)
			(fill
				(thermal_gap 0.5)
				(thermal_bridge_width 0.5)
				(island_removal_mode 0)
			)
			(polygon
				(pts
					(arc
						(start 111.880904 -53.50002)
						(mid 111.118904 -53.50002)
						(end 111.880904 -53.50002)
					)
				)
			)
		)
		(zone
			(layer "F.Cu")
			(hatch none 0.5)
			(connect_pads
				(clearance 0)
			)
			(min_thickness 0.25)
			(keepout
				(tracks allowed)
				(vias not_allowed)
				(pads allowed)
				(copperpour not_allowed)
				(footprints allowed)
			)
			(placement
				(enabled no)
				(sheetname "")
			)
			(fill
				(thermal_gap 0.5)
				(thermal_bridge_width 0.5)
				(island_removal_mode 0)
			)
			(polygon
				(pts
					(arc
						(start 111.880904 -52.500022)
						(mid 111.118904 -52.500022)
						(end 111.880904 -52.500022)
					)
				)
			)
		)
		(zone
			(layer "F.Cu")
			(hatch none 0.5)
			(connect_pads
				(clearance 0)
			)
			(min_thickness 0.25)
			(keepout
				(tracks allowed)
				(vias not_allowed)
				(pads allowed)
				(copperpour not_allowed)
				(footprints allowed)
			)
			(placement
				(enabled no)
				(sheetname "")
			)
			(fill
				(thermal_gap 0.5)
				(thermal_bridge_width 0.5)
				(island_removal_mode 0)
			)
			(polygon
				(pts
					(arc
						(start 111.880904 -51.500024)
						(mid 111.118904 -51.500024)
						(end 111.880904 -51.500024)
					)
				)
			)
		)
		(zone
			(layer "F.Cu")
			(hatch none 0.5)
			(connect_pads
				(clearance 0)
			)
			(min_thickness 0.25)
			(keepout
				(tracks allowed)
				(vias not_allowed)
				(pads allowed)
				(copperpour not_allowed)
				(footprints allowed)
			)
			(placement
				(enabled no)
				(sheetname "")
			)
			(fill
				(thermal_gap 0.5)
				(thermal_bridge_width 0.5)
				(island_removal_mode 0)
			)
			(polygon
				(pts
					(arc
						(start 112.880902 -82.500216)
						(mid 112.118902 -82.500216)
						(end 112.880902 -82.500216)
					)
				)
			)
		)
		(zone
			(layer "F.Cu")
			(hatch none 0.5)
			(connect_pads
				(clearance 0)
			)
			(min_thickness 0.25)
			(keepout
				(tracks allowed)
				(vias not_allowed)
				(pads allowed)
				(copperpour not_allowed)
				(footprints allowed)
			)
			(placement
				(enabled no)
				(sheetname "")
			)
			(fill
				(thermal_gap 0.5)
				(thermal_bridge_width 0.5)
				(island_removal_mode 0)
			)
			(polygon
				(pts
					(arc
						(start 112.880902 -81.500218)
						(mid 112.118902 -81.500218)
						(end 112.880902 -81.500218)
					)
				)
			)
		)
		(zone
			(layer "F.Cu")
			(hatch none 0.5)
			(connect_pads
				(clearance 0)
			)
			(min_thickness 0.25)
			(keepout
				(tracks allowed)
				(vias not_allowed)
				(pads allowed)
				(copperpour not_allowed)
				(footprints allowed)
			)
			(placement
				(enabled no)
				(sheetname "")
			)
			(fill
				(thermal_gap 0.5)
				(thermal_bridge_width 0.5)
				(island_removal_mode 0)
			)
			(polygon
				(pts
					(arc
						(start 112.880902 -80.50022)
						(mid 112.118902 -80.50022)
						(end 112.880902 -80.50022)
					)
				)
			)
		)
		(zone
			(layer "F.Cu")
			(hatch none 0.5)
			(connect_pads
				(clearance 0)
			)
			(min_thickness 0.25)
			(keepout
				(tracks allowed)
				(vias not_allowed)
				(pads allowed)
				(copperpour not_allowed)
				(footprints allowed)
			)
			(placement
				(enabled no)
				(sheetname "")
			)
			(fill
				(thermal_gap 0.5)
				(thermal_bridge_width 0.5)
				(island_removal_mode 0)
			)
			(polygon
				(pts
					(arc
						(start 112.880902 -79.500222)
						(mid 112.118902 -79.500222)
						(end 112.880902 -79.500222)
					)
				)
			)
		)
		(zone
			(layer "F.Cu")
			(hatch none 0.5)
			(connect_pads
				(clearance 0)
			)
			(min_thickness 0.25)
			(keepout
				(tracks allowed)
				(vias not_allowed)
				(pads allowed)
				(copperpour not_allowed)
				(footprints allowed)
			)
			(placement
				(enabled no)
				(sheetname "")
			)
			(fill
				(thermal_gap 0.5)
				(thermal_bridge_width 0.5)
				(island_removal_mode 0)
			)
			(polygon
				(pts
					(arc
						(start 112.880902 -78.500224)
						(mid 112.118902 -78.500224)
						(end 112.880902 -78.500224)
					)
				)
			)
		)
		(zone
			(layer "F.Cu")
			(hatch none 0.5)
			(connect_pads
				(clearance 0)
			)
			(min_thickness 0.25)
			(keepout
				(tracks allowed)
				(vias not_allowed)
				(pads allowed)
				(copperpour not_allowed)
				(footprints allowed)
			)
			(placement
				(enabled no)
				(sheetname "")
			)
			(fill
				(thermal_gap 0.5)
				(thermal_bridge_width 0.5)
				(island_removal_mode 0)
			)
			(polygon
				(pts
					(arc
						(start 112.880902 -77.500226)
						(mid 112.118902 -77.500226)
						(end 112.880902 -77.500226)
					)
				)
			)
		)
		(zone
			(layer "F.Cu")
			(hatch none 0.5)
			(connect_pads
				(clearance 0)
			)
			(min_thickness 0.25)
			(keepout
				(tracks allowed)
				(vias not_allowed)
				(pads allowed)
				(copperpour not_allowed)
				(footprints allowed)
			)
			(placement
				(enabled no)
				(sheetname "")
			)
			(fill
				(thermal_gap 0.5)
				(thermal_bridge_width 0.5)
				(island_removal_mode 0)
			)
			(polygon
				(pts
					(arc
						(start 112.880902 -76.500228)
						(mid 112.118902 -76.500228)
						(end 112.880902 -76.500228)
					)
				)
			)
		)
		(zone
			(layer "F.Cu")
			(hatch none 0.5)
			(connect_pads
				(clearance 0)
			)
			(min_thickness 0.25)
			(keepout
				(tracks allowed)
				(vias not_allowed)
				(pads allowed)
				(copperpour not_allowed)
				(footprints allowed)
			)
			(placement
				(enabled no)
				(sheetname "")
			)
			(fill
				(thermal_gap 0.5)
				(thermal_bridge_width 0.5)
				(island_removal_mode 0)
			)
			(polygon
				(pts
					(arc
						(start 112.880902 -75.50023)
						(mid 112.118902 -75.50023)
						(end 112.880902 -75.50023)
					)
				)
			)
		)
		(zone
			(layer "F.Cu")
			(hatch none 0.5)
			(connect_pads
				(clearance 0)
			)
			(min_thickness 0.25)
			(keepout
				(tracks allowed)
				(vias not_allowed)
				(pads allowed)
				(copperpour not_allowed)
				(footprints allowed)
			)
			(placement
				(enabled no)
				(sheetname "")
			)
			(fill
				(thermal_gap 0.5)
				(thermal_bridge_width 0.5)
				(island_removal_mode 0)
			)
			(polygon
				(pts
					(arc
						(start 112.880902 -74.500232)
						(mid 112.118902 -74.500232)
						(end 112.880902 -74.500232)
					)
				)
			)
		)
		(zone
			(layer "F.Cu")
			(hatch none 0.5)
			(connect_pads
				(clearance 0)
			)
			(min_thickness 0.25)
			(keepout
				(tracks allowed)
				(vias not_allowed)
				(pads allowed)
				(copperpour not_allowed)
				(footprints allowed)
			)
			(placement
				(enabled no)
				(sheetname "")
			)
			(fill
				(thermal_gap 0.5)
				(thermal_bridge_width 0.5)
				(island_removal_mode 0)
			)
			(polygon
				(pts
					(arc
						(start 112.880902 -73.500234)
						(mid 112.118902 -73.500234)
						(end 112.880902 -73.500234)
					)
				)
			)
		)
		(zone
			(layer "F.Cu")
			(hatch none 0.5)
			(connect_pads
				(clearance 0)
			)
			(min_thickness 0.25)
			(keepout
				(tracks allowed)
				(vias not_allowed)
				(pads allowed)
				(copperpour not_allowed)
				(footprints allowed)
			)
			(placement
				(enabled no)
				(sheetname "")
			)
			(fill
				(thermal_gap 0.5)
				(thermal_bridge_width 0.5)
				(island_removal_mode 0)
			)
			(polygon
				(pts
					(arc
						(start 112.880902 -72.500236)
						(mid 112.118902 -72.500236)
						(end 112.880902 -72.500236)
					)
				)
			)
		)
		(zone
			(layer "F.Cu")
			(hatch none 0.5)
			(connect_pads
				(clearance 0)
			)
			(min_thickness 0.25)
			(keepout
				(tracks allowed)
				(vias not_allowed)
				(pads allowed)
				(copperpour not_allowed)
				(footprints allowed)
			)
			(placement
				(enabled no)
				(sheetname "")
			)
			(fill
				(thermal_gap 0.5)
				(thermal_bridge_width 0.5)
				(island_removal_mode 0)
			)
			(polygon
				(pts
					(arc
						(start 112.880902 -71.500238)
						(mid 112.118902 -71.500238)
						(end 112.880902 -71.500238)
					)
				)
			)
		)
		(zone
			(layer "F.Cu")
			(hatch none 0.5)
			(connect_pads
				(clearance 0)
			)
			(min_thickness 0.25)
			(keepout
				(tracks allowed)
				(vias not_allowed)
				(pads allowed)
				(copperpour not_allowed)
				(footprints allowed)
			)
			(placement
				(enabled no)
				(sheetname "")
			)
			(fill
				(thermal_gap 0.5)
				(thermal_bridge_width 0.5)
				(island_removal_mode 0)
			)
			(polygon
				(pts
					(arc
						(start 112.880902 -70.50024)
						(mid 112.118902 -70.50024)
						(end 112.880902 -70.50024)
					)
				)
			)
		)
		(zone
			(layer "F.Cu")
			(hatch none 0.5)
			(connect_pads
				(clearance 0)
			)
			(min_thickness 0.25)
			(keepout
				(tracks allowed)
				(vias not_allowed)
				(pads allowed)
				(copperpour not_allowed)
				(footprints allowed)
			)
			(placement
				(enabled no)
				(sheetname "")
			)
			(fill
				(thermal_gap 0.5)
				(thermal_bridge_width 0.5)
				(island_removal_mode 0)
			)
			(polygon
				(pts
					(arc
						(start 112.880902 -69.500242)
						(mid 112.118902 -69.500242)
						(end 112.880902 -69.500242)
					)
				)
			)
		)
		(zone
			(layer "F.Cu")
			(hatch none 0.5)
			(connect_pads
				(clearance 0)
			)
			(min_thickness 0.25)
			(keepout
				(tracks allowed)
				(vias not_allowed)
				(pads allowed)
				(copperpour not_allowed)
				(footprints allowed)
			)
			(placement
				(enabled no)
				(sheetname "")
			)
			(fill
				(thermal_gap 0.5)
				(thermal_bridge_width 0.5)
				(island_removal_mode 0)
			)
			(polygon
				(pts
					(arc
						(start 112.880902 -68.500244)
						(mid 112.118902 -68.500244)
						(end 112.880902 -68.500244)
					)
				)
			)
		)
		(zone
			(layer "F.Cu")
			(hatch none 0.5)
			(connect_pads
				(clearance 0)
			)
			(min_thickness 0.25)
			(keepout
				(tracks allowed)
				(vias not_allowed)
				(pads allowed)
				(copperpour not_allowed)
				(footprints allowed)
			)
			(placement
				(enabled no)
				(sheetname "")
			)
			(fill
				(thermal_gap 0.5)
				(thermal_bridge_width 0.5)
				(island_removal_mode 0)
			)
			(polygon
				(pts
					(arc
						(start 112.880902 -67.500246)
						(mid 112.118902 -67.500246)
						(end 112.880902 -67.500246)
					)
				)
			)
		)
		(zone
			(layer "F.Cu")
			(hatch none 0.5)
			(connect_pads
				(clearance 0)
			)
			(min_thickness 0.25)
			(keepout
				(tracks allowed)
				(vias not_allowed)
				(pads allowed)
				(copperpour not_allowed)
				(footprints allowed)
			)
			(placement
				(enabled no)
				(sheetname "")
			)
			(fill
				(thermal_gap 0.5)
				(thermal_bridge_width 0.5)
				(island_removal_mode 0)
			)
			(polygon
				(pts
					(arc
						(start 112.880902 -66.499994)
						(mid 112.118902 -66.499994)
						(end 112.880902 -66.499994)
					)
				)
			)
		)
		(zone
			(layer "F.Cu")
			(hatch none 0.5)
			(connect_pads
				(clearance 0)
			)
			(min_thickness 0.25)
			(keepout
				(tracks allowed)
				(vias not_allowed)
				(pads allowed)
				(copperpour not_allowed)
				(footprints allowed)
			)
			(placement
				(enabled no)
				(sheetname "")
			)
			(fill
				(thermal_gap 0.5)
				(thermal_bridge_width 0.5)
				(island_removal_mode 0)
			)
			(polygon
				(pts
					(arc
						(start 112.880902 -65.499996)
						(mid 112.118902 -65.499996)
						(end 112.880902 -65.499996)
					)
				)
			)
		)
		(zone
			(layer "F.Cu")
			(hatch none 0.5)
			(connect_pads
				(clearance 0)
			)
			(min_thickness 0.25)
			(keepout
				(tracks allowed)
				(vias not_allowed)
				(pads allowed)
				(copperpour not_allowed)
				(footprints allowed)
			)
			(placement
				(enabled no)
				(sheetname "")
			)
			(fill
				(thermal_gap 0.5)
				(thermal_bridge_width 0.5)
				(island_removal_mode 0)
			)
			(polygon
				(pts
					(arc
						(start 112.880902 -64.499998)
						(mid 112.118902 -64.499998)
						(end 112.880902 -64.499998)
					)
				)
			)
		)
		(zone
			(layer "F.Cu")
			(hatch none 0.5)
			(connect_pads
				(clearance 0)
			)
			(min_thickness 0.25)
			(keepout
				(tracks allowed)
				(vias not_allowed)
				(pads allowed)
				(copperpour not_allowed)
				(footprints allowed)
			)
			(placement
				(enabled no)
				(sheetname "")
			)
			(fill
				(thermal_gap 0.5)
				(thermal_bridge_width 0.5)
				(island_removal_mode 0)
			)
			(polygon
				(pts
					(arc
						(start 112.880902 -63.5)
						(mid 112.118902 -63.5)
						(end 112.880902 -63.5)
					)
				)
			)
		)
		(zone
			(layer "F.Cu")
			(hatch none 0.5)
			(connect_pads
				(clearance 0)
			)
			(min_thickness 0.25)
			(keepout
				(tracks allowed)
				(vias not_allowed)
				(pads allowed)
				(copperpour not_allowed)
				(footprints allowed)
			)
			(placement
				(enabled no)
				(sheetname "")
			)
			(fill
				(thermal_gap 0.5)
				(thermal_bridge_width 0.5)
				(island_removal_mode 0)
			)
			(polygon
				(pts
					(arc
						(start 112.880902 -62.500002)
						(mid 112.118902 -62.500002)
						(end 112.880902 -62.500002)
					)
				)
			)
		)
		(zone
			(layer "F.Cu")
			(hatch none 0.5)
			(connect_pads
				(clearance 0)
			)
			(min_thickness 0.25)
			(keepout
				(tracks allowed)
				(vias not_allowed)
				(pads allowed)
				(copperpour not_allowed)
				(footprints allowed)
			)
			(placement
				(enabled no)
				(sheetname "")
			)
			(fill
				(thermal_gap 0.5)
				(thermal_bridge_width 0.5)
				(island_removal_mode 0)
			)
			(polygon
				(pts
					(arc
						(start 112.880902 -61.500004)
						(mid 112.118902 -61.500004)
						(end 112.880902 -61.500004)
					)
				)
			)
		)
		(zone
			(layer "F.Cu")
			(hatch none 0.5)
			(connect_pads
				(clearance 0)
			)
			(min_thickness 0.25)
			(keepout
				(tracks allowed)
				(vias not_allowed)
				(pads allowed)
				(copperpour not_allowed)
				(footprints allowed)
			)
			(placement
				(enabled no)
				(sheetname "")
			)
			(fill
				(thermal_gap 0.5)
				(thermal_bridge_width 0.5)
				(island_removal_mode 0)
			)
			(polygon
				(pts
					(arc
						(start 112.880902 -60.500006)
						(mid 112.118902 -60.500006)
						(end 112.880902 -60.500006)
					)
				)
			)
		)
		(zone
			(layer "F.Cu")
			(hatch none 0.5)
			(connect_pads
				(clearance 0)
			)
			(min_thickness 0.25)
			(keepout
				(tracks allowed)
				(vias not_allowed)
				(pads allowed)
				(copperpour not_allowed)
				(footprints allowed)
			)
			(placement
				(enabled no)
				(sheetname "")
			)
			(fill
				(thermal_gap 0.5)
				(thermal_bridge_width 0.5)
				(island_removal_mode 0)
			)
			(polygon
				(pts
					(arc
						(start 112.880902 -59.500008)
						(mid 112.118902 -59.500008)
						(end 112.880902 -59.500008)
					)
				)
			)
		)
		(zone
			(layer "F.Cu")
			(hatch none 0.5)
			(connect_pads
				(clearance 0)
			)
			(min_thickness 0.25)
			(keepout
				(tracks allowed)
				(vias not_allowed)
				(pads allowed)
				(copperpour not_allowed)
				(footprints allowed)
			)
			(placement
				(enabled no)
				(sheetname "")
			)
			(fill
				(thermal_gap 0.5)
				(thermal_bridge_width 0.5)
				(island_removal_mode 0)
			)
			(polygon
				(pts
					(arc
						(start 112.880902 -58.50001)
						(mid 112.118902 -58.50001)
						(end 112.880902 -58.50001)
					)
				)
			)
		)
		(zone
			(layer "F.Cu")
			(hatch none 0.5)
			(connect_pads
				(clearance 0)
			)
			(min_thickness 0.25)
			(keepout
				(tracks allowed)
				(vias not_allowed)
				(pads allowed)
				(copperpour not_allowed)
				(footprints allowed)
			)
			(placement
				(enabled no)
				(sheetname "")
			)
			(fill
				(thermal_gap 0.5)
				(thermal_bridge_width 0.5)
				(island_removal_mode 0)
			)
			(polygon
				(pts
					(arc
						(start 112.880902 -57.500012)
						(mid 112.118902 -57.500012)
						(end 112.880902 -57.500012)
					)
				)
			)
		)
		(zone
			(layer "F.Cu")
			(hatch none 0.5)
			(connect_pads
				(clearance 0)
			)
			(min_thickness 0.25)
			(keepout
				(tracks allowed)
				(vias not_allowed)
				(pads allowed)
				(copperpour not_allowed)
				(footprints allowed)
			)
			(placement
				(enabled no)
				(sheetname "")
			)
			(fill
				(thermal_gap 0.5)
				(thermal_bridge_width 0.5)
				(island_removal_mode 0)
			)
			(polygon
				(pts
					(arc
						(start 112.880902 -56.500014)
						(mid 112.118902 -56.500014)
						(end 112.880902 -56.500014)
					)
				)
			)
		)
		(zone
			(layer "F.Cu")
			(hatch none 0.5)
			(connect_pads
				(clearance 0)
			)
			(min_thickness 0.25)
			(keepout
				(tracks allowed)
				(vias not_allowed)
				(pads allowed)
				(copperpour not_allowed)
				(footprints allowed)
			)
			(placement
				(enabled no)
				(sheetname "")
			)
			(fill
				(thermal_gap 0.5)
				(thermal_bridge_width 0.5)
				(island_removal_mode 0)
			)
			(polygon
				(pts
					(arc
						(start 112.880902 -55.500016)
						(mid 112.118902 -55.500016)
						(end 112.880902 -55.500016)
					)
				)
			)
		)
		(zone
			(layer "F.Cu")
			(hatch none 0.5)
			(connect_pads
				(clearance 0)
			)
			(min_thickness 0.25)
			(keepout
				(tracks allowed)
				(vias not_allowed)
				(pads allowed)
				(copperpour not_allowed)
				(footprints allowed)
			)
			(placement
				(enabled no)
				(sheetname "")
			)
			(fill
				(thermal_gap 0.5)
				(thermal_bridge_width 0.5)
				(island_removal_mode 0)
			)
			(polygon
				(pts
					(arc
						(start 112.880902 -54.500018)
						(mid 112.118902 -54.500018)
						(end 112.880902 -54.500018)
					)
				)
			)
		)
		(zone
			(layer "F.Cu")
			(hatch none 0.5)
			(connect_pads
				(clearance 0)
			)
			(min_thickness 0.25)
			(keepout
				(tracks allowed)
				(vias not_allowed)
				(pads allowed)
				(copperpour not_allowed)
				(footprints allowed)
			)
			(placement
				(enabled no)
				(sheetname "")
			)
			(fill
				(thermal_gap 0.5)
				(thermal_bridge_width 0.5)
				(island_removal_mode 0)
			)
			(polygon
				(pts
					(arc
						(start 112.880902 -53.50002)
						(mid 112.118902 -53.50002)
						(end 112.880902 -53.50002)
					)
				)
			)
		)
		(zone
			(layer "F.Cu")
			(hatch none 0.5)
			(connect_pads
				(clearance 0)
			)
			(min_thickness 0.25)
			(keepout
				(tracks allowed)
				(vias not_allowed)
				(pads allowed)
				(copperpour not_allowed)
				(footprints allowed)
			)
			(placement
				(enabled no)
				(sheetname "")
			)
			(fill
				(thermal_gap 0.5)
				(thermal_bridge_width 0.5)
				(island_removal_mode 0)
			)
			(polygon
				(pts
					(arc
						(start 112.880902 -52.500022)
						(mid 112.118902 -52.500022)
						(end 112.880902 -52.500022)
					)
				)
			)
		)
		(zone
			(layer "F.Cu")
			(hatch none 0.5)
			(connect_pads
				(clearance 0)
			)
			(min_thickness 0.25)
			(keepout
				(tracks allowed)
				(vias not_allowed)
				(pads allowed)
				(copperpour not_allowed)
				(footprints allowed)
			)
			(placement
				(enabled no)
				(sheetname "")
			)
			(fill
				(thermal_gap 0.5)
				(thermal_bridge_width 0.5)
				(island_removal_mode 0)
			)
			(polygon
				(pts
					(arc
						(start 112.880902 -51.500024)
						(mid 112.118902 -51.500024)
						(end 112.880902 -51.500024)
					)
				)
			)
		)
		(zone
			(layer "F.Cu")
			(hatch none 0.5)
			(connect_pads
				(clearance 0)
			)
			(min_thickness 0.25)
			(keepout
				(tracks allowed)
				(vias not_allowed)
				(pads allowed)
				(copperpour not_allowed)
				(footprints allowed)
			)
			(placement
				(enabled no)
				(sheetname "")
			)
			(fill
				(thermal_gap 0.5)
				(thermal_bridge_width 0.5)
				(island_removal_mode 0)
			)
			(polygon
				(pts
					(arc
						(start 113.8809 -82.500216)
						(mid 113.1189 -82.500216)
						(end 113.8809 -82.500216)
					)
				)
			)
		)
		(zone
			(layer "F.Cu")
			(hatch none 0.5)
			(connect_pads
				(clearance 0)
			)
			(min_thickness 0.25)
			(keepout
				(tracks allowed)
				(vias not_allowed)
				(pads allowed)
				(copperpour not_allowed)
				(footprints allowed)
			)
			(placement
				(enabled no)
				(sheetname "")
			)
			(fill
				(thermal_gap 0.5)
				(thermal_bridge_width 0.5)
				(island_removal_mode 0)
			)
			(polygon
				(pts
					(arc
						(start 113.8809 -81.500218)
						(mid 113.1189 -81.500218)
						(end 113.8809 -81.500218)
					)
				)
			)
		)
		(zone
			(layer "F.Cu")
			(hatch none 0.5)
			(connect_pads
				(clearance 0)
			)
			(min_thickness 0.25)
			(keepout
				(tracks allowed)
				(vias not_allowed)
				(pads allowed)
				(copperpour not_allowed)
				(footprints allowed)
			)
			(placement
				(enabled no)
				(sheetname "")
			)
			(fill
				(thermal_gap 0.5)
				(thermal_bridge_width 0.5)
				(island_removal_mode 0)
			)
			(polygon
				(pts
					(arc
						(start 113.8809 -80.50022)
						(mid 113.1189 -80.50022)
						(end 113.8809 -80.50022)
					)
				)
			)
		)
		(zone
			(layer "F.Cu")
			(hatch none 0.5)
			(connect_pads
				(clearance 0)
			)
			(min_thickness 0.25)
			(keepout
				(tracks allowed)
				(vias not_allowed)
				(pads allowed)
				(copperpour not_allowed)
				(footprints allowed)
			)
			(placement
				(enabled no)
				(sheetname "")
			)
			(fill
				(thermal_gap 0.5)
				(thermal_bridge_width 0.5)
				(island_removal_mode 0)
			)
			(polygon
				(pts
					(arc
						(start 113.8809 -79.500222)
						(mid 113.1189 -79.500222)
						(end 113.8809 -79.500222)
					)
				)
			)
		)
		(zone
			(layer "F.Cu")
			(hatch none 0.5)
			(connect_pads
				(clearance 0)
			)
			(min_thickness 0.25)
			(keepout
				(tracks allowed)
				(vias not_allowed)
				(pads allowed)
				(copperpour not_allowed)
				(footprints allowed)
			)
			(placement
				(enabled no)
				(sheetname "")
			)
			(fill
				(thermal_gap 0.5)
				(thermal_bridge_width 0.5)
				(island_removal_mode 0)
			)
			(polygon
				(pts
					(arc
						(start 113.8809 -78.500224)
						(mid 113.1189 -78.500224)
						(end 113.8809 -78.500224)
					)
				)
			)
		)
		(zone
			(layer "F.Cu")
			(hatch none 0.5)
			(connect_pads
				(clearance 0)
			)
			(min_thickness 0.25)
			(keepout
				(tracks allowed)
				(vias not_allowed)
				(pads allowed)
				(copperpour not_allowed)
				(footprints allowed)
			)
			(placement
				(enabled no)
				(sheetname "")
			)
			(fill
				(thermal_gap 0.5)
				(thermal_bridge_width 0.5)
				(island_removal_mode 0)
			)
			(polygon
				(pts
					(arc
						(start 113.8809 -77.500226)
						(mid 113.1189 -77.500226)
						(end 113.8809 -77.500226)
					)
				)
			)
		)
		(zone
			(layer "F.Cu")
			(hatch none 0.5)
			(connect_pads
				(clearance 0)
			)
			(min_thickness 0.25)
			(keepout
				(tracks allowed)
				(vias not_allowed)
				(pads allowed)
				(copperpour not_allowed)
				(footprints allowed)
			)
			(placement
				(enabled no)
				(sheetname "")
			)
			(fill
				(thermal_gap 0.5)
				(thermal_bridge_width 0.5)
				(island_removal_mode 0)
			)
			(polygon
				(pts
					(arc
						(start 113.8809 -76.500228)
						(mid 113.1189 -76.500228)
						(end 113.8809 -76.500228)
					)
				)
			)
		)
		(zone
			(layer "F.Cu")
			(hatch none 0.5)
			(connect_pads
				(clearance 0)
			)
			(min_thickness 0.25)
			(keepout
				(tracks allowed)
				(vias not_allowed)
				(pads allowed)
				(copperpour not_allowed)
				(footprints allowed)
			)
			(placement
				(enabled no)
				(sheetname "")
			)
			(fill
				(thermal_gap 0.5)
				(thermal_bridge_width 0.5)
				(island_removal_mode 0)
			)
			(polygon
				(pts
					(arc
						(start 113.8809 -75.50023)
						(mid 113.1189 -75.50023)
						(end 113.8809 -75.50023)
					)
				)
			)
		)
		(zone
			(layer "F.Cu")
			(hatch none 0.5)
			(connect_pads
				(clearance 0)
			)
			(min_thickness 0.25)
			(keepout
				(tracks allowed)
				(vias not_allowed)
				(pads allowed)
				(copperpour not_allowed)
				(footprints allowed)
			)
			(placement
				(enabled no)
				(sheetname "")
			)
			(fill
				(thermal_gap 0.5)
				(thermal_bridge_width 0.5)
				(island_removal_mode 0)
			)
			(polygon
				(pts
					(arc
						(start 113.8809 -74.500232)
						(mid 113.1189 -74.500232)
						(end 113.8809 -74.500232)
					)
				)
			)
		)
		(zone
			(layer "F.Cu")
			(hatch none 0.5)
			(connect_pads
				(clearance 0)
			)
			(min_thickness 0.25)
			(keepout
				(tracks allowed)
				(vias not_allowed)
				(pads allowed)
				(copperpour not_allowed)
				(footprints allowed)
			)
			(placement
				(enabled no)
				(sheetname "")
			)
			(fill
				(thermal_gap 0.5)
				(thermal_bridge_width 0.5)
				(island_removal_mode 0)
			)
			(polygon
				(pts
					(arc
						(start 113.8809 -73.500234)
						(mid 113.1189 -73.500234)
						(end 113.8809 -73.500234)
					)
				)
			)
		)
		(zone
			(layer "F.Cu")
			(hatch none 0.5)
			(connect_pads
				(clearance 0)
			)
			(min_thickness 0.25)
			(keepout
				(tracks allowed)
				(vias not_allowed)
				(pads allowed)
				(copperpour not_allowed)
				(footprints allowed)
			)
			(placement
				(enabled no)
				(sheetname "")
			)
			(fill
				(thermal_gap 0.5)
				(thermal_bridge_width 0.5)
				(island_removal_mode 0)
			)
			(polygon
				(pts
					(arc
						(start 113.8809 -72.500236)
						(mid 113.1189 -72.500236)
						(end 113.8809 -72.500236)
					)
				)
			)
		)
		(zone
			(layer "F.Cu")
			(hatch none 0.5)
			(connect_pads
				(clearance 0)
			)
			(min_thickness 0.25)
			(keepout
				(tracks allowed)
				(vias not_allowed)
				(pads allowed)
				(copperpour not_allowed)
				(footprints allowed)
			)
			(placement
				(enabled no)
				(sheetname "")
			)
			(fill
				(thermal_gap 0.5)
				(thermal_bridge_width 0.5)
				(island_removal_mode 0)
			)
			(polygon
				(pts
					(arc
						(start 113.8809 -71.500238)
						(mid 113.1189 -71.500238)
						(end 113.8809 -71.500238)
					)
				)
			)
		)
		(zone
			(layer "F.Cu")
			(hatch none 0.5)
			(connect_pads
				(clearance 0)
			)
			(min_thickness 0.25)
			(keepout
				(tracks allowed)
				(vias not_allowed)
				(pads allowed)
				(copperpour not_allowed)
				(footprints allowed)
			)
			(placement
				(enabled no)
				(sheetname "")
			)
			(fill
				(thermal_gap 0.5)
				(thermal_bridge_width 0.5)
				(island_removal_mode 0)
			)
			(polygon
				(pts
					(arc
						(start 113.8809 -70.50024)
						(mid 113.1189 -70.50024)
						(end 113.8809 -70.50024)
					)
				)
			)
		)
		(zone
			(layer "F.Cu")
			(hatch none 0.5)
			(connect_pads
				(clearance 0)
			)
			(min_thickness 0.25)
			(keepout
				(tracks allowed)
				(vias not_allowed)
				(pads allowed)
				(copperpour not_allowed)
				(footprints allowed)
			)
			(placement
				(enabled no)
				(sheetname "")
			)
			(fill
				(thermal_gap 0.5)
				(thermal_bridge_width 0.5)
				(island_removal_mode 0)
			)
			(polygon
				(pts
					(arc
						(start 113.8809 -69.500242)
						(mid 113.1189 -69.500242)
						(end 113.8809 -69.500242)
					)
				)
			)
		)
		(zone
			(layer "F.Cu")
			(hatch none 0.5)
			(connect_pads
				(clearance 0)
			)
			(min_thickness 0.25)
			(keepout
				(tracks allowed)
				(vias not_allowed)
				(pads allowed)
				(copperpour not_allowed)
				(footprints allowed)
			)
			(placement
				(enabled no)
				(sheetname "")
			)
			(fill
				(thermal_gap 0.5)
				(thermal_bridge_width 0.5)
				(island_removal_mode 0)
			)
			(polygon
				(pts
					(arc
						(start 113.8809 -68.500244)
						(mid 113.1189 -68.500244)
						(end 113.8809 -68.500244)
					)
				)
			)
		)
		(zone
			(layer "F.Cu")
			(hatch none 0.5)
			(connect_pads
				(clearance 0)
			)
			(min_thickness 0.25)
			(keepout
				(tracks allowed)
				(vias not_allowed)
				(pads allowed)
				(copperpour not_allowed)
				(footprints allowed)
			)
			(placement
				(enabled no)
				(sheetname "")
			)
			(fill
				(thermal_gap 0.5)
				(thermal_bridge_width 0.5)
				(island_removal_mode 0)
			)
			(polygon
				(pts
					(arc
						(start 113.8809 -67.500246)
						(mid 113.1189 -67.500246)
						(end 113.8809 -67.500246)
					)
				)
			)
		)
		(zone
			(layer "F.Cu")
			(hatch none 0.5)
			(connect_pads
				(clearance 0)
			)
			(min_thickness 0.25)
			(keepout
				(tracks allowed)
				(vias not_allowed)
				(pads allowed)
				(copperpour not_allowed)
				(footprints allowed)
			)
			(placement
				(enabled no)
				(sheetname "")
			)
			(fill
				(thermal_gap 0.5)
				(thermal_bridge_width 0.5)
				(island_removal_mode 0)
			)
			(polygon
				(pts
					(arc
						(start 113.8809 -66.499994)
						(mid 113.1189 -66.499994)
						(end 113.8809 -66.499994)
					)
				)
			)
		)
		(zone
			(layer "F.Cu")
			(hatch none 0.5)
			(connect_pads
				(clearance 0)
			)
			(min_thickness 0.25)
			(keepout
				(tracks allowed)
				(vias not_allowed)
				(pads allowed)
				(copperpour not_allowed)
				(footprints allowed)
			)
			(placement
				(enabled no)
				(sheetname "")
			)
			(fill
				(thermal_gap 0.5)
				(thermal_bridge_width 0.5)
				(island_removal_mode 0)
			)
			(polygon
				(pts
					(arc
						(start 113.8809 -65.499996)
						(mid 113.1189 -65.499996)
						(end 113.8809 -65.499996)
					)
				)
			)
		)
		(zone
			(layer "F.Cu")
			(hatch none 0.5)
			(connect_pads
				(clearance 0)
			)
			(min_thickness 0.25)
			(keepout
				(tracks allowed)
				(vias not_allowed)
				(pads allowed)
				(copperpour not_allowed)
				(footprints allowed)
			)
			(placement
				(enabled no)
				(sheetname "")
			)
			(fill
				(thermal_gap 0.5)
				(thermal_bridge_width 0.5)
				(island_removal_mode 0)
			)
			(polygon
				(pts
					(arc
						(start 113.8809 -64.499998)
						(mid 113.1189 -64.499998)
						(end 113.8809 -64.499998)
					)
				)
			)
		)
		(zone
			(layer "F.Cu")
			(hatch none 0.5)
			(connect_pads
				(clearance 0)
			)
			(min_thickness 0.25)
			(keepout
				(tracks allowed)
				(vias not_allowed)
				(pads allowed)
				(copperpour not_allowed)
				(footprints allowed)
			)
			(placement
				(enabled no)
				(sheetname "")
			)
			(fill
				(thermal_gap 0.5)
				(thermal_bridge_width 0.5)
				(island_removal_mode 0)
			)
			(polygon
				(pts
					(arc
						(start 113.8809 -63.5)
						(mid 113.1189 -63.5)
						(end 113.8809 -63.5)
					)
				)
			)
		)
		(zone
			(layer "F.Cu")
			(hatch none 0.5)
			(connect_pads
				(clearance 0)
			)
			(min_thickness 0.25)
			(keepout
				(tracks allowed)
				(vias not_allowed)
				(pads allowed)
				(copperpour not_allowed)
				(footprints allowed)
			)
			(placement
				(enabled no)
				(sheetname "")
			)
			(fill
				(thermal_gap 0.5)
				(thermal_bridge_width 0.5)
				(island_removal_mode 0)
			)
			(polygon
				(pts
					(arc
						(start 113.8809 -62.500002)
						(mid 113.1189 -62.500002)
						(end 113.8809 -62.500002)
					)
				)
			)
		)
		(zone
			(layer "F.Cu")
			(hatch none 0.5)
			(connect_pads
				(clearance 0)
			)
			(min_thickness 0.25)
			(keepout
				(tracks allowed)
				(vias not_allowed)
				(pads allowed)
				(copperpour not_allowed)
				(footprints allowed)
			)
			(placement
				(enabled no)
				(sheetname "")
			)
			(fill
				(thermal_gap 0.5)
				(thermal_bridge_width 0.5)
				(island_removal_mode 0)
			)
			(polygon
				(pts
					(arc
						(start 113.8809 -61.500004)
						(mid 113.1189 -61.500004)
						(end 113.8809 -61.500004)
					)
				)
			)
		)
		(zone
			(layer "F.Cu")
			(hatch none 0.5)
			(connect_pads
				(clearance 0)
			)
			(min_thickness 0.25)
			(keepout
				(tracks allowed)
				(vias not_allowed)
				(pads allowed)
				(copperpour not_allowed)
				(footprints allowed)
			)
			(placement
				(enabled no)
				(sheetname "")
			)
			(fill
				(thermal_gap 0.5)
				(thermal_bridge_width 0.5)
				(island_removal_mode 0)
			)
			(polygon
				(pts
					(arc
						(start 113.8809 -60.500006)
						(mid 113.1189 -60.500006)
						(end 113.8809 -60.500006)
					)
				)
			)
		)
		(zone
			(layer "F.Cu")
			(hatch none 0.5)
			(connect_pads
				(clearance 0)
			)
			(min_thickness 0.25)
			(keepout
				(tracks allowed)
				(vias not_allowed)
				(pads allowed)
				(copperpour not_allowed)
				(footprints allowed)
			)
			(placement
				(enabled no)
				(sheetname "")
			)
			(fill
				(thermal_gap 0.5)
				(thermal_bridge_width 0.5)
				(island_removal_mode 0)
			)
			(polygon
				(pts
					(arc
						(start 113.8809 -59.500008)
						(mid 113.1189 -59.500008)
						(end 113.8809 -59.500008)
					)
				)
			)
		)
		(zone
			(layer "F.Cu")
			(hatch none 0.5)
			(connect_pads
				(clearance 0)
			)
			(min_thickness 0.25)
			(keepout
				(tracks allowed)
				(vias not_allowed)
				(pads allowed)
				(copperpour not_allowed)
				(footprints allowed)
			)
			(placement
				(enabled no)
				(sheetname "")
			)
			(fill
				(thermal_gap 0.5)
				(thermal_bridge_width 0.5)
				(island_removal_mode 0)
			)
			(polygon
				(pts
					(arc
						(start 113.8809 -58.50001)
						(mid 113.1189 -58.50001)
						(end 113.8809 -58.50001)
					)
				)
			)
		)
		(zone
			(layer "F.Cu")
			(hatch none 0.5)
			(connect_pads
				(clearance 0)
			)
			(min_thickness 0.25)
			(keepout
				(tracks allowed)
				(vias not_allowed)
				(pads allowed)
				(copperpour not_allowed)
				(footprints allowed)
			)
			(placement
				(enabled no)
				(sheetname "")
			)
			(fill
				(thermal_gap 0.5)
				(thermal_bridge_width 0.5)
				(island_removal_mode 0)
			)
			(polygon
				(pts
					(arc
						(start 113.8809 -57.500012)
						(mid 113.1189 -57.500012)
						(end 113.8809 -57.500012)
					)
				)
			)
		)
		(zone
			(layer "F.Cu")
			(hatch none 0.5)
			(connect_pads
				(clearance 0)
			)
			(min_thickness 0.25)
			(keepout
				(tracks allowed)
				(vias not_allowed)
				(pads allowed)
				(copperpour not_allowed)
				(footprints allowed)
			)
			(placement
				(enabled no)
				(sheetname "")
			)
			(fill
				(thermal_gap 0.5)
				(thermal_bridge_width 0.5)
				(island_removal_mode 0)
			)
			(polygon
				(pts
					(arc
						(start 113.8809 -56.500014)
						(mid 113.1189 -56.500014)
						(end 113.8809 -56.500014)
					)
				)
			)
		)
		(zone
			(layer "F.Cu")
			(hatch none 0.5)
			(connect_pads
				(clearance 0)
			)
			(min_thickness 0.25)
			(keepout
				(tracks allowed)
				(vias not_allowed)
				(pads allowed)
				(copperpour not_allowed)
				(footprints allowed)
			)
			(placement
				(enabled no)
				(sheetname "")
			)
			(fill
				(thermal_gap 0.5)
				(thermal_bridge_width 0.5)
				(island_removal_mode 0)
			)
			(polygon
				(pts
					(arc
						(start 113.8809 -55.500016)
						(mid 113.1189 -55.500016)
						(end 113.8809 -55.500016)
					)
				)
			)
		)
		(zone
			(layer "F.Cu")
			(hatch none 0.5)
			(connect_pads
				(clearance 0)
			)
			(min_thickness 0.25)
			(keepout
				(tracks allowed)
				(vias not_allowed)
				(pads allowed)
				(copperpour not_allowed)
				(footprints allowed)
			)
			(placement
				(enabled no)
				(sheetname "")
			)
			(fill
				(thermal_gap 0.5)
				(thermal_bridge_width 0.5)
				(island_removal_mode 0)
			)
			(polygon
				(pts
					(arc
						(start 113.8809 -54.500018)
						(mid 113.1189 -54.500018)
						(end 113.8809 -54.500018)
					)
				)
			)
		)
		(zone
			(layer "F.Cu")
			(hatch none 0.5)
			(connect_pads
				(clearance 0)
			)
			(min_thickness 0.25)
			(keepout
				(tracks allowed)
				(vias not_allowed)
				(pads allowed)
				(copperpour not_allowed)
				(footprints allowed)
			)
			(placement
				(enabled no)
				(sheetname "")
			)
			(fill
				(thermal_gap 0.5)
				(thermal_bridge_width 0.5)
				(island_removal_mode 0)
			)
			(polygon
				(pts
					(arc
						(start 113.8809 -53.50002)
						(mid 113.1189 -53.50002)
						(end 113.8809 -53.50002)
					)
				)
			)
		)
		(zone
			(layer "F.Cu")
			(hatch none 0.5)
			(connect_pads
				(clearance 0)
			)
			(min_thickness 0.25)
			(keepout
				(tracks allowed)
				(vias not_allowed)
				(pads allowed)
				(copperpour not_allowed)
				(footprints allowed)
			)
			(placement
				(enabled no)
				(sheetname "")
			)
			(fill
				(thermal_gap 0.5)
				(thermal_bridge_width 0.5)
				(island_removal_mode 0)
			)
			(polygon
				(pts
					(arc
						(start 113.8809 -52.500022)
						(mid 113.1189 -52.500022)
						(end 113.8809 -52.500022)
					)
				)
			)
		)
		(zone
			(layer "F.Cu")
			(hatch none 0.5)
			(connect_pads
				(clearance 0)
			)
			(min_thickness 0.25)
			(keepout
				(tracks allowed)
				(vias not_allowed)
				(pads allowed)
				(copperpour not_allowed)
				(footprints allowed)
			)
			(placement
				(enabled no)
				(sheetname "")
			)
			(fill
				(thermal_gap 0.5)
				(thermal_bridge_width 0.5)
				(island_removal_mode 0)
			)
			(polygon
				(pts
					(arc
						(start 113.8809 -51.500024)
						(mid 113.1189 -51.500024)
						(end 113.8809 -51.500024)
					)
				)
			)
		)
		(zone
			(layer "F.Cu")
			(hatch none 0.5)
			(connect_pads
				(clearance 0)
			)
			(min_thickness 0.25)
			(keepout
				(tracks allowed)
				(vias not_allowed)
				(pads allowed)
				(copperpour not_allowed)
				(footprints allowed)
			)
			(placement
				(enabled no)
				(sheetname "")
			)
			(fill
				(thermal_gap 0.5)
				(thermal_bridge_width 0.5)
				(island_removal_mode 0)
			)
			(polygon
				(pts
					(arc
						(start 114.880898 -82.500216)
						(mid 114.118898 -82.500216)
						(end 114.880898 -82.500216)
					)
				)
			)
		)
		(zone
			(layer "F.Cu")
			(hatch none 0.5)
			(connect_pads
				(clearance 0)
			)
			(min_thickness 0.25)
			(keepout
				(tracks allowed)
				(vias not_allowed)
				(pads allowed)
				(copperpour not_allowed)
				(footprints allowed)
			)
			(placement
				(enabled no)
				(sheetname "")
			)
			(fill
				(thermal_gap 0.5)
				(thermal_bridge_width 0.5)
				(island_removal_mode 0)
			)
			(polygon
				(pts
					(arc
						(start 114.880898 -81.500218)
						(mid 114.118898 -81.500218)
						(end 114.880898 -81.500218)
					)
				)
			)
		)
		(zone
			(layer "F.Cu")
			(hatch none 0.5)
			(connect_pads
				(clearance 0)
			)
			(min_thickness 0.25)
			(keepout
				(tracks allowed)
				(vias not_allowed)
				(pads allowed)
				(copperpour not_allowed)
				(footprints allowed)
			)
			(placement
				(enabled no)
				(sheetname "")
			)
			(fill
				(thermal_gap 0.5)
				(thermal_bridge_width 0.5)
				(island_removal_mode 0)
			)
			(polygon
				(pts
					(arc
						(start 114.880898 -80.50022)
						(mid 114.118898 -80.50022)
						(end 114.880898 -80.50022)
					)
				)
			)
		)
		(zone
			(layer "F.Cu")
			(hatch none 0.5)
			(connect_pads
				(clearance 0)
			)
			(min_thickness 0.25)
			(keepout
				(tracks allowed)
				(vias not_allowed)
				(pads allowed)
				(copperpour not_allowed)
				(footprints allowed)
			)
			(placement
				(enabled no)
				(sheetname "")
			)
			(fill
				(thermal_gap 0.5)
				(thermal_bridge_width 0.5)
				(island_removal_mode 0)
			)
			(polygon
				(pts
					(arc
						(start 114.880898 -79.500222)
						(mid 114.118898 -79.500222)
						(end 114.880898 -79.500222)
					)
				)
			)
		)
		(zone
			(layer "F.Cu")
			(hatch none 0.5)
			(connect_pads
				(clearance 0)
			)
			(min_thickness 0.25)
			(keepout
				(tracks allowed)
				(vias not_allowed)
				(pads allowed)
				(copperpour not_allowed)
				(footprints allowed)
			)
			(placement
				(enabled no)
				(sheetname "")
			)
			(fill
				(thermal_gap 0.5)
				(thermal_bridge_width 0.5)
				(island_removal_mode 0)
			)
			(polygon
				(pts
					(arc
						(start 114.880898 -78.500224)
						(mid 114.118898 -78.500224)
						(end 114.880898 -78.500224)
					)
				)
			)
		)
		(zone
			(layer "F.Cu")
			(hatch none 0.5)
			(connect_pads
				(clearance 0)
			)
			(min_thickness 0.25)
			(keepout
				(tracks allowed)
				(vias not_allowed)
				(pads allowed)
				(copperpour not_allowed)
				(footprints allowed)
			)
			(placement
				(enabled no)
				(sheetname "")
			)
			(fill
				(thermal_gap 0.5)
				(thermal_bridge_width 0.5)
				(island_removal_mode 0)
			)
			(polygon
				(pts
					(arc
						(start 114.880898 -77.500226)
						(mid 114.118898 -77.500226)
						(end 114.880898 -77.500226)
					)
				)
			)
		)
		(zone
			(layer "F.Cu")
			(hatch none 0.5)
			(connect_pads
				(clearance 0)
			)
			(min_thickness 0.25)
			(keepout
				(tracks allowed)
				(vias not_allowed)
				(pads allowed)
				(copperpour not_allowed)
				(footprints allowed)
			)
			(placement
				(enabled no)
				(sheetname "")
			)
			(fill
				(thermal_gap 0.5)
				(thermal_bridge_width 0.5)
				(island_removal_mode 0)
			)
			(polygon
				(pts
					(arc
						(start 114.880898 -76.500228)
						(mid 114.118898 -76.500228)
						(end 114.880898 -76.500228)
					)
				)
			)
		)
		(zone
			(layer "F.Cu")
			(hatch none 0.5)
			(connect_pads
				(clearance 0)
			)
			(min_thickness 0.25)
			(keepout
				(tracks allowed)
				(vias not_allowed)
				(pads allowed)
				(copperpour not_allowed)
				(footprints allowed)
			)
			(placement
				(enabled no)
				(sheetname "")
			)
			(fill
				(thermal_gap 0.5)
				(thermal_bridge_width 0.5)
				(island_removal_mode 0)
			)
			(polygon
				(pts
					(arc
						(start 114.880898 -75.50023)
						(mid 114.118898 -75.50023)
						(end 114.880898 -75.50023)
					)
				)
			)
		)
		(zone
			(layer "F.Cu")
			(hatch none 0.5)
			(connect_pads
				(clearance 0)
			)
			(min_thickness 0.25)
			(keepout
				(tracks allowed)
				(vias not_allowed)
				(pads allowed)
				(copperpour not_allowed)
				(footprints allowed)
			)
			(placement
				(enabled no)
				(sheetname "")
			)
			(fill
				(thermal_gap 0.5)
				(thermal_bridge_width 0.5)
				(island_removal_mode 0)
			)
			(polygon
				(pts
					(arc
						(start 114.880898 -74.500232)
						(mid 114.118898 -74.500232)
						(end 114.880898 -74.500232)
					)
				)
			)
		)
		(zone
			(layer "F.Cu")
			(hatch none 0.5)
			(connect_pads
				(clearance 0)
			)
			(min_thickness 0.25)
			(keepout
				(tracks allowed)
				(vias not_allowed)
				(pads allowed)
				(copperpour not_allowed)
				(footprints allowed)
			)
			(placement
				(enabled no)
				(sheetname "")
			)
			(fill
				(thermal_gap 0.5)
				(thermal_bridge_width 0.5)
				(island_removal_mode 0)
			)
			(polygon
				(pts
					(arc
						(start 114.880898 -73.500234)
						(mid 114.118898 -73.500234)
						(end 114.880898 -73.500234)
					)
				)
			)
		)
		(zone
			(layer "F.Cu")
			(hatch none 0.5)
			(connect_pads
				(clearance 0)
			)
			(min_thickness 0.25)
			(keepout
				(tracks allowed)
				(vias not_allowed)
				(pads allowed)
				(copperpour not_allowed)
				(footprints allowed)
			)
			(placement
				(enabled no)
				(sheetname "")
			)
			(fill
				(thermal_gap 0.5)
				(thermal_bridge_width 0.5)
				(island_removal_mode 0)
			)
			(polygon
				(pts
					(arc
						(start 114.880898 -72.500236)
						(mid 114.118898 -72.500236)
						(end 114.880898 -72.500236)
					)
				)
			)
		)
		(zone
			(layer "F.Cu")
			(hatch none 0.5)
			(connect_pads
				(clearance 0)
			)
			(min_thickness 0.25)
			(keepout
				(tracks allowed)
				(vias not_allowed)
				(pads allowed)
				(copperpour not_allowed)
				(footprints allowed)
			)
			(placement
				(enabled no)
				(sheetname "")
			)
			(fill
				(thermal_gap 0.5)
				(thermal_bridge_width 0.5)
				(island_removal_mode 0)
			)
			(polygon
				(pts
					(arc
						(start 114.880898 -71.500238)
						(mid 114.118898 -71.500238)
						(end 114.880898 -71.500238)
					)
				)
			)
		)
		(zone
			(layer "F.Cu")
			(hatch none 0.5)
			(connect_pads
				(clearance 0)
			)
			(min_thickness 0.25)
			(keepout
				(tracks allowed)
				(vias not_allowed)
				(pads allowed)
				(copperpour not_allowed)
				(footprints allowed)
			)
			(placement
				(enabled no)
				(sheetname "")
			)
			(fill
				(thermal_gap 0.5)
				(thermal_bridge_width 0.5)
				(island_removal_mode 0)
			)
			(polygon
				(pts
					(arc
						(start 114.880898 -70.50024)
						(mid 114.118898 -70.50024)
						(end 114.880898 -70.50024)
					)
				)
			)
		)
		(zone
			(layer "F.Cu")
			(hatch none 0.5)
			(connect_pads
				(clearance 0)
			)
			(min_thickness 0.25)
			(keepout
				(tracks allowed)
				(vias not_allowed)
				(pads allowed)
				(copperpour not_allowed)
				(footprints allowed)
			)
			(placement
				(enabled no)
				(sheetname "")
			)
			(fill
				(thermal_gap 0.5)
				(thermal_bridge_width 0.5)
				(island_removal_mode 0)
			)
			(polygon
				(pts
					(arc
						(start 114.880898 -69.500242)
						(mid 114.118898 -69.500242)
						(end 114.880898 -69.500242)
					)
				)
			)
		)
		(zone
			(layer "F.Cu")
			(hatch none 0.5)
			(connect_pads
				(clearance 0)
			)
			(min_thickness 0.25)
			(keepout
				(tracks allowed)
				(vias not_allowed)
				(pads allowed)
				(copperpour not_allowed)
				(footprints allowed)
			)
			(placement
				(enabled no)
				(sheetname "")
			)
			(fill
				(thermal_gap 0.5)
				(thermal_bridge_width 0.5)
				(island_removal_mode 0)
			)
			(polygon
				(pts
					(arc
						(start 114.880898 -68.500244)
						(mid 114.118898 -68.500244)
						(end 114.880898 -68.500244)
					)
				)
			)
		)
		(zone
			(layer "F.Cu")
			(hatch none 0.5)
			(connect_pads
				(clearance 0)
			)
			(min_thickness 0.25)
			(keepout
				(tracks allowed)
				(vias not_allowed)
				(pads allowed)
				(copperpour not_allowed)
				(footprints allowed)
			)
			(placement
				(enabled no)
				(sheetname "")
			)
			(fill
				(thermal_gap 0.5)
				(thermal_bridge_width 0.5)
				(island_removal_mode 0)
			)
			(polygon
				(pts
					(arc
						(start 114.880898 -67.500246)
						(mid 114.118898 -67.500246)
						(end 114.880898 -67.500246)
					)
				)
			)
		)
		(zone
			(layer "F.Cu")
			(hatch none 0.5)
			(connect_pads
				(clearance 0)
			)
			(min_thickness 0.25)
			(keepout
				(tracks allowed)
				(vias not_allowed)
				(pads allowed)
				(copperpour not_allowed)
				(footprints allowed)
			)
			(placement
				(enabled no)
				(sheetname "")
			)
			(fill
				(thermal_gap 0.5)
				(thermal_bridge_width 0.5)
				(island_removal_mode 0)
			)
			(polygon
				(pts
					(arc
						(start 114.880898 -66.499994)
						(mid 114.118898 -66.499994)
						(end 114.880898 -66.499994)
					)
				)
			)
		)
		(zone
			(layer "F.Cu")
			(hatch none 0.5)
			(connect_pads
				(clearance 0)
			)
			(min_thickness 0.25)
			(keepout
				(tracks allowed)
				(vias not_allowed)
				(pads allowed)
				(copperpour not_allowed)
				(footprints allowed)
			)
			(placement
				(enabled no)
				(sheetname "")
			)
			(fill
				(thermal_gap 0.5)
				(thermal_bridge_width 0.5)
				(island_removal_mode 0)
			)
			(polygon
				(pts
					(arc
						(start 114.880898 -65.499996)
						(mid 114.118898 -65.499996)
						(end 114.880898 -65.499996)
					)
				)
			)
		)
		(zone
			(layer "F.Cu")
			(hatch none 0.5)
			(connect_pads
				(clearance 0)
			)
			(min_thickness 0.25)
			(keepout
				(tracks allowed)
				(vias not_allowed)
				(pads allowed)
				(copperpour not_allowed)
				(footprints allowed)
			)
			(placement
				(enabled no)
				(sheetname "")
			)
			(fill
				(thermal_gap 0.5)
				(thermal_bridge_width 0.5)
				(island_removal_mode 0)
			)
			(polygon
				(pts
					(arc
						(start 114.880898 -64.499998)
						(mid 114.118898 -64.499998)
						(end 114.880898 -64.499998)
					)
				)
			)
		)
		(zone
			(layer "F.Cu")
			(hatch none 0.5)
			(connect_pads
				(clearance 0)
			)
			(min_thickness 0.25)
			(keepout
				(tracks allowed)
				(vias not_allowed)
				(pads allowed)
				(copperpour not_allowed)
				(footprints allowed)
			)
			(placement
				(enabled no)
				(sheetname "")
			)
			(fill
				(thermal_gap 0.5)
				(thermal_bridge_width 0.5)
				(island_removal_mode 0)
			)
			(polygon
				(pts
					(arc
						(start 114.880898 -63.5)
						(mid 114.118898 -63.5)
						(end 114.880898 -63.5)
					)
				)
			)
		)
		(zone
			(layer "F.Cu")
			(hatch none 0.5)
			(connect_pads
				(clearance 0)
			)
			(min_thickness 0.25)
			(keepout
				(tracks allowed)
				(vias not_allowed)
				(pads allowed)
				(copperpour not_allowed)
				(footprints allowed)
			)
			(placement
				(enabled no)
				(sheetname "")
			)
			(fill
				(thermal_gap 0.5)
				(thermal_bridge_width 0.5)
				(island_removal_mode 0)
			)
			(polygon
				(pts
					(arc
						(start 114.880898 -62.500002)
						(mid 114.118898 -62.500002)
						(end 114.880898 -62.500002)
					)
				)
			)
		)
		(zone
			(layer "F.Cu")
			(hatch none 0.5)
			(connect_pads
				(clearance 0)
			)
			(min_thickness 0.25)
			(keepout
				(tracks allowed)
				(vias not_allowed)
				(pads allowed)
				(copperpour not_allowed)
				(footprints allowed)
			)
			(placement
				(enabled no)
				(sheetname "")
			)
			(fill
				(thermal_gap 0.5)
				(thermal_bridge_width 0.5)
				(island_removal_mode 0)
			)
			(polygon
				(pts
					(arc
						(start 114.880898 -61.500004)
						(mid 114.118898 -61.500004)
						(end 114.880898 -61.500004)
					)
				)
			)
		)
		(zone
			(layer "F.Cu")
			(hatch none 0.5)
			(connect_pads
				(clearance 0)
			)
			(min_thickness 0.25)
			(keepout
				(tracks allowed)
				(vias not_allowed)
				(pads allowed)
				(copperpour not_allowed)
				(footprints allowed)
			)
			(placement
				(enabled no)
				(sheetname "")
			)
			(fill
				(thermal_gap 0.5)
				(thermal_bridge_width 0.5)
				(island_removal_mode 0)
			)
			(polygon
				(pts
					(arc
						(start 114.880898 -60.500006)
						(mid 114.118898 -60.500006)
						(end 114.880898 -60.500006)
					)
				)
			)
		)
		(zone
			(layer "F.Cu")
			(hatch none 0.5)
			(connect_pads
				(clearance 0)
			)
			(min_thickness 0.25)
			(keepout
				(tracks allowed)
				(vias not_allowed)
				(pads allowed)
				(copperpour not_allowed)
				(footprints allowed)
			)
			(placement
				(enabled no)
				(sheetname "")
			)
			(fill
				(thermal_gap 0.5)
				(thermal_bridge_width 0.5)
				(island_removal_mode 0)
			)
			(polygon
				(pts
					(arc
						(start 114.880898 -59.500008)
						(mid 114.118898 -59.500008)
						(end 114.880898 -59.500008)
					)
				)
			)
		)
		(zone
			(layer "F.Cu")
			(hatch none 0.5)
			(connect_pads
				(clearance 0)
			)
			(min_thickness 0.25)
			(keepout
				(tracks allowed)
				(vias not_allowed)
				(pads allowed)
				(copperpour not_allowed)
				(footprints allowed)
			)
			(placement
				(enabled no)
				(sheetname "")
			)
			(fill
				(thermal_gap 0.5)
				(thermal_bridge_width 0.5)
				(island_removal_mode 0)
			)
			(polygon
				(pts
					(arc
						(start 114.880898 -58.50001)
						(mid 114.118898 -58.50001)
						(end 114.880898 -58.50001)
					)
				)
			)
		)
		(zone
			(layer "F.Cu")
			(hatch none 0.5)
			(connect_pads
				(clearance 0)
			)
			(min_thickness 0.25)
			(keepout
				(tracks allowed)
				(vias not_allowed)
				(pads allowed)
				(copperpour not_allowed)
				(footprints allowed)
			)
			(placement
				(enabled no)
				(sheetname "")
			)
			(fill
				(thermal_gap 0.5)
				(thermal_bridge_width 0.5)
				(island_removal_mode 0)
			)
			(polygon
				(pts
					(arc
						(start 114.880898 -57.500012)
						(mid 114.118898 -57.500012)
						(end 114.880898 -57.500012)
					)
				)
			)
		)
		(zone
			(layer "F.Cu")
			(hatch none 0.5)
			(connect_pads
				(clearance 0)
			)
			(min_thickness 0.25)
			(keepout
				(tracks allowed)
				(vias not_allowed)
				(pads allowed)
				(copperpour not_allowed)
				(footprints allowed)
			)
			(placement
				(enabled no)
				(sheetname "")
			)
			(fill
				(thermal_gap 0.5)
				(thermal_bridge_width 0.5)
				(island_removal_mode 0)
			)
			(polygon
				(pts
					(arc
						(start 114.880898 -56.500014)
						(mid 114.118898 -56.500014)
						(end 114.880898 -56.500014)
					)
				)
			)
		)
		(zone
			(layer "F.Cu")
			(hatch none 0.5)
			(connect_pads
				(clearance 0)
			)
			(min_thickness 0.25)
			(keepout
				(tracks allowed)
				(vias not_allowed)
				(pads allowed)
				(copperpour not_allowed)
				(footprints allowed)
			)
			(placement
				(enabled no)
				(sheetname "")
			)
			(fill
				(thermal_gap 0.5)
				(thermal_bridge_width 0.5)
				(island_removal_mode 0)
			)
			(polygon
				(pts
					(arc
						(start 114.880898 -55.500016)
						(mid 114.118898 -55.500016)
						(end 114.880898 -55.500016)
					)
				)
			)
		)
		(zone
			(layer "F.Cu")
			(hatch none 0.5)
			(connect_pads
				(clearance 0)
			)
			(min_thickness 0.25)
			(keepout
				(tracks allowed)
				(vias not_allowed)
				(pads allowed)
				(copperpour not_allowed)
				(footprints allowed)
			)
			(placement
				(enabled no)
				(sheetname "")
			)
			(fill
				(thermal_gap 0.5)
				(thermal_bridge_width 0.5)
				(island_removal_mode 0)
			)
			(polygon
				(pts
					(arc
						(start 114.880898 -54.500018)
						(mid 114.118898 -54.500018)
						(end 114.880898 -54.500018)
					)
				)
			)
		)
		(zone
			(layer "F.Cu")
			(hatch none 0.5)
			(connect_pads
				(clearance 0)
			)
			(min_thickness 0.25)
			(keepout
				(tracks allowed)
				(vias not_allowed)
				(pads allowed)
				(copperpour not_allowed)
				(footprints allowed)
			)
			(placement
				(enabled no)
				(sheetname "")
			)
			(fill
				(thermal_gap 0.5)
				(thermal_bridge_width 0.5)
				(island_removal_mode 0)
			)
			(polygon
				(pts
					(arc
						(start 114.880898 -53.50002)
						(mid 114.118898 -53.50002)
						(end 114.880898 -53.50002)
					)
				)
			)
		)
		(zone
			(layer "F.Cu")
			(hatch none 0.5)
			(connect_pads
				(clearance 0)
			)
			(min_thickness 0.25)
			(keepout
				(tracks allowed)
				(vias not_allowed)
				(pads allowed)
				(copperpour not_allowed)
				(footprints allowed)
			)
			(placement
				(enabled no)
				(sheetname "")
			)
			(fill
				(thermal_gap 0.5)
				(thermal_bridge_width 0.5)
				(island_removal_mode 0)
			)
			(polygon
				(pts
					(arc
						(start 114.880898 -52.500022)
						(mid 114.118898 -52.500022)
						(end 114.880898 -52.500022)
					)
				)
			)
		)
		(zone
			(layer "F.Cu")
			(hatch none 0.5)
			(connect_pads
				(clearance 0)
			)
			(min_thickness 0.25)
			(keepout
				(tracks allowed)
				(vias not_allowed)
				(pads allowed)
				(copperpour not_allowed)
				(footprints allowed)
			)
			(placement
				(enabled no)
				(sheetname "")
			)
			(fill
				(thermal_gap 0.5)
				(thermal_bridge_width 0.5)
				(island_removal_mode 0)
			)
			(polygon
				(pts
					(arc
						(start 114.880898 -51.500024)
						(mid 114.118898 -51.500024)
						(end 114.880898 -51.500024)
					)
				)
			)
		)
		(zone
			(layer "F.Cu")
			(hatch none 0.5)
			(connect_pads
				(clearance 0)
			)
			(min_thickness 0.25)
			(keepout
				(tracks allowed)
				(vias not_allowed)
				(pads allowed)
				(copperpour not_allowed)
				(footprints allowed)
			)
			(placement
				(enabled no)
				(sheetname "")
			)
			(fill
				(thermal_gap 0.5)
				(thermal_bridge_width 0.5)
				(island_removal_mode 0)
			)
			(polygon
				(pts
					(arc
						(start 115.88115 -82.500216)
						(mid 115.11915 -82.500216)
						(end 115.88115 -82.500216)
					)
				)
			)
		)
		(zone
			(layer "F.Cu")
			(hatch none 0.5)
			(connect_pads
				(clearance 0)
			)
			(min_thickness 0.25)
			(keepout
				(tracks allowed)
				(vias not_allowed)
				(pads allowed)
				(copperpour not_allowed)
				(footprints allowed)
			)
			(placement
				(enabled no)
				(sheetname "")
			)
			(fill
				(thermal_gap 0.5)
				(thermal_bridge_width 0.5)
				(island_removal_mode 0)
			)
			(polygon
				(pts
					(arc
						(start 115.88115 -81.500218)
						(mid 115.11915 -81.500218)
						(end 115.88115 -81.500218)
					)
				)
			)
		)
		(zone
			(layer "F.Cu")
			(hatch none 0.5)
			(connect_pads
				(clearance 0)
			)
			(min_thickness 0.25)
			(keepout
				(tracks allowed)
				(vias not_allowed)
				(pads allowed)
				(copperpour not_allowed)
				(footprints allowed)
			)
			(placement
				(enabled no)
				(sheetname "")
			)
			(fill
				(thermal_gap 0.5)
				(thermal_bridge_width 0.5)
				(island_removal_mode 0)
			)
			(polygon
				(pts
					(arc
						(start 115.88115 -80.50022)
						(mid 115.11915 -80.50022)
						(end 115.88115 -80.50022)
					)
				)
			)
		)
		(zone
			(layer "F.Cu")
			(hatch none 0.5)
			(connect_pads
				(clearance 0)
			)
			(min_thickness 0.25)
			(keepout
				(tracks allowed)
				(vias not_allowed)
				(pads allowed)
				(copperpour not_allowed)
				(footprints allowed)
			)
			(placement
				(enabled no)
				(sheetname "")
			)
			(fill
				(thermal_gap 0.5)
				(thermal_bridge_width 0.5)
				(island_removal_mode 0)
			)
			(polygon
				(pts
					(arc
						(start 115.88115 -79.500222)
						(mid 115.11915 -79.500222)
						(end 115.88115 -79.500222)
					)
				)
			)
		)
		(zone
			(layer "F.Cu")
			(hatch none 0.5)
			(connect_pads
				(clearance 0)
			)
			(min_thickness 0.25)
			(keepout
				(tracks allowed)
				(vias not_allowed)
				(pads allowed)
				(copperpour not_allowed)
				(footprints allowed)
			)
			(placement
				(enabled no)
				(sheetname "")
			)
			(fill
				(thermal_gap 0.5)
				(thermal_bridge_width 0.5)
				(island_removal_mode 0)
			)
			(polygon
				(pts
					(arc
						(start 115.88115 -78.500224)
						(mid 115.11915 -78.500224)
						(end 115.88115 -78.500224)
					)
				)
			)
		)
		(zone
			(layer "F.Cu")
			(hatch none 0.5)
			(connect_pads
				(clearance 0)
			)
			(min_thickness 0.25)
			(keepout
				(tracks allowed)
				(vias not_allowed)
				(pads allowed)
				(copperpour not_allowed)
				(footprints allowed)
			)
			(placement
				(enabled no)
				(sheetname "")
			)
			(fill
				(thermal_gap 0.5)
				(thermal_bridge_width 0.5)
				(island_removal_mode 0)
			)
			(polygon
				(pts
					(arc
						(start 115.88115 -77.500226)
						(mid 115.11915 -77.500226)
						(end 115.88115 -77.500226)
					)
				)
			)
		)
		(zone
			(layer "F.Cu")
			(hatch none 0.5)
			(connect_pads
				(clearance 0)
			)
			(min_thickness 0.25)
			(keepout
				(tracks allowed)
				(vias not_allowed)
				(pads allowed)
				(copperpour not_allowed)
				(footprints allowed)
			)
			(placement
				(enabled no)
				(sheetname "")
			)
			(fill
				(thermal_gap 0.5)
				(thermal_bridge_width 0.5)
				(island_removal_mode 0)
			)
			(polygon
				(pts
					(arc
						(start 115.88115 -76.500228)
						(mid 115.11915 -76.500228)
						(end 115.88115 -76.500228)
					)
				)
			)
		)
		(zone
			(layer "F.Cu")
			(hatch none 0.5)
			(connect_pads
				(clearance 0)
			)
			(min_thickness 0.25)
			(keepout
				(tracks allowed)
				(vias not_allowed)
				(pads allowed)
				(copperpour not_allowed)
				(footprints allowed)
			)
			(placement
				(enabled no)
				(sheetname "")
			)
			(fill
				(thermal_gap 0.5)
				(thermal_bridge_width 0.5)
				(island_removal_mode 0)
			)
			(polygon
				(pts
					(arc
						(start 115.88115 -75.50023)
						(mid 115.11915 -75.50023)
						(end 115.88115 -75.50023)
					)
				)
			)
		)
		(zone
			(layer "F.Cu")
			(hatch none 0.5)
			(connect_pads
				(clearance 0)
			)
			(min_thickness 0.25)
			(keepout
				(tracks allowed)
				(vias not_allowed)
				(pads allowed)
				(copperpour not_allowed)
				(footprints allowed)
			)
			(placement
				(enabled no)
				(sheetname "")
			)
			(fill
				(thermal_gap 0.5)
				(thermal_bridge_width 0.5)
				(island_removal_mode 0)
			)
			(polygon
				(pts
					(arc
						(start 115.88115 -74.500232)
						(mid 115.11915 -74.500232)
						(end 115.88115 -74.500232)
					)
				)
			)
		)
		(zone
			(layer "F.Cu")
			(hatch none 0.5)
			(connect_pads
				(clearance 0)
			)
			(min_thickness 0.25)
			(keepout
				(tracks allowed)
				(vias not_allowed)
				(pads allowed)
				(copperpour not_allowed)
				(footprints allowed)
			)
			(placement
				(enabled no)
				(sheetname "")
			)
			(fill
				(thermal_gap 0.5)
				(thermal_bridge_width 0.5)
				(island_removal_mode 0)
			)
			(polygon
				(pts
					(arc
						(start 115.88115 -73.500234)
						(mid 115.11915 -73.500234)
						(end 115.88115 -73.500234)
					)
				)
			)
		)
		(zone
			(layer "F.Cu")
			(hatch none 0.5)
			(connect_pads
				(clearance 0)
			)
			(min_thickness 0.25)
			(keepout
				(tracks allowed)
				(vias not_allowed)
				(pads allowed)
				(copperpour not_allowed)
				(footprints allowed)
			)
			(placement
				(enabled no)
				(sheetname "")
			)
			(fill
				(thermal_gap 0.5)
				(thermal_bridge_width 0.5)
				(island_removal_mode 0)
			)
			(polygon
				(pts
					(arc
						(start 115.88115 -72.500236)
						(mid 115.11915 -72.500236)
						(end 115.88115 -72.500236)
					)
				)
			)
		)
		(zone
			(layer "F.Cu")
			(hatch none 0.5)
			(connect_pads
				(clearance 0)
			)
			(min_thickness 0.25)
			(keepout
				(tracks allowed)
				(vias not_allowed)
				(pads allowed)
				(copperpour not_allowed)
				(footprints allowed)
			)
			(placement
				(enabled no)
				(sheetname "")
			)
			(fill
				(thermal_gap 0.5)
				(thermal_bridge_width 0.5)
				(island_removal_mode 0)
			)
			(polygon
				(pts
					(arc
						(start 115.88115 -71.500238)
						(mid 115.11915 -71.500238)
						(end 115.88115 -71.500238)
					)
				)
			)
		)
		(zone
			(layer "F.Cu")
			(hatch none 0.5)
			(connect_pads
				(clearance 0)
			)
			(min_thickness 0.25)
			(keepout
				(tracks allowed)
				(vias not_allowed)
				(pads allowed)
				(copperpour not_allowed)
				(footprints allowed)
			)
			(placement
				(enabled no)
				(sheetname "")
			)
			(fill
				(thermal_gap 0.5)
				(thermal_bridge_width 0.5)
				(island_removal_mode 0)
			)
			(polygon
				(pts
					(arc
						(start 115.88115 -70.50024)
						(mid 115.11915 -70.50024)
						(end 115.88115 -70.50024)
					)
				)
			)
		)
		(zone
			(layer "F.Cu")
			(hatch none 0.5)
			(connect_pads
				(clearance 0)
			)
			(min_thickness 0.25)
			(keepout
				(tracks allowed)
				(vias not_allowed)
				(pads allowed)
				(copperpour not_allowed)
				(footprints allowed)
			)
			(placement
				(enabled no)
				(sheetname "")
			)
			(fill
				(thermal_gap 0.5)
				(thermal_bridge_width 0.5)
				(island_removal_mode 0)
			)
			(polygon
				(pts
					(arc
						(start 115.88115 -69.500242)
						(mid 115.11915 -69.500242)
						(end 115.88115 -69.500242)
					)
				)
			)
		)
		(zone
			(layer "F.Cu")
			(hatch none 0.5)
			(connect_pads
				(clearance 0)
			)
			(min_thickness 0.25)
			(keepout
				(tracks allowed)
				(vias not_allowed)
				(pads allowed)
				(copperpour not_allowed)
				(footprints allowed)
			)
			(placement
				(enabled no)
				(sheetname "")
			)
			(fill
				(thermal_gap 0.5)
				(thermal_bridge_width 0.5)
				(island_removal_mode 0)
			)
			(polygon
				(pts
					(arc
						(start 115.88115 -68.500244)
						(mid 115.11915 -68.500244)
						(end 115.88115 -68.500244)
					)
				)
			)
		)
		(zone
			(layer "F.Cu")
			(hatch none 0.5)
			(connect_pads
				(clearance 0)
			)
			(min_thickness 0.25)
			(keepout
				(tracks allowed)
				(vias not_allowed)
				(pads allowed)
				(copperpour not_allowed)
				(footprints allowed)
			)
			(placement
				(enabled no)
				(sheetname "")
			)
			(fill
				(thermal_gap 0.5)
				(thermal_bridge_width 0.5)
				(island_removal_mode 0)
			)
			(polygon
				(pts
					(arc
						(start 115.88115 -67.500246)
						(mid 115.11915 -67.500246)
						(end 115.88115 -67.500246)
					)
				)
			)
		)
		(zone
			(layer "F.Cu")
			(hatch none 0.5)
			(connect_pads
				(clearance 0)
			)
			(min_thickness 0.25)
			(keepout
				(tracks allowed)
				(vias not_allowed)
				(pads allowed)
				(copperpour not_allowed)
				(footprints allowed)
			)
			(placement
				(enabled no)
				(sheetname "")
			)
			(fill
				(thermal_gap 0.5)
				(thermal_bridge_width 0.5)
				(island_removal_mode 0)
			)
			(polygon
				(pts
					(arc
						(start 115.88115 -66.499994)
						(mid 115.11915 -66.499994)
						(end 115.88115 -66.499994)
					)
				)
			)
		)
		(zone
			(layer "F.Cu")
			(hatch none 0.5)
			(connect_pads
				(clearance 0)
			)
			(min_thickness 0.25)
			(keepout
				(tracks allowed)
				(vias not_allowed)
				(pads allowed)
				(copperpour not_allowed)
				(footprints allowed)
			)
			(placement
				(enabled no)
				(sheetname "")
			)
			(fill
				(thermal_gap 0.5)
				(thermal_bridge_width 0.5)
				(island_removal_mode 0)
			)
			(polygon
				(pts
					(arc
						(start 115.88115 -65.499996)
						(mid 115.11915 -65.499996)
						(end 115.88115 -65.499996)
					)
				)
			)
		)
		(zone
			(layer "F.Cu")
			(hatch none 0.5)
			(connect_pads
				(clearance 0)
			)
			(min_thickness 0.25)
			(keepout
				(tracks allowed)
				(vias not_allowed)
				(pads allowed)
				(copperpour not_allowed)
				(footprints allowed)
			)
			(placement
				(enabled no)
				(sheetname "")
			)
			(fill
				(thermal_gap 0.5)
				(thermal_bridge_width 0.5)
				(island_removal_mode 0)
			)
			(polygon
				(pts
					(arc
						(start 115.88115 -64.499998)
						(mid 115.11915 -64.499998)
						(end 115.88115 -64.499998)
					)
				)
			)
		)
		(zone
			(layer "F.Cu")
			(hatch none 0.5)
			(connect_pads
				(clearance 0)
			)
			(min_thickness 0.25)
			(keepout
				(tracks allowed)
				(vias not_allowed)
				(pads allowed)
				(copperpour not_allowed)
				(footprints allowed)
			)
			(placement
				(enabled no)
				(sheetname "")
			)
			(fill
				(thermal_gap 0.5)
				(thermal_bridge_width 0.5)
				(island_removal_mode 0)
			)
			(polygon
				(pts
					(arc
						(start 115.88115 -63.5)
						(mid 115.11915 -63.5)
						(end 115.88115 -63.5)
					)
				)
			)
		)
		(zone
			(layer "F.Cu")
			(hatch none 0.5)
			(connect_pads
				(clearance 0)
			)
			(min_thickness 0.25)
			(keepout
				(tracks allowed)
				(vias not_allowed)
				(pads allowed)
				(copperpour not_allowed)
				(footprints allowed)
			)
			(placement
				(enabled no)
				(sheetname "")
			)
			(fill
				(thermal_gap 0.5)
				(thermal_bridge_width 0.5)
				(island_removal_mode 0)
			)
			(polygon
				(pts
					(arc
						(start 115.88115 -62.500002)
						(mid 115.11915 -62.500002)
						(end 115.88115 -62.500002)
					)
				)
			)
		)
		(zone
			(layer "F.Cu")
			(hatch none 0.5)
			(connect_pads
				(clearance 0)
			)
			(min_thickness 0.25)
			(keepout
				(tracks allowed)
				(vias not_allowed)
				(pads allowed)
				(copperpour not_allowed)
				(footprints allowed)
			)
			(placement
				(enabled no)
				(sheetname "")
			)
			(fill
				(thermal_gap 0.5)
				(thermal_bridge_width 0.5)
				(island_removal_mode 0)
			)
			(polygon
				(pts
					(arc
						(start 115.88115 -61.500004)
						(mid 115.11915 -61.500004)
						(end 115.88115 -61.500004)
					)
				)
			)
		)
		(zone
			(layer "F.Cu")
			(hatch none 0.5)
			(connect_pads
				(clearance 0)
			)
			(min_thickness 0.25)
			(keepout
				(tracks allowed)
				(vias not_allowed)
				(pads allowed)
				(copperpour not_allowed)
				(footprints allowed)
			)
			(placement
				(enabled no)
				(sheetname "")
			)
			(fill
				(thermal_gap 0.5)
				(thermal_bridge_width 0.5)
				(island_removal_mode 0)
			)
			(polygon
				(pts
					(arc
						(start 115.88115 -60.500006)
						(mid 115.11915 -60.500006)
						(end 115.88115 -60.500006)
					)
				)
			)
		)
		(zone
			(layer "F.Cu")
			(hatch none 0.5)
			(connect_pads
				(clearance 0)
			)
			(min_thickness 0.25)
			(keepout
				(tracks allowed)
				(vias not_allowed)
				(pads allowed)
				(copperpour not_allowed)
				(footprints allowed)
			)
			(placement
				(enabled no)
				(sheetname "")
			)
			(fill
				(thermal_gap 0.5)
				(thermal_bridge_width 0.5)
				(island_removal_mode 0)
			)
			(polygon
				(pts
					(arc
						(start 115.88115 -59.500008)
						(mid 115.11915 -59.500008)
						(end 115.88115 -59.500008)
					)
				)
			)
		)
		(zone
			(layer "F.Cu")
			(hatch none 0.5)
			(connect_pads
				(clearance 0)
			)
			(min_thickness 0.25)
			(keepout
				(tracks allowed)
				(vias not_allowed)
				(pads allowed)
				(copperpour not_allowed)
				(footprints allowed)
			)
			(placement
				(enabled no)
				(sheetname "")
			)
			(fill
				(thermal_gap 0.5)
				(thermal_bridge_width 0.5)
				(island_removal_mode 0)
			)
			(polygon
				(pts
					(arc
						(start 115.88115 -58.50001)
						(mid 115.11915 -58.50001)
						(end 115.88115 -58.50001)
					)
				)
			)
		)
		(zone
			(layer "F.Cu")
			(hatch none 0.5)
			(connect_pads
				(clearance 0)
			)
			(min_thickness 0.25)
			(keepout
				(tracks allowed)
				(vias not_allowed)
				(pads allowed)
				(copperpour not_allowed)
				(footprints allowed)
			)
			(placement
				(enabled no)
				(sheetname "")
			)
			(fill
				(thermal_gap 0.5)
				(thermal_bridge_width 0.5)
				(island_removal_mode 0)
			)
			(polygon
				(pts
					(arc
						(start 115.88115 -57.500012)
						(mid 115.11915 -57.500012)
						(end 115.88115 -57.500012)
					)
				)
			)
		)
		(zone
			(layer "F.Cu")
			(hatch none 0.5)
			(connect_pads
				(clearance 0)
			)
			(min_thickness 0.25)
			(keepout
				(tracks allowed)
				(vias not_allowed)
				(pads allowed)
				(copperpour not_allowed)
				(footprints allowed)
			)
			(placement
				(enabled no)
				(sheetname "")
			)
			(fill
				(thermal_gap 0.5)
				(thermal_bridge_width 0.5)
				(island_removal_mode 0)
			)
			(polygon
				(pts
					(arc
						(start 115.88115 -56.500014)
						(mid 115.11915 -56.500014)
						(end 115.88115 -56.500014)
					)
				)
			)
		)
		(zone
			(layer "F.Cu")
			(hatch none 0.5)
			(connect_pads
				(clearance 0)
			)
			(min_thickness 0.25)
			(keepout
				(tracks allowed)
				(vias not_allowed)
				(pads allowed)
				(copperpour not_allowed)
				(footprints allowed)
			)
			(placement
				(enabled no)
				(sheetname "")
			)
			(fill
				(thermal_gap 0.5)
				(thermal_bridge_width 0.5)
				(island_removal_mode 0)
			)
			(polygon
				(pts
					(arc
						(start 115.88115 -55.500016)
						(mid 115.11915 -55.500016)
						(end 115.88115 -55.500016)
					)
				)
			)
		)
		(zone
			(layer "F.Cu")
			(hatch none 0.5)
			(connect_pads
				(clearance 0)
			)
			(min_thickness 0.25)
			(keepout
				(tracks allowed)
				(vias not_allowed)
				(pads allowed)
				(copperpour not_allowed)
				(footprints allowed)
			)
			(placement
				(enabled no)
				(sheetname "")
			)
			(fill
				(thermal_gap 0.5)
				(thermal_bridge_width 0.5)
				(island_removal_mode 0)
			)
			(polygon
				(pts
					(arc
						(start 115.88115 -54.500018)
						(mid 115.11915 -54.500018)
						(end 115.88115 -54.500018)
					)
				)
			)
		)
		(zone
			(layer "F.Cu")
			(hatch none 0.5)
			(connect_pads
				(clearance 0)
			)
			(min_thickness 0.25)
			(keepout
				(tracks allowed)
				(vias not_allowed)
				(pads allowed)
				(copperpour not_allowed)
				(footprints allowed)
			)
			(placement
				(enabled no)
				(sheetname "")
			)
			(fill
				(thermal_gap 0.5)
				(thermal_bridge_width 0.5)
				(island_removal_mode 0)
			)
			(polygon
				(pts
					(arc
						(start 115.88115 -53.50002)
						(mid 115.11915 -53.50002)
						(end 115.88115 -53.50002)
					)
				)
			)
		)
		(zone
			(layer "F.Cu")
			(hatch none 0.5)
			(connect_pads
				(clearance 0)
			)
			(min_thickness 0.25)
			(keepout
				(tracks allowed)
				(vias not_allowed)
				(pads allowed)
				(copperpour not_allowed)
				(footprints allowed)
			)
			(placement
				(enabled no)
				(sheetname "")
			)
			(fill
				(thermal_gap 0.5)
				(thermal_bridge_width 0.5)
				(island_removal_mode 0)
			)
			(polygon
				(pts
					(arc
						(start 115.88115 -52.500022)
						(mid 115.11915 -52.500022)
						(end 115.88115 -52.500022)
					)
				)
			)
		)
		(zone
			(layer "F.Cu")
			(hatch none 0.5)
			(connect_pads
				(clearance 0)
			)
			(min_thickness 0.25)
			(keepout
				(tracks allowed)
				(vias not_allowed)
				(pads allowed)
				(copperpour not_allowed)
				(footprints allowed)
			)
			(placement
				(enabled no)
				(sheetname "")
			)
			(fill
				(thermal_gap 0.5)
				(thermal_bridge_width 0.5)
				(island_removal_mode 0)
			)
			(polygon
				(pts
					(arc
						(start 115.88115 -51.500024)
						(mid 115.11915 -51.500024)
						(end 115.88115 -51.500024)
					)
				)
			)
		)
		(zone
			(layer "F.Cu")
			(hatch none 0.5)
			(connect_pads
				(clearance 0)
			)
			(min_thickness 0.25)
			(keepout
				(tracks allowed)
				(vias not_allowed)
				(pads allowed)
				(copperpour not_allowed)
				(footprints allowed)
			)
			(placement
				(enabled no)
				(sheetname "")
			)
			(fill
				(thermal_gap 0.5)
				(thermal_bridge_width 0.5)
				(island_removal_mode 0)
			)
			(polygon
				(pts
					(arc
						(start 116.881148 -82.500216)
						(mid 116.119148 -82.500216)
						(end 116.881148 -82.500216)
					)
				)
			)
		)
		(zone
			(layer "F.Cu")
			(hatch none 0.5)
			(connect_pads
				(clearance 0)
			)
			(min_thickness 0.25)
			(keepout
				(tracks allowed)
				(vias not_allowed)
				(pads allowed)
				(copperpour not_allowed)
				(footprints allowed)
			)
			(placement
				(enabled no)
				(sheetname "")
			)
			(fill
				(thermal_gap 0.5)
				(thermal_bridge_width 0.5)
				(island_removal_mode 0)
			)
			(polygon
				(pts
					(arc
						(start 116.881148 -81.500218)
						(mid 116.119148 -81.500218)
						(end 116.881148 -81.500218)
					)
				)
			)
		)
		(zone
			(layer "F.Cu")
			(hatch none 0.5)
			(connect_pads
				(clearance 0)
			)
			(min_thickness 0.25)
			(keepout
				(tracks allowed)
				(vias not_allowed)
				(pads allowed)
				(copperpour not_allowed)
				(footprints allowed)
			)
			(placement
				(enabled no)
				(sheetname "")
			)
			(fill
				(thermal_gap 0.5)
				(thermal_bridge_width 0.5)
				(island_removal_mode 0)
			)
			(polygon
				(pts
					(arc
						(start 116.881148 -80.50022)
						(mid 116.119148 -80.50022)
						(end 116.881148 -80.50022)
					)
				)
			)
		)
		(zone
			(layer "F.Cu")
			(hatch none 0.5)
			(connect_pads
				(clearance 0)
			)
			(min_thickness 0.25)
			(keepout
				(tracks allowed)
				(vias not_allowed)
				(pads allowed)
				(copperpour not_allowed)
				(footprints allowed)
			)
			(placement
				(enabled no)
				(sheetname "")
			)
			(fill
				(thermal_gap 0.5)
				(thermal_bridge_width 0.5)
				(island_removal_mode 0)
			)
			(polygon
				(pts
					(arc
						(start 116.881148 -79.500222)
						(mid 116.119148 -79.500222)
						(end 116.881148 -79.500222)
					)
				)
			)
		)
		(zone
			(layer "F.Cu")
			(hatch none 0.5)
			(connect_pads
				(clearance 0)
			)
			(min_thickness 0.25)
			(keepout
				(tracks allowed)
				(vias not_allowed)
				(pads allowed)
				(copperpour not_allowed)
				(footprints allowed)
			)
			(placement
				(enabled no)
				(sheetname "")
			)
			(fill
				(thermal_gap 0.5)
				(thermal_bridge_width 0.5)
				(island_removal_mode 0)
			)
			(polygon
				(pts
					(arc
						(start 116.881148 -78.500224)
						(mid 116.119148 -78.500224)
						(end 116.881148 -78.500224)
					)
				)
			)
		)
		(zone
			(layer "F.Cu")
			(hatch none 0.5)
			(connect_pads
				(clearance 0)
			)
			(min_thickness 0.25)
			(keepout
				(tracks allowed)
				(vias not_allowed)
				(pads allowed)
				(copperpour not_allowed)
				(footprints allowed)
			)
			(placement
				(enabled no)
				(sheetname "")
			)
			(fill
				(thermal_gap 0.5)
				(thermal_bridge_width 0.5)
				(island_removal_mode 0)
			)
			(polygon
				(pts
					(arc
						(start 116.881148 -77.500226)
						(mid 116.119148 -77.500226)
						(end 116.881148 -77.500226)
					)
				)
			)
		)
		(zone
			(layer "F.Cu")
			(hatch none 0.5)
			(connect_pads
				(clearance 0)
			)
			(min_thickness 0.25)
			(keepout
				(tracks allowed)
				(vias not_allowed)
				(pads allowed)
				(copperpour not_allowed)
				(footprints allowed)
			)
			(placement
				(enabled no)
				(sheetname "")
			)
			(fill
				(thermal_gap 0.5)
				(thermal_bridge_width 0.5)
				(island_removal_mode 0)
			)
			(polygon
				(pts
					(arc
						(start 116.881148 -76.500228)
						(mid 116.119148 -76.500228)
						(end 116.881148 -76.500228)
					)
				)
			)
		)
		(zone
			(layer "F.Cu")
			(hatch none 0.5)
			(connect_pads
				(clearance 0)
			)
			(min_thickness 0.25)
			(keepout
				(tracks allowed)
				(vias not_allowed)
				(pads allowed)
				(copperpour not_allowed)
				(footprints allowed)
			)
			(placement
				(enabled no)
				(sheetname "")
			)
			(fill
				(thermal_gap 0.5)
				(thermal_bridge_width 0.5)
				(island_removal_mode 0)
			)
			(polygon
				(pts
					(arc
						(start 116.881148 -75.50023)
						(mid 116.119148 -75.50023)
						(end 116.881148 -75.50023)
					)
				)
			)
		)
		(zone
			(layer "F.Cu")
			(hatch none 0.5)
			(connect_pads
				(clearance 0)
			)
			(min_thickness 0.25)
			(keepout
				(tracks allowed)
				(vias not_allowed)
				(pads allowed)
				(copperpour not_allowed)
				(footprints allowed)
			)
			(placement
				(enabled no)
				(sheetname "")
			)
			(fill
				(thermal_gap 0.5)
				(thermal_bridge_width 0.5)
				(island_removal_mode 0)
			)
			(polygon
				(pts
					(arc
						(start 116.881148 -74.500232)
						(mid 116.119148 -74.500232)
						(end 116.881148 -74.500232)
					)
				)
			)
		)
		(zone
			(layer "F.Cu")
			(hatch none 0.5)
			(connect_pads
				(clearance 0)
			)
			(min_thickness 0.25)
			(keepout
				(tracks allowed)
				(vias not_allowed)
				(pads allowed)
				(copperpour not_allowed)
				(footprints allowed)
			)
			(placement
				(enabled no)
				(sheetname "")
			)
			(fill
				(thermal_gap 0.5)
				(thermal_bridge_width 0.5)
				(island_removal_mode 0)
			)
			(polygon
				(pts
					(arc
						(start 116.881148 -73.500234)
						(mid 116.119148 -73.500234)
						(end 116.881148 -73.500234)
					)
				)
			)
		)
		(zone
			(layer "F.Cu")
			(hatch none 0.5)
			(connect_pads
				(clearance 0)
			)
			(min_thickness 0.25)
			(keepout
				(tracks allowed)
				(vias not_allowed)
				(pads allowed)
				(copperpour not_allowed)
				(footprints allowed)
			)
			(placement
				(enabled no)
				(sheetname "")
			)
			(fill
				(thermal_gap 0.5)
				(thermal_bridge_width 0.5)
				(island_removal_mode 0)
			)
			(polygon
				(pts
					(arc
						(start 116.881148 -72.500236)
						(mid 116.119148 -72.500236)
						(end 116.881148 -72.500236)
					)
				)
			)
		)
		(zone
			(layer "F.Cu")
			(hatch none 0.5)
			(connect_pads
				(clearance 0)
			)
			(min_thickness 0.25)
			(keepout
				(tracks allowed)
				(vias not_allowed)
				(pads allowed)
				(copperpour not_allowed)
				(footprints allowed)
			)
			(placement
				(enabled no)
				(sheetname "")
			)
			(fill
				(thermal_gap 0.5)
				(thermal_bridge_width 0.5)
				(island_removal_mode 0)
			)
			(polygon
				(pts
					(arc
						(start 116.881148 -71.500238)
						(mid 116.119148 -71.500238)
						(end 116.881148 -71.500238)
					)
				)
			)
		)
		(zone
			(layer "F.Cu")
			(hatch none 0.5)
			(connect_pads
				(clearance 0)
			)
			(min_thickness 0.25)
			(keepout
				(tracks allowed)
				(vias not_allowed)
				(pads allowed)
				(copperpour not_allowed)
				(footprints allowed)
			)
			(placement
				(enabled no)
				(sheetname "")
			)
			(fill
				(thermal_gap 0.5)
				(thermal_bridge_width 0.5)
				(island_removal_mode 0)
			)
			(polygon
				(pts
					(arc
						(start 116.881148 -70.50024)
						(mid 116.119148 -70.50024)
						(end 116.881148 -70.50024)
					)
				)
			)
		)
		(zone
			(layer "F.Cu")
			(hatch none 0.5)
			(connect_pads
				(clearance 0)
			)
			(min_thickness 0.25)
			(keepout
				(tracks allowed)
				(vias not_allowed)
				(pads allowed)
				(copperpour not_allowed)
				(footprints allowed)
			)
			(placement
				(enabled no)
				(sheetname "")
			)
			(fill
				(thermal_gap 0.5)
				(thermal_bridge_width 0.5)
				(island_removal_mode 0)
			)
			(polygon
				(pts
					(arc
						(start 116.881148 -69.500242)
						(mid 116.119148 -69.500242)
						(end 116.881148 -69.500242)
					)
				)
			)
		)
		(zone
			(layer "F.Cu")
			(hatch none 0.5)
			(connect_pads
				(clearance 0)
			)
			(min_thickness 0.25)
			(keepout
				(tracks allowed)
				(vias not_allowed)
				(pads allowed)
				(copperpour not_allowed)
				(footprints allowed)
			)
			(placement
				(enabled no)
				(sheetname "")
			)
			(fill
				(thermal_gap 0.5)
				(thermal_bridge_width 0.5)
				(island_removal_mode 0)
			)
			(polygon
				(pts
					(arc
						(start 116.881148 -68.500244)
						(mid 116.119148 -68.500244)
						(end 116.881148 -68.500244)
					)
				)
			)
		)
		(zone
			(layer "F.Cu")
			(hatch none 0.5)
			(connect_pads
				(clearance 0)
			)
			(min_thickness 0.25)
			(keepout
				(tracks allowed)
				(vias not_allowed)
				(pads allowed)
				(copperpour not_allowed)
				(footprints allowed)
			)
			(placement
				(enabled no)
				(sheetname "")
			)
			(fill
				(thermal_gap 0.5)
				(thermal_bridge_width 0.5)
				(island_removal_mode 0)
			)
			(polygon
				(pts
					(arc
						(start 116.881148 -67.500246)
						(mid 116.119148 -67.500246)
						(end 116.881148 -67.500246)
					)
				)
			)
		)
		(zone
			(layer "F.Cu")
			(hatch none 0.5)
			(connect_pads
				(clearance 0)
			)
			(min_thickness 0.25)
			(keepout
				(tracks allowed)
				(vias not_allowed)
				(pads allowed)
				(copperpour not_allowed)
				(footprints allowed)
			)
			(placement
				(enabled no)
				(sheetname "")
			)
			(fill
				(thermal_gap 0.5)
				(thermal_bridge_width 0.5)
				(island_removal_mode 0)
			)
			(polygon
				(pts
					(arc
						(start 116.881148 -66.499994)
						(mid 116.119148 -66.499994)
						(end 116.881148 -66.499994)
					)
				)
			)
		)
		(zone
			(layer "F.Cu")
			(hatch none 0.5)
			(connect_pads
				(clearance 0)
			)
			(min_thickness 0.25)
			(keepout
				(tracks allowed)
				(vias not_allowed)
				(pads allowed)
				(copperpour not_allowed)
				(footprints allowed)
			)
			(placement
				(enabled no)
				(sheetname "")
			)
			(fill
				(thermal_gap 0.5)
				(thermal_bridge_width 0.5)
				(island_removal_mode 0)
			)
			(polygon
				(pts
					(arc
						(start 116.881148 -65.499996)
						(mid 116.119148 -65.499996)
						(end 116.881148 -65.499996)
					)
				)
			)
		)
		(zone
			(layer "F.Cu")
			(hatch none 0.5)
			(connect_pads
				(clearance 0)
			)
			(min_thickness 0.25)
			(keepout
				(tracks allowed)
				(vias not_allowed)
				(pads allowed)
				(copperpour not_allowed)
				(footprints allowed)
			)
			(placement
				(enabled no)
				(sheetname "")
			)
			(fill
				(thermal_gap 0.5)
				(thermal_bridge_width 0.5)
				(island_removal_mode 0)
			)
			(polygon
				(pts
					(arc
						(start 116.881148 -64.499998)
						(mid 116.119148 -64.499998)
						(end 116.881148 -64.499998)
					)
				)
			)
		)
		(zone
			(layer "F.Cu")
			(hatch none 0.5)
			(connect_pads
				(clearance 0)
			)
			(min_thickness 0.25)
			(keepout
				(tracks allowed)
				(vias not_allowed)
				(pads allowed)
				(copperpour not_allowed)
				(footprints allowed)
			)
			(placement
				(enabled no)
				(sheetname "")
			)
			(fill
				(thermal_gap 0.5)
				(thermal_bridge_width 0.5)
				(island_removal_mode 0)
			)
			(polygon
				(pts
					(arc
						(start 116.881148 -63.5)
						(mid 116.119148 -63.5)
						(end 116.881148 -63.5)
					)
				)
			)
		)
		(zone
			(layer "F.Cu")
			(hatch none 0.5)
			(connect_pads
				(clearance 0)
			)
			(min_thickness 0.25)
			(keepout
				(tracks allowed)
				(vias not_allowed)
				(pads allowed)
				(copperpour not_allowed)
				(footprints allowed)
			)
			(placement
				(enabled no)
				(sheetname "")
			)
			(fill
				(thermal_gap 0.5)
				(thermal_bridge_width 0.5)
				(island_removal_mode 0)
			)
			(polygon
				(pts
					(arc
						(start 116.881148 -62.500002)
						(mid 116.119148 -62.500002)
						(end 116.881148 -62.500002)
					)
				)
			)
		)
		(zone
			(layer "F.Cu")
			(hatch none 0.5)
			(connect_pads
				(clearance 0)
			)
			(min_thickness 0.25)
			(keepout
				(tracks allowed)
				(vias not_allowed)
				(pads allowed)
				(copperpour not_allowed)
				(footprints allowed)
			)
			(placement
				(enabled no)
				(sheetname "")
			)
			(fill
				(thermal_gap 0.5)
				(thermal_bridge_width 0.5)
				(island_removal_mode 0)
			)
			(polygon
				(pts
					(arc
						(start 116.881148 -61.500004)
						(mid 116.119148 -61.500004)
						(end 116.881148 -61.500004)
					)
				)
			)
		)
		(zone
			(layer "F.Cu")
			(hatch none 0.5)
			(connect_pads
				(clearance 0)
			)
			(min_thickness 0.25)
			(keepout
				(tracks allowed)
				(vias not_allowed)
				(pads allowed)
				(copperpour not_allowed)
				(footprints allowed)
			)
			(placement
				(enabled no)
				(sheetname "")
			)
			(fill
				(thermal_gap 0.5)
				(thermal_bridge_width 0.5)
				(island_removal_mode 0)
			)
			(polygon
				(pts
					(arc
						(start 116.881148 -60.500006)
						(mid 116.119148 -60.500006)
						(end 116.881148 -60.500006)
					)
				)
			)
		)
		(zone
			(layer "F.Cu")
			(hatch none 0.5)
			(connect_pads
				(clearance 0)
			)
			(min_thickness 0.25)
			(keepout
				(tracks allowed)
				(vias not_allowed)
				(pads allowed)
				(copperpour not_allowed)
				(footprints allowed)
			)
			(placement
				(enabled no)
				(sheetname "")
			)
			(fill
				(thermal_gap 0.5)
				(thermal_bridge_width 0.5)
				(island_removal_mode 0)
			)
			(polygon
				(pts
					(arc
						(start 116.881148 -59.500008)
						(mid 116.119148 -59.500008)
						(end 116.881148 -59.500008)
					)
				)
			)
		)
		(zone
			(layer "F.Cu")
			(hatch none 0.5)
			(connect_pads
				(clearance 0)
			)
			(min_thickness 0.25)
			(keepout
				(tracks allowed)
				(vias not_allowed)
				(pads allowed)
				(copperpour not_allowed)
				(footprints allowed)
			)
			(placement
				(enabled no)
				(sheetname "")
			)
			(fill
				(thermal_gap 0.5)
				(thermal_bridge_width 0.5)
				(island_removal_mode 0)
			)
			(polygon
				(pts
					(arc
						(start 116.881148 -58.50001)
						(mid 116.119148 -58.50001)
						(end 116.881148 -58.50001)
					)
				)
			)
		)
		(zone
			(layer "F.Cu")
			(hatch none 0.5)
			(connect_pads
				(clearance 0)
			)
			(min_thickness 0.25)
			(keepout
				(tracks allowed)
				(vias not_allowed)
				(pads allowed)
				(copperpour not_allowed)
				(footprints allowed)
			)
			(placement
				(enabled no)
				(sheetname "")
			)
			(fill
				(thermal_gap 0.5)
				(thermal_bridge_width 0.5)
				(island_removal_mode 0)
			)
			(polygon
				(pts
					(arc
						(start 116.881148 -57.500012)
						(mid 116.119148 -57.500012)
						(end 116.881148 -57.500012)
					)
				)
			)
		)
		(zone
			(layer "F.Cu")
			(hatch none 0.5)
			(connect_pads
				(clearance 0)
			)
			(min_thickness 0.25)
			(keepout
				(tracks allowed)
				(vias not_allowed)
				(pads allowed)
				(copperpour not_allowed)
				(footprints allowed)
			)
			(placement
				(enabled no)
				(sheetname "")
			)
			(fill
				(thermal_gap 0.5)
				(thermal_bridge_width 0.5)
				(island_removal_mode 0)
			)
			(polygon
				(pts
					(arc
						(start 116.881148 -56.500014)
						(mid 116.119148 -56.500014)
						(end 116.881148 -56.500014)
					)
				)
			)
		)
		(zone
			(layer "F.Cu")
			(hatch none 0.5)
			(connect_pads
				(clearance 0)
			)
			(min_thickness 0.25)
			(keepout
				(tracks allowed)
				(vias not_allowed)
				(pads allowed)
				(copperpour not_allowed)
				(footprints allowed)
			)
			(placement
				(enabled no)
				(sheetname "")
			)
			(fill
				(thermal_gap 0.5)
				(thermal_bridge_width 0.5)
				(island_removal_mode 0)
			)
			(polygon
				(pts
					(arc
						(start 116.881148 -55.500016)
						(mid 116.119148 -55.500016)
						(end 116.881148 -55.500016)
					)
				)
			)
		)
		(zone
			(layer "F.Cu")
			(hatch none 0.5)
			(connect_pads
				(clearance 0)
			)
			(min_thickness 0.25)
			(keepout
				(tracks allowed)
				(vias not_allowed)
				(pads allowed)
				(copperpour not_allowed)
				(footprints allowed)
			)
			(placement
				(enabled no)
				(sheetname "")
			)
			(fill
				(thermal_gap 0.5)
				(thermal_bridge_width 0.5)
				(island_removal_mode 0)
			)
			(polygon
				(pts
					(arc
						(start 116.881148 -54.500018)
						(mid 116.119148 -54.500018)
						(end 116.881148 -54.500018)
					)
				)
			)
		)
		(zone
			(layer "F.Cu")
			(hatch none 0.5)
			(connect_pads
				(clearance 0)
			)
			(min_thickness 0.25)
			(keepout
				(tracks allowed)
				(vias not_allowed)
				(pads allowed)
				(copperpour not_allowed)
				(footprints allowed)
			)
			(placement
				(enabled no)
				(sheetname "")
			)
			(fill
				(thermal_gap 0.5)
				(thermal_bridge_width 0.5)
				(island_removal_mode 0)
			)
			(polygon
				(pts
					(arc
						(start 116.881148 -53.50002)
						(mid 116.119148 -53.50002)
						(end 116.881148 -53.50002)
					)
				)
			)
		)
		(zone
			(layer "F.Cu")
			(hatch none 0.5)
			(connect_pads
				(clearance 0)
			)
			(min_thickness 0.25)
			(keepout
				(tracks allowed)
				(vias not_allowed)
				(pads allowed)
				(copperpour not_allowed)
				(footprints allowed)
			)
			(placement
				(enabled no)
				(sheetname "")
			)
			(fill
				(thermal_gap 0.5)
				(thermal_bridge_width 0.5)
				(island_removal_mode 0)
			)
			(polygon
				(pts
					(arc
						(start 116.881148 -52.500022)
						(mid 116.119148 -52.500022)
						(end 116.881148 -52.500022)
					)
				)
			)
		)
		(zone
			(layer "F.Cu")
			(hatch none 0.5)
			(connect_pads
				(clearance 0)
			)
			(min_thickness 0.25)
			(keepout
				(tracks allowed)
				(vias not_allowed)
				(pads allowed)
				(copperpour not_allowed)
				(footprints allowed)
			)
			(placement
				(enabled no)
				(sheetname "")
			)
			(fill
				(thermal_gap 0.5)
				(thermal_bridge_width 0.5)
				(island_removal_mode 0)
			)
			(polygon
				(pts
					(arc
						(start 116.881148 -51.500024)
						(mid 116.119148 -51.500024)
						(end 116.881148 -51.500024)
					)
				)
			)
		)
		(zone
			(layer "F.Cu")
			(hatch none 0.5)
			(connect_pads
				(clearance 0)
			)
			(min_thickness 0.25)
			(keepout
				(tracks allowed)
				(vias not_allowed)
				(pads allowed)
				(copperpour not_allowed)
				(footprints allowed)
			)
			(placement
				(enabled no)
				(sheetname "")
			)
			(fill
				(thermal_gap 0.5)
				(thermal_bridge_width 0.5)
				(island_removal_mode 0)
			)
			(polygon
				(pts
					(arc
						(start 117.881146 -82.500216)
						(mid 117.119146 -82.500216)
						(end 117.881146 -82.500216)
					)
				)
			)
		)
		(zone
			(layer "F.Cu")
			(hatch none 0.5)
			(connect_pads
				(clearance 0)
			)
			(min_thickness 0.25)
			(keepout
				(tracks allowed)
				(vias not_allowed)
				(pads allowed)
				(copperpour not_allowed)
				(footprints allowed)
			)
			(placement
				(enabled no)
				(sheetname "")
			)
			(fill
				(thermal_gap 0.5)
				(thermal_bridge_width 0.5)
				(island_removal_mode 0)
			)
			(polygon
				(pts
					(arc
						(start 117.881146 -81.500218)
						(mid 117.119146 -81.500218)
						(end 117.881146 -81.500218)
					)
				)
			)
		)
		(zone
			(layer "F.Cu")
			(hatch none 0.5)
			(connect_pads
				(clearance 0)
			)
			(min_thickness 0.25)
			(keepout
				(tracks allowed)
				(vias not_allowed)
				(pads allowed)
				(copperpour not_allowed)
				(footprints allowed)
			)
			(placement
				(enabled no)
				(sheetname "")
			)
			(fill
				(thermal_gap 0.5)
				(thermal_bridge_width 0.5)
				(island_removal_mode 0)
			)
			(polygon
				(pts
					(arc
						(start 117.881146 -80.50022)
						(mid 117.119146 -80.50022)
						(end 117.881146 -80.50022)
					)
				)
			)
		)
		(zone
			(layer "F.Cu")
			(hatch none 0.5)
			(connect_pads
				(clearance 0)
			)
			(min_thickness 0.25)
			(keepout
				(tracks allowed)
				(vias not_allowed)
				(pads allowed)
				(copperpour not_allowed)
				(footprints allowed)
			)
			(placement
				(enabled no)
				(sheetname "")
			)
			(fill
				(thermal_gap 0.5)
				(thermal_bridge_width 0.5)
				(island_removal_mode 0)
			)
			(polygon
				(pts
					(arc
						(start 117.881146 -79.500222)
						(mid 117.119146 -79.500222)
						(end 117.881146 -79.500222)
					)
				)
			)
		)
		(zone
			(layer "F.Cu")
			(hatch none 0.5)
			(connect_pads
				(clearance 0)
			)
			(min_thickness 0.25)
			(keepout
				(tracks allowed)
				(vias not_allowed)
				(pads allowed)
				(copperpour not_allowed)
				(footprints allowed)
			)
			(placement
				(enabled no)
				(sheetname "")
			)
			(fill
				(thermal_gap 0.5)
				(thermal_bridge_width 0.5)
				(island_removal_mode 0)
			)
			(polygon
				(pts
					(arc
						(start 117.881146 -78.500224)
						(mid 117.119146 -78.500224)
						(end 117.881146 -78.500224)
					)
				)
			)
		)
		(zone
			(layer "F.Cu")
			(hatch none 0.5)
			(connect_pads
				(clearance 0)
			)
			(min_thickness 0.25)
			(keepout
				(tracks allowed)
				(vias not_allowed)
				(pads allowed)
				(copperpour not_allowed)
				(footprints allowed)
			)
			(placement
				(enabled no)
				(sheetname "")
			)
			(fill
				(thermal_gap 0.5)
				(thermal_bridge_width 0.5)
				(island_removal_mode 0)
			)
			(polygon
				(pts
					(arc
						(start 117.881146 -77.500226)
						(mid 117.119146 -77.500226)
						(end 117.881146 -77.500226)
					)
				)
			)
		)
		(zone
			(layer "F.Cu")
			(hatch none 0.5)
			(connect_pads
				(clearance 0)
			)
			(min_thickness 0.25)
			(keepout
				(tracks allowed)
				(vias not_allowed)
				(pads allowed)
				(copperpour not_allowed)
				(footprints allowed)
			)
			(placement
				(enabled no)
				(sheetname "")
			)
			(fill
				(thermal_gap 0.5)
				(thermal_bridge_width 0.5)
				(island_removal_mode 0)
			)
			(polygon
				(pts
					(arc
						(start 117.881146 -76.500228)
						(mid 117.119146 -76.500228)
						(end 117.881146 -76.500228)
					)
				)
			)
		)
		(zone
			(layer "F.Cu")
			(hatch none 0.5)
			(connect_pads
				(clearance 0)
			)
			(min_thickness 0.25)
			(keepout
				(tracks allowed)
				(vias not_allowed)
				(pads allowed)
				(copperpour not_allowed)
				(footprints allowed)
			)
			(placement
				(enabled no)
				(sheetname "")
			)
			(fill
				(thermal_gap 0.5)
				(thermal_bridge_width 0.5)
				(island_removal_mode 0)
			)
			(polygon
				(pts
					(arc
						(start 117.881146 -75.50023)
						(mid 117.119146 -75.50023)
						(end 117.881146 -75.50023)
					)
				)
			)
		)
		(zone
			(layer "F.Cu")
			(hatch none 0.5)
			(connect_pads
				(clearance 0)
			)
			(min_thickness 0.25)
			(keepout
				(tracks allowed)
				(vias not_allowed)
				(pads allowed)
				(copperpour not_allowed)
				(footprints allowed)
			)
			(placement
				(enabled no)
				(sheetname "")
			)
			(fill
				(thermal_gap 0.5)
				(thermal_bridge_width 0.5)
				(island_removal_mode 0)
			)
			(polygon
				(pts
					(arc
						(start 117.881146 -74.500232)
						(mid 117.119146 -74.500232)
						(end 117.881146 -74.500232)
					)
				)
			)
		)
		(zone
			(layer "F.Cu")
			(hatch none 0.5)
			(connect_pads
				(clearance 0)
			)
			(min_thickness 0.25)
			(keepout
				(tracks allowed)
				(vias not_allowed)
				(pads allowed)
				(copperpour not_allowed)
				(footprints allowed)
			)
			(placement
				(enabled no)
				(sheetname "")
			)
			(fill
				(thermal_gap 0.5)
				(thermal_bridge_width 0.5)
				(island_removal_mode 0)
			)
			(polygon
				(pts
					(arc
						(start 117.881146 -73.500234)
						(mid 117.119146 -73.500234)
						(end 117.881146 -73.500234)
					)
				)
			)
		)
		(zone
			(layer "F.Cu")
			(hatch none 0.5)
			(connect_pads
				(clearance 0)
			)
			(min_thickness 0.25)
			(keepout
				(tracks allowed)
				(vias not_allowed)
				(pads allowed)
				(copperpour not_allowed)
				(footprints allowed)
			)
			(placement
				(enabled no)
				(sheetname "")
			)
			(fill
				(thermal_gap 0.5)
				(thermal_bridge_width 0.5)
				(island_removal_mode 0)
			)
			(polygon
				(pts
					(arc
						(start 117.881146 -72.500236)
						(mid 117.119146 -72.500236)
						(end 117.881146 -72.500236)
					)
				)
			)
		)
		(zone
			(layer "F.Cu")
			(hatch none 0.5)
			(connect_pads
				(clearance 0)
			)
			(min_thickness 0.25)
			(keepout
				(tracks allowed)
				(vias not_allowed)
				(pads allowed)
				(copperpour not_allowed)
				(footprints allowed)
			)
			(placement
				(enabled no)
				(sheetname "")
			)
			(fill
				(thermal_gap 0.5)
				(thermal_bridge_width 0.5)
				(island_removal_mode 0)
			)
			(polygon
				(pts
					(arc
						(start 117.881146 -71.500238)
						(mid 117.119146 -71.500238)
						(end 117.881146 -71.500238)
					)
				)
			)
		)
		(zone
			(layer "F.Cu")
			(hatch none 0.5)
			(connect_pads
				(clearance 0)
			)
			(min_thickness 0.25)
			(keepout
				(tracks allowed)
				(vias not_allowed)
				(pads allowed)
				(copperpour not_allowed)
				(footprints allowed)
			)
			(placement
				(enabled no)
				(sheetname "")
			)
			(fill
				(thermal_gap 0.5)
				(thermal_bridge_width 0.5)
				(island_removal_mode 0)
			)
			(polygon
				(pts
					(arc
						(start 117.881146 -70.50024)
						(mid 117.119146 -70.50024)
						(end 117.881146 -70.50024)
					)
				)
			)
		)
		(zone
			(layer "F.Cu")
			(hatch none 0.5)
			(connect_pads
				(clearance 0)
			)
			(min_thickness 0.25)
			(keepout
				(tracks allowed)
				(vias not_allowed)
				(pads allowed)
				(copperpour not_allowed)
				(footprints allowed)
			)
			(placement
				(enabled no)
				(sheetname "")
			)
			(fill
				(thermal_gap 0.5)
				(thermal_bridge_width 0.5)
				(island_removal_mode 0)
			)
			(polygon
				(pts
					(arc
						(start 117.881146 -69.500242)
						(mid 117.119146 -69.500242)
						(end 117.881146 -69.500242)
					)
				)
			)
		)
		(zone
			(layer "F.Cu")
			(hatch none 0.5)
			(connect_pads
				(clearance 0)
			)
			(min_thickness 0.25)
			(keepout
				(tracks allowed)
				(vias not_allowed)
				(pads allowed)
				(copperpour not_allowed)
				(footprints allowed)
			)
			(placement
				(enabled no)
				(sheetname "")
			)
			(fill
				(thermal_gap 0.5)
				(thermal_bridge_width 0.5)
				(island_removal_mode 0)
			)
			(polygon
				(pts
					(arc
						(start 117.881146 -68.500244)
						(mid 117.119146 -68.500244)
						(end 117.881146 -68.500244)
					)
				)
			)
		)
		(zone
			(layer "F.Cu")
			(hatch none 0.5)
			(connect_pads
				(clearance 0)
			)
			(min_thickness 0.25)
			(keepout
				(tracks allowed)
				(vias not_allowed)
				(pads allowed)
				(copperpour not_allowed)
				(footprints allowed)
			)
			(placement
				(enabled no)
				(sheetname "")
			)
			(fill
				(thermal_gap 0.5)
				(thermal_bridge_width 0.5)
				(island_removal_mode 0)
			)
			(polygon
				(pts
					(arc
						(start 117.881146 -67.500246)
						(mid 117.119146 -67.500246)
						(end 117.881146 -67.500246)
					)
				)
			)
		)
		(zone
			(layer "F.Cu")
			(hatch none 0.5)
			(connect_pads
				(clearance 0)
			)
			(min_thickness 0.25)
			(keepout
				(tracks allowed)
				(vias not_allowed)
				(pads allowed)
				(copperpour not_allowed)
				(footprints allowed)
			)
			(placement
				(enabled no)
				(sheetname "")
			)
			(fill
				(thermal_gap 0.5)
				(thermal_bridge_width 0.5)
				(island_removal_mode 0)
			)
			(polygon
				(pts
					(arc
						(start 117.881146 -66.499994)
						(mid 117.119146 -66.499994)
						(end 117.881146 -66.499994)
					)
				)
			)
		)
		(zone
			(layer "F.Cu")
			(hatch none 0.5)
			(connect_pads
				(clearance 0)
			)
			(min_thickness 0.25)
			(keepout
				(tracks allowed)
				(vias not_allowed)
				(pads allowed)
				(copperpour not_allowed)
				(footprints allowed)
			)
			(placement
				(enabled no)
				(sheetname "")
			)
			(fill
				(thermal_gap 0.5)
				(thermal_bridge_width 0.5)
				(island_removal_mode 0)
			)
			(polygon
				(pts
					(arc
						(start 117.881146 -65.499996)
						(mid 117.119146 -65.499996)
						(end 117.881146 -65.499996)
					)
				)
			)
		)
		(zone
			(layer "F.Cu")
			(hatch none 0.5)
			(connect_pads
				(clearance 0)
			)
			(min_thickness 0.25)
			(keepout
				(tracks allowed)
				(vias not_allowed)
				(pads allowed)
				(copperpour not_allowed)
				(footprints allowed)
			)
			(placement
				(enabled no)
				(sheetname "")
			)
			(fill
				(thermal_gap 0.5)
				(thermal_bridge_width 0.5)
				(island_removal_mode 0)
			)
			(polygon
				(pts
					(arc
						(start 117.881146 -64.499998)
						(mid 117.119146 -64.499998)
						(end 117.881146 -64.499998)
					)
				)
			)
		)
		(zone
			(layer "F.Cu")
			(hatch none 0.5)
			(connect_pads
				(clearance 0)
			)
			(min_thickness 0.25)
			(keepout
				(tracks allowed)
				(vias not_allowed)
				(pads allowed)
				(copperpour not_allowed)
				(footprints allowed)
			)
			(placement
				(enabled no)
				(sheetname "")
			)
			(fill
				(thermal_gap 0.5)
				(thermal_bridge_width 0.5)
				(island_removal_mode 0)
			)
			(polygon
				(pts
					(arc
						(start 117.881146 -63.5)
						(mid 117.119146 -63.5)
						(end 117.881146 -63.5)
					)
				)
			)
		)
		(zone
			(layer "F.Cu")
			(hatch none 0.5)
			(connect_pads
				(clearance 0)
			)
			(min_thickness 0.25)
			(keepout
				(tracks allowed)
				(vias not_allowed)
				(pads allowed)
				(copperpour not_allowed)
				(footprints allowed)
			)
			(placement
				(enabled no)
				(sheetname "")
			)
			(fill
				(thermal_gap 0.5)
				(thermal_bridge_width 0.5)
				(island_removal_mode 0)
			)
			(polygon
				(pts
					(arc
						(start 117.881146 -62.500002)
						(mid 117.119146 -62.500002)
						(end 117.881146 -62.500002)
					)
				)
			)
		)
		(zone
			(layer "F.Cu")
			(hatch none 0.5)
			(connect_pads
				(clearance 0)
			)
			(min_thickness 0.25)
			(keepout
				(tracks allowed)
				(vias not_allowed)
				(pads allowed)
				(copperpour not_allowed)
				(footprints allowed)
			)
			(placement
				(enabled no)
				(sheetname "")
			)
			(fill
				(thermal_gap 0.5)
				(thermal_bridge_width 0.5)
				(island_removal_mode 0)
			)
			(polygon
				(pts
					(arc
						(start 117.881146 -61.500004)
						(mid 117.119146 -61.500004)
						(end 117.881146 -61.500004)
					)
				)
			)
		)
		(zone
			(layer "F.Cu")
			(hatch none 0.5)
			(connect_pads
				(clearance 0)
			)
			(min_thickness 0.25)
			(keepout
				(tracks allowed)
				(vias not_allowed)
				(pads allowed)
				(copperpour not_allowed)
				(footprints allowed)
			)
			(placement
				(enabled no)
				(sheetname "")
			)
			(fill
				(thermal_gap 0.5)
				(thermal_bridge_width 0.5)
				(island_removal_mode 0)
			)
			(polygon
				(pts
					(arc
						(start 117.881146 -60.500006)
						(mid 117.119146 -60.500006)
						(end 117.881146 -60.500006)
					)
				)
			)
		)
		(zone
			(layer "F.Cu")
			(hatch none 0.5)
			(connect_pads
				(clearance 0)
			)
			(min_thickness 0.25)
			(keepout
				(tracks allowed)
				(vias not_allowed)
				(pads allowed)
				(copperpour not_allowed)
				(footprints allowed)
			)
			(placement
				(enabled no)
				(sheetname "")
			)
			(fill
				(thermal_gap 0.5)
				(thermal_bridge_width 0.5)
				(island_removal_mode 0)
			)
			(polygon
				(pts
					(arc
						(start 117.881146 -59.500008)
						(mid 117.119146 -59.500008)
						(end 117.881146 -59.500008)
					)
				)
			)
		)
		(zone
			(layer "F.Cu")
			(hatch none 0.5)
			(connect_pads
				(clearance 0)
			)
			(min_thickness 0.25)
			(keepout
				(tracks allowed)
				(vias not_allowed)
				(pads allowed)
				(copperpour not_allowed)
				(footprints allowed)
			)
			(placement
				(enabled no)
				(sheetname "")
			)
			(fill
				(thermal_gap 0.5)
				(thermal_bridge_width 0.5)
				(island_removal_mode 0)
			)
			(polygon
				(pts
					(arc
						(start 117.881146 -58.50001)
						(mid 117.119146 -58.50001)
						(end 117.881146 -58.50001)
					)
				)
			)
		)
		(zone
			(layer "F.Cu")
			(hatch none 0.5)
			(connect_pads
				(clearance 0)
			)
			(min_thickness 0.25)
			(keepout
				(tracks allowed)
				(vias not_allowed)
				(pads allowed)
				(copperpour not_allowed)
				(footprints allowed)
			)
			(placement
				(enabled no)
				(sheetname "")
			)
			(fill
				(thermal_gap 0.5)
				(thermal_bridge_width 0.5)
				(island_removal_mode 0)
			)
			(polygon
				(pts
					(arc
						(start 117.881146 -57.500012)
						(mid 117.119146 -57.500012)
						(end 117.881146 -57.500012)
					)
				)
			)
		)
		(zone
			(layer "F.Cu")
			(hatch none 0.5)
			(connect_pads
				(clearance 0)
			)
			(min_thickness 0.25)
			(keepout
				(tracks allowed)
				(vias not_allowed)
				(pads allowed)
				(copperpour not_allowed)
				(footprints allowed)
			)
			(placement
				(enabled no)
				(sheetname "")
			)
			(fill
				(thermal_gap 0.5)
				(thermal_bridge_width 0.5)
				(island_removal_mode 0)
			)
			(polygon
				(pts
					(arc
						(start 117.881146 -56.500014)
						(mid 117.119146 -56.500014)
						(end 117.881146 -56.500014)
					)
				)
			)
		)
		(zone
			(layer "F.Cu")
			(hatch none 0.5)
			(connect_pads
				(clearance 0)
			)
			(min_thickness 0.25)
			(keepout
				(tracks allowed)
				(vias not_allowed)
				(pads allowed)
				(copperpour not_allowed)
				(footprints allowed)
			)
			(placement
				(enabled no)
				(sheetname "")
			)
			(fill
				(thermal_gap 0.5)
				(thermal_bridge_width 0.5)
				(island_removal_mode 0)
			)
			(polygon
				(pts
					(arc
						(start 117.881146 -55.500016)
						(mid 117.119146 -55.500016)
						(end 117.881146 -55.500016)
					)
				)
			)
		)
		(zone
			(layer "F.Cu")
			(hatch none 0.5)
			(connect_pads
				(clearance 0)
			)
			(min_thickness 0.25)
			(keepout
				(tracks allowed)
				(vias not_allowed)
				(pads allowed)
				(copperpour not_allowed)
				(footprints allowed)
			)
			(placement
				(enabled no)
				(sheetname "")
			)
			(fill
				(thermal_gap 0.5)
				(thermal_bridge_width 0.5)
				(island_removal_mode 0)
			)
			(polygon
				(pts
					(arc
						(start 117.881146 -54.500018)
						(mid 117.119146 -54.500018)
						(end 117.881146 -54.500018)
					)
				)
			)
		)
		(zone
			(layer "F.Cu")
			(hatch none 0.5)
			(connect_pads
				(clearance 0)
			)
			(min_thickness 0.25)
			(keepout
				(tracks allowed)
				(vias not_allowed)
				(pads allowed)
				(copperpour not_allowed)
				(footprints allowed)
			)
			(placement
				(enabled no)
				(sheetname "")
			)
			(fill
				(thermal_gap 0.5)
				(thermal_bridge_width 0.5)
				(island_removal_mode 0)
			)
			(polygon
				(pts
					(arc
						(start 117.881146 -53.50002)
						(mid 117.119146 -53.50002)
						(end 117.881146 -53.50002)
					)
				)
			)
		)
		(zone
			(layer "F.Cu")
			(hatch none 0.5)
			(connect_pads
				(clearance 0)
			)
			(min_thickness 0.25)
			(keepout
				(tracks allowed)
				(vias not_allowed)
				(pads allowed)
				(copperpour not_allowed)
				(footprints allowed)
			)
			(placement
				(enabled no)
				(sheetname "")
			)
			(fill
				(thermal_gap 0.5)
				(thermal_bridge_width 0.5)
				(island_removal_mode 0)
			)
			(polygon
				(pts
					(arc
						(start 117.881146 -52.500022)
						(mid 117.119146 -52.500022)
						(end 117.881146 -52.500022)
					)
				)
			)
		)
		(zone
			(layer "F.Cu")
			(hatch none 0.5)
			(connect_pads
				(clearance 0)
			)
			(min_thickness 0.25)
			(keepout
				(tracks allowed)
				(vias not_allowed)
				(pads allowed)
				(copperpour not_allowed)
				(footprints allowed)
			)
			(placement
				(enabled no)
				(sheetname "")
			)
			(fill
				(thermal_gap 0.5)
				(thermal_bridge_width 0.5)
				(island_removal_mode 0)
			)
			(polygon
				(pts
					(arc
						(start 117.881146 -51.500024)
						(mid 117.119146 -51.500024)
						(end 117.881146 -51.500024)
					)
				)
			)
		)
		(zone
			(layer "F.Cu")
			(hatch none 0.5)
			(connect_pads
				(clearance 0)
			)
			(min_thickness 0.25)
			(keepout
				(tracks allowed)
				(vias not_allowed)
				(pads allowed)
				(copperpour not_allowed)
				(footprints allowed)
			)
			(placement
				(enabled no)
				(sheetname "")
			)
			(fill
				(thermal_gap 0.5)
				(thermal_bridge_width 0.5)
				(island_removal_mode 0)
			)
			(polygon
				(pts
					(arc
						(start 118.881144 -82.500216)
						(mid 118.119144 -82.500216)
						(end 118.881144 -82.500216)
					)
				)
			)
		)
		(zone
			(layer "F.Cu")
			(hatch none 0.5)
			(connect_pads
				(clearance 0)
			)
			(min_thickness 0.25)
			(keepout
				(tracks allowed)
				(vias not_allowed)
				(pads allowed)
				(copperpour not_allowed)
				(footprints allowed)
			)
			(placement
				(enabled no)
				(sheetname "")
			)
			(fill
				(thermal_gap 0.5)
				(thermal_bridge_width 0.5)
				(island_removal_mode 0)
			)
			(polygon
				(pts
					(arc
						(start 118.881144 -81.500218)
						(mid 118.119144 -81.500218)
						(end 118.881144 -81.500218)
					)
				)
			)
		)
		(zone
			(layer "F.Cu")
			(hatch none 0.5)
			(connect_pads
				(clearance 0)
			)
			(min_thickness 0.25)
			(keepout
				(tracks allowed)
				(vias not_allowed)
				(pads allowed)
				(copperpour not_allowed)
				(footprints allowed)
			)
			(placement
				(enabled no)
				(sheetname "")
			)
			(fill
				(thermal_gap 0.5)
				(thermal_bridge_width 0.5)
				(island_removal_mode 0)
			)
			(polygon
				(pts
					(arc
						(start 118.881144 -80.50022)
						(mid 118.119144 -80.50022)
						(end 118.881144 -80.50022)
					)
				)
			)
		)
		(zone
			(layer "F.Cu")
			(hatch none 0.5)
			(connect_pads
				(clearance 0)
			)
			(min_thickness 0.25)
			(keepout
				(tracks allowed)
				(vias not_allowed)
				(pads allowed)
				(copperpour not_allowed)
				(footprints allowed)
			)
			(placement
				(enabled no)
				(sheetname "")
			)
			(fill
				(thermal_gap 0.5)
				(thermal_bridge_width 0.5)
				(island_removal_mode 0)
			)
			(polygon
				(pts
					(arc
						(start 118.881144 -79.500222)
						(mid 118.119144 -79.500222)
						(end 118.881144 -79.500222)
					)
				)
			)
		)
		(zone
			(layer "F.Cu")
			(hatch none 0.5)
			(connect_pads
				(clearance 0)
			)
			(min_thickness 0.25)
			(keepout
				(tracks allowed)
				(vias not_allowed)
				(pads allowed)
				(copperpour not_allowed)
				(footprints allowed)
			)
			(placement
				(enabled no)
				(sheetname "")
			)
			(fill
				(thermal_gap 0.5)
				(thermal_bridge_width 0.5)
				(island_removal_mode 0)
			)
			(polygon
				(pts
					(arc
						(start 118.881144 -78.500224)
						(mid 118.119144 -78.500224)
						(end 118.881144 -78.500224)
					)
				)
			)
		)
		(zone
			(layer "F.Cu")
			(hatch none 0.5)
			(connect_pads
				(clearance 0)
			)
			(min_thickness 0.25)
			(keepout
				(tracks allowed)
				(vias not_allowed)
				(pads allowed)
				(copperpour not_allowed)
				(footprints allowed)
			)
			(placement
				(enabled no)
				(sheetname "")
			)
			(fill
				(thermal_gap 0.5)
				(thermal_bridge_width 0.5)
				(island_removal_mode 0)
			)
			(polygon
				(pts
					(arc
						(start 118.881144 -77.500226)
						(mid 118.119144 -77.500226)
						(end 118.881144 -77.500226)
					)
				)
			)
		)
		(zone
			(layer "F.Cu")
			(hatch none 0.5)
			(connect_pads
				(clearance 0)
			)
			(min_thickness 0.25)
			(keepout
				(tracks allowed)
				(vias not_allowed)
				(pads allowed)
				(copperpour not_allowed)
				(footprints allowed)
			)
			(placement
				(enabled no)
				(sheetname "")
			)
			(fill
				(thermal_gap 0.5)
				(thermal_bridge_width 0.5)
				(island_removal_mode 0)
			)
			(polygon
				(pts
					(arc
						(start 118.881144 -76.500228)
						(mid 118.119144 -76.500228)
						(end 118.881144 -76.500228)
					)
				)
			)
		)
		(zone
			(layer "F.Cu")
			(hatch none 0.5)
			(connect_pads
				(clearance 0)
			)
			(min_thickness 0.25)
			(keepout
				(tracks allowed)
				(vias not_allowed)
				(pads allowed)
				(copperpour not_allowed)
				(footprints allowed)
			)
			(placement
				(enabled no)
				(sheetname "")
			)
			(fill
				(thermal_gap 0.5)
				(thermal_bridge_width 0.5)
				(island_removal_mode 0)
			)
			(polygon
				(pts
					(arc
						(start 118.881144 -75.50023)
						(mid 118.119144 -75.50023)
						(end 118.881144 -75.50023)
					)
				)
			)
		)
		(zone
			(layer "F.Cu")
			(hatch none 0.5)
			(connect_pads
				(clearance 0)
			)
			(min_thickness 0.25)
			(keepout
				(tracks allowed)
				(vias not_allowed)
				(pads allowed)
				(copperpour not_allowed)
				(footprints allowed)
			)
			(placement
				(enabled no)
				(sheetname "")
			)
			(fill
				(thermal_gap 0.5)
				(thermal_bridge_width 0.5)
				(island_removal_mode 0)
			)
			(polygon
				(pts
					(arc
						(start 118.881144 -74.500232)
						(mid 118.119144 -74.500232)
						(end 118.881144 -74.500232)
					)
				)
			)
		)
		(zone
			(layer "F.Cu")
			(hatch none 0.5)
			(connect_pads
				(clearance 0)
			)
			(min_thickness 0.25)
			(keepout
				(tracks allowed)
				(vias not_allowed)
				(pads allowed)
				(copperpour not_allowed)
				(footprints allowed)
			)
			(placement
				(enabled no)
				(sheetname "")
			)
			(fill
				(thermal_gap 0.5)
				(thermal_bridge_width 0.5)
				(island_removal_mode 0)
			)
			(polygon
				(pts
					(arc
						(start 118.881144 -73.500234)
						(mid 118.119144 -73.500234)
						(end 118.881144 -73.500234)
					)
				)
			)
		)
		(zone
			(layer "F.Cu")
			(hatch none 0.5)
			(connect_pads
				(clearance 0)
			)
			(min_thickness 0.25)
			(keepout
				(tracks allowed)
				(vias not_allowed)
				(pads allowed)
				(copperpour not_allowed)
				(footprints allowed)
			)
			(placement
				(enabled no)
				(sheetname "")
			)
			(fill
				(thermal_gap 0.5)
				(thermal_bridge_width 0.5)
				(island_removal_mode 0)
			)
			(polygon
				(pts
					(arc
						(start 118.881144 -72.500236)
						(mid 118.119144 -72.500236)
						(end 118.881144 -72.500236)
					)
				)
			)
		)
		(zone
			(layer "F.Cu")
			(hatch none 0.5)
			(connect_pads
				(clearance 0)
			)
			(min_thickness 0.25)
			(keepout
				(tracks allowed)
				(vias not_allowed)
				(pads allowed)
				(copperpour not_allowed)
				(footprints allowed)
			)
			(placement
				(enabled no)
				(sheetname "")
			)
			(fill
				(thermal_gap 0.5)
				(thermal_bridge_width 0.5)
				(island_removal_mode 0)
			)
			(polygon
				(pts
					(arc
						(start 118.881144 -71.500238)
						(mid 118.119144 -71.500238)
						(end 118.881144 -71.500238)
					)
				)
			)
		)
		(zone
			(layer "F.Cu")
			(hatch none 0.5)
			(connect_pads
				(clearance 0)
			)
			(min_thickness 0.25)
			(keepout
				(tracks allowed)
				(vias not_allowed)
				(pads allowed)
				(copperpour not_allowed)
				(footprints allowed)
			)
			(placement
				(enabled no)
				(sheetname "")
			)
			(fill
				(thermal_gap 0.5)
				(thermal_bridge_width 0.5)
				(island_removal_mode 0)
			)
			(polygon
				(pts
					(arc
						(start 118.881144 -70.50024)
						(mid 118.119144 -70.50024)
						(end 118.881144 -70.50024)
					)
				)
			)
		)
		(zone
			(layer "F.Cu")
			(hatch none 0.5)
			(connect_pads
				(clearance 0)
			)
			(min_thickness 0.25)
			(keepout
				(tracks allowed)
				(vias not_allowed)
				(pads allowed)
				(copperpour not_allowed)
				(footprints allowed)
			)
			(placement
				(enabled no)
				(sheetname "")
			)
			(fill
				(thermal_gap 0.5)
				(thermal_bridge_width 0.5)
				(island_removal_mode 0)
			)
			(polygon
				(pts
					(arc
						(start 118.881144 -69.500242)
						(mid 118.119144 -69.500242)
						(end 118.881144 -69.500242)
					)
				)
			)
		)
		(zone
			(layer "F.Cu")
			(hatch none 0.5)
			(connect_pads
				(clearance 0)
			)
			(min_thickness 0.25)
			(keepout
				(tracks allowed)
				(vias not_allowed)
				(pads allowed)
				(copperpour not_allowed)
				(footprints allowed)
			)
			(placement
				(enabled no)
				(sheetname "")
			)
			(fill
				(thermal_gap 0.5)
				(thermal_bridge_width 0.5)
				(island_removal_mode 0)
			)
			(polygon
				(pts
					(arc
						(start 118.881144 -68.500244)
						(mid 118.119144 -68.500244)
						(end 118.881144 -68.500244)
					)
				)
			)
		)
		(zone
			(layer "F.Cu")
			(hatch none 0.5)
			(connect_pads
				(clearance 0)
			)
			(min_thickness 0.25)
			(keepout
				(tracks allowed)
				(vias not_allowed)
				(pads allowed)
				(copperpour not_allowed)
				(footprints allowed)
			)
			(placement
				(enabled no)
				(sheetname "")
			)
			(fill
				(thermal_gap 0.5)
				(thermal_bridge_width 0.5)
				(island_removal_mode 0)
			)
			(polygon
				(pts
					(arc
						(start 118.881144 -67.500246)
						(mid 118.119144 -67.500246)
						(end 118.881144 -67.500246)
					)
				)
			)
		)
		(zone
			(layer "F.Cu")
			(hatch none 0.5)
			(connect_pads
				(clearance 0)
			)
			(min_thickness 0.25)
			(keepout
				(tracks allowed)
				(vias not_allowed)
				(pads allowed)
				(copperpour not_allowed)
				(footprints allowed)
			)
			(placement
				(enabled no)
				(sheetname "")
			)
			(fill
				(thermal_gap 0.5)
				(thermal_bridge_width 0.5)
				(island_removal_mode 0)
			)
			(polygon
				(pts
					(arc
						(start 118.881144 -66.499994)
						(mid 118.119144 -66.499994)
						(end 118.881144 -66.499994)
					)
				)
			)
		)
		(zone
			(layer "F.Cu")
			(hatch none 0.5)
			(connect_pads
				(clearance 0)
			)
			(min_thickness 0.25)
			(keepout
				(tracks allowed)
				(vias not_allowed)
				(pads allowed)
				(copperpour not_allowed)
				(footprints allowed)
			)
			(placement
				(enabled no)
				(sheetname "")
			)
			(fill
				(thermal_gap 0.5)
				(thermal_bridge_width 0.5)
				(island_removal_mode 0)
			)
			(polygon
				(pts
					(arc
						(start 118.881144 -65.499996)
						(mid 118.119144 -65.499996)
						(end 118.881144 -65.499996)
					)
				)
			)
		)
		(zone
			(layer "F.Cu")
			(hatch none 0.5)
			(connect_pads
				(clearance 0)
			)
			(min_thickness 0.25)
			(keepout
				(tracks allowed)
				(vias not_allowed)
				(pads allowed)
				(copperpour not_allowed)
				(footprints allowed)
			)
			(placement
				(enabled no)
				(sheetname "")
			)
			(fill
				(thermal_gap 0.5)
				(thermal_bridge_width 0.5)
				(island_removal_mode 0)
			)
			(polygon
				(pts
					(arc
						(start 118.881144 -64.499998)
						(mid 118.119144 -64.499998)
						(end 118.881144 -64.499998)
					)
				)
			)
		)
		(zone
			(layer "F.Cu")
			(hatch none 0.5)
			(connect_pads
				(clearance 0)
			)
			(min_thickness 0.25)
			(keepout
				(tracks allowed)
				(vias not_allowed)
				(pads allowed)
				(copperpour not_allowed)
				(footprints allowed)
			)
			(placement
				(enabled no)
				(sheetname "")
			)
			(fill
				(thermal_gap 0.5)
				(thermal_bridge_width 0.5)
				(island_removal_mode 0)
			)
			(polygon
				(pts
					(arc
						(start 118.881144 -63.5)
						(mid 118.119144 -63.5)
						(end 118.881144 -63.5)
					)
				)
			)
		)
		(zone
			(layer "F.Cu")
			(hatch none 0.5)
			(connect_pads
				(clearance 0)
			)
			(min_thickness 0.25)
			(keepout
				(tracks allowed)
				(vias not_allowed)
				(pads allowed)
				(copperpour not_allowed)
				(footprints allowed)
			)
			(placement
				(enabled no)
				(sheetname "")
			)
			(fill
				(thermal_gap 0.5)
				(thermal_bridge_width 0.5)
				(island_removal_mode 0)
			)
			(polygon
				(pts
					(arc
						(start 118.881144 -62.500002)
						(mid 118.119144 -62.500002)
						(end 118.881144 -62.500002)
					)
				)
			)
		)
		(zone
			(layer "F.Cu")
			(hatch none 0.5)
			(connect_pads
				(clearance 0)
			)
			(min_thickness 0.25)
			(keepout
				(tracks allowed)
				(vias not_allowed)
				(pads allowed)
				(copperpour not_allowed)
				(footprints allowed)
			)
			(placement
				(enabled no)
				(sheetname "")
			)
			(fill
				(thermal_gap 0.5)
				(thermal_bridge_width 0.5)
				(island_removal_mode 0)
			)
			(polygon
				(pts
					(arc
						(start 118.881144 -61.500004)
						(mid 118.119144 -61.500004)
						(end 118.881144 -61.500004)
					)
				)
			)
		)
		(zone
			(layer "F.Cu")
			(hatch none 0.5)
			(connect_pads
				(clearance 0)
			)
			(min_thickness 0.25)
			(keepout
				(tracks allowed)
				(vias not_allowed)
				(pads allowed)
				(copperpour not_allowed)
				(footprints allowed)
			)
			(placement
				(enabled no)
				(sheetname "")
			)
			(fill
				(thermal_gap 0.5)
				(thermal_bridge_width 0.5)
				(island_removal_mode 0)
			)
			(polygon
				(pts
					(arc
						(start 118.881144 -60.500006)
						(mid 118.119144 -60.500006)
						(end 118.881144 -60.500006)
					)
				)
			)
		)
		(zone
			(layer "F.Cu")
			(hatch none 0.5)
			(connect_pads
				(clearance 0)
			)
			(min_thickness 0.25)
			(keepout
				(tracks allowed)
				(vias not_allowed)
				(pads allowed)
				(copperpour not_allowed)
				(footprints allowed)
			)
			(placement
				(enabled no)
				(sheetname "")
			)
			(fill
				(thermal_gap 0.5)
				(thermal_bridge_width 0.5)
				(island_removal_mode 0)
			)
			(polygon
				(pts
					(arc
						(start 118.881144 -59.500008)
						(mid 118.119144 -59.500008)
						(end 118.881144 -59.500008)
					)
				)
			)
		)
		(zone
			(layer "F.Cu")
			(hatch none 0.5)
			(connect_pads
				(clearance 0)
			)
			(min_thickness 0.25)
			(keepout
				(tracks allowed)
				(vias not_allowed)
				(pads allowed)
				(copperpour not_allowed)
				(footprints allowed)
			)
			(placement
				(enabled no)
				(sheetname "")
			)
			(fill
				(thermal_gap 0.5)
				(thermal_bridge_width 0.5)
				(island_removal_mode 0)
			)
			(polygon
				(pts
					(arc
						(start 118.881144 -58.50001)
						(mid 118.119144 -58.50001)
						(end 118.881144 -58.50001)
					)
				)
			)
		)
		(zone
			(layer "F.Cu")
			(hatch none 0.5)
			(connect_pads
				(clearance 0)
			)
			(min_thickness 0.25)
			(keepout
				(tracks allowed)
				(vias not_allowed)
				(pads allowed)
				(copperpour not_allowed)
				(footprints allowed)
			)
			(placement
				(enabled no)
				(sheetname "")
			)
			(fill
				(thermal_gap 0.5)
				(thermal_bridge_width 0.5)
				(island_removal_mode 0)
			)
			(polygon
				(pts
					(arc
						(start 118.881144 -57.500012)
						(mid 118.119144 -57.500012)
						(end 118.881144 -57.500012)
					)
				)
			)
		)
		(zone
			(layer "F.Cu")
			(hatch none 0.5)
			(connect_pads
				(clearance 0)
			)
			(min_thickness 0.25)
			(keepout
				(tracks allowed)
				(vias not_allowed)
				(pads allowed)
				(copperpour not_allowed)
				(footprints allowed)
			)
			(placement
				(enabled no)
				(sheetname "")
			)
			(fill
				(thermal_gap 0.5)
				(thermal_bridge_width 0.5)
				(island_removal_mode 0)
			)
			(polygon
				(pts
					(arc
						(start 118.881144 -56.500014)
						(mid 118.119144 -56.500014)
						(end 118.881144 -56.500014)
					)
				)
			)
		)
		(zone
			(layer "F.Cu")
			(hatch none 0.5)
			(connect_pads
				(clearance 0)
			)
			(min_thickness 0.25)
			(keepout
				(tracks allowed)
				(vias not_allowed)
				(pads allowed)
				(copperpour not_allowed)
				(footprints allowed)
			)
			(placement
				(enabled no)
				(sheetname "")
			)
			(fill
				(thermal_gap 0.5)
				(thermal_bridge_width 0.5)
				(island_removal_mode 0)
			)
			(polygon
				(pts
					(arc
						(start 118.881144 -55.500016)
						(mid 118.119144 -55.500016)
						(end 118.881144 -55.500016)
					)
				)
			)
		)
		(zone
			(layer "F.Cu")
			(hatch none 0.5)
			(connect_pads
				(clearance 0)
			)
			(min_thickness 0.25)
			(keepout
				(tracks allowed)
				(vias not_allowed)
				(pads allowed)
				(copperpour not_allowed)
				(footprints allowed)
			)
			(placement
				(enabled no)
				(sheetname "")
			)
			(fill
				(thermal_gap 0.5)
				(thermal_bridge_width 0.5)
				(island_removal_mode 0)
			)
			(polygon
				(pts
					(arc
						(start 118.881144 -54.500018)
						(mid 118.119144 -54.500018)
						(end 118.881144 -54.500018)
					)
				)
			)
		)
		(zone
			(layer "F.Cu")
			(hatch none 0.5)
			(connect_pads
				(clearance 0)
			)
			(min_thickness 0.25)
			(keepout
				(tracks allowed)
				(vias not_allowed)
				(pads allowed)
				(copperpour not_allowed)
				(footprints allowed)
			)
			(placement
				(enabled no)
				(sheetname "")
			)
			(fill
				(thermal_gap 0.5)
				(thermal_bridge_width 0.5)
				(island_removal_mode 0)
			)
			(polygon
				(pts
					(arc
						(start 118.881144 -53.50002)
						(mid 118.119144 -53.50002)
						(end 118.881144 -53.50002)
					)
				)
			)
		)
		(zone
			(layer "F.Cu")
			(hatch none 0.5)
			(connect_pads
				(clearance 0)
			)
			(min_thickness 0.25)
			(keepout
				(tracks allowed)
				(vias not_allowed)
				(pads allowed)
				(copperpour not_allowed)
				(footprints allowed)
			)
			(placement
				(enabled no)
				(sheetname "")
			)
			(fill
				(thermal_gap 0.5)
				(thermal_bridge_width 0.5)
				(island_removal_mode 0)
			)
			(polygon
				(pts
					(arc
						(start 118.881144 -52.500022)
						(mid 118.119144 -52.500022)
						(end 118.881144 -52.500022)
					)
				)
			)
		)
		(zone
			(layer "F.Cu")
			(hatch none 0.5)
			(connect_pads
				(clearance 0)
			)
			(min_thickness 0.25)
			(keepout
				(tracks allowed)
				(vias not_allowed)
				(pads allowed)
				(copperpour not_allowed)
				(footprints allowed)
			)
			(placement
				(enabled no)
				(sheetname "")
			)
			(fill
				(thermal_gap 0.5)
				(thermal_bridge_width 0.5)
				(island_removal_mode 0)
			)
			(polygon
				(pts
					(arc
						(start 118.881144 -51.500024)
						(mid 118.119144 -51.500024)
						(end 118.881144 -51.500024)
					)
				)
			)
		)
		(zone
			(layer "F.Cu")
			(hatch none 0.5)
			(connect_pads
				(clearance 0)
			)
			(min_thickness 0.25)
			(keepout
				(tracks allowed)
				(vias not_allowed)
				(pads allowed)
				(copperpour not_allowed)
				(footprints allowed)
			)
			(placement
				(enabled no)
				(sheetname "")
			)
			(fill
				(thermal_gap 0.5)
				(thermal_bridge_width 0.5)
				(island_removal_mode 0)
			)
			(polygon
				(pts
					(arc
						(start 119.881142 -82.500216)
						(mid 119.119142 -82.500216)
						(end 119.881142 -82.500216)
					)
				)
			)
		)
		(zone
			(layer "F.Cu")
			(hatch none 0.5)
			(connect_pads
				(clearance 0)
			)
			(min_thickness 0.25)
			(keepout
				(tracks allowed)
				(vias not_allowed)
				(pads allowed)
				(copperpour not_allowed)
				(footprints allowed)
			)
			(placement
				(enabled no)
				(sheetname "")
			)
			(fill
				(thermal_gap 0.5)
				(thermal_bridge_width 0.5)
				(island_removal_mode 0)
			)
			(polygon
				(pts
					(arc
						(start 119.881142 -81.500218)
						(mid 119.119142 -81.500218)
						(end 119.881142 -81.500218)
					)
				)
			)
		)
		(zone
			(layer "F.Cu")
			(hatch none 0.5)
			(connect_pads
				(clearance 0)
			)
			(min_thickness 0.25)
			(keepout
				(tracks allowed)
				(vias not_allowed)
				(pads allowed)
				(copperpour not_allowed)
				(footprints allowed)
			)
			(placement
				(enabled no)
				(sheetname "")
			)
			(fill
				(thermal_gap 0.5)
				(thermal_bridge_width 0.5)
				(island_removal_mode 0)
			)
			(polygon
				(pts
					(arc
						(start 119.881142 -80.50022)
						(mid 119.119142 -80.50022)
						(end 119.881142 -80.50022)
					)
				)
			)
		)
		(zone
			(layer "F.Cu")
			(hatch none 0.5)
			(connect_pads
				(clearance 0)
			)
			(min_thickness 0.25)
			(keepout
				(tracks allowed)
				(vias not_allowed)
				(pads allowed)
				(copperpour not_allowed)
				(footprints allowed)
			)
			(placement
				(enabled no)
				(sheetname "")
			)
			(fill
				(thermal_gap 0.5)
				(thermal_bridge_width 0.5)
				(island_removal_mode 0)
			)
			(polygon
				(pts
					(arc
						(start 119.881142 -79.500222)
						(mid 119.119142 -79.500222)
						(end 119.881142 -79.500222)
					)
				)
			)
		)
		(zone
			(layer "F.Cu")
			(hatch none 0.5)
			(connect_pads
				(clearance 0)
			)
			(min_thickness 0.25)
			(keepout
				(tracks allowed)
				(vias not_allowed)
				(pads allowed)
				(copperpour not_allowed)
				(footprints allowed)
			)
			(placement
				(enabled no)
				(sheetname "")
			)
			(fill
				(thermal_gap 0.5)
				(thermal_bridge_width 0.5)
				(island_removal_mode 0)
			)
			(polygon
				(pts
					(arc
						(start 119.881142 -78.500224)
						(mid 119.119142 -78.500224)
						(end 119.881142 -78.500224)
					)
				)
			)
		)
		(zone
			(layer "F.Cu")
			(hatch none 0.5)
			(connect_pads
				(clearance 0)
			)
			(min_thickness 0.25)
			(keepout
				(tracks allowed)
				(vias not_allowed)
				(pads allowed)
				(copperpour not_allowed)
				(footprints allowed)
			)
			(placement
				(enabled no)
				(sheetname "")
			)
			(fill
				(thermal_gap 0.5)
				(thermal_bridge_width 0.5)
				(island_removal_mode 0)
			)
			(polygon
				(pts
					(arc
						(start 119.881142 -77.500226)
						(mid 119.119142 -77.500226)
						(end 119.881142 -77.500226)
					)
				)
			)
		)
		(zone
			(layer "F.Cu")
			(hatch none 0.5)
			(connect_pads
				(clearance 0)
			)
			(min_thickness 0.25)
			(keepout
				(tracks allowed)
				(vias not_allowed)
				(pads allowed)
				(copperpour not_allowed)
				(footprints allowed)
			)
			(placement
				(enabled no)
				(sheetname "")
			)
			(fill
				(thermal_gap 0.5)
				(thermal_bridge_width 0.5)
				(island_removal_mode 0)
			)
			(polygon
				(pts
					(arc
						(start 119.881142 -76.500228)
						(mid 119.119142 -76.500228)
						(end 119.881142 -76.500228)
					)
				)
			)
		)
		(zone
			(layer "F.Cu")
			(hatch none 0.5)
			(connect_pads
				(clearance 0)
			)
			(min_thickness 0.25)
			(keepout
				(tracks allowed)
				(vias not_allowed)
				(pads allowed)
				(copperpour not_allowed)
				(footprints allowed)
			)
			(placement
				(enabled no)
				(sheetname "")
			)
			(fill
				(thermal_gap 0.5)
				(thermal_bridge_width 0.5)
				(island_removal_mode 0)
			)
			(polygon
				(pts
					(arc
						(start 119.881142 -75.50023)
						(mid 119.119142 -75.50023)
						(end 119.881142 -75.50023)
					)
				)
			)
		)
		(zone
			(layer "F.Cu")
			(hatch none 0.5)
			(connect_pads
				(clearance 0)
			)
			(min_thickness 0.25)
			(keepout
				(tracks allowed)
				(vias not_allowed)
				(pads allowed)
				(copperpour not_allowed)
				(footprints allowed)
			)
			(placement
				(enabled no)
				(sheetname "")
			)
			(fill
				(thermal_gap 0.5)
				(thermal_bridge_width 0.5)
				(island_removal_mode 0)
			)
			(polygon
				(pts
					(arc
						(start 119.881142 -74.500232)
						(mid 119.119142 -74.500232)
						(end 119.881142 -74.500232)
					)
				)
			)
		)
		(zone
			(layer "F.Cu")
			(hatch none 0.5)
			(connect_pads
				(clearance 0)
			)
			(min_thickness 0.25)
			(keepout
				(tracks allowed)
				(vias not_allowed)
				(pads allowed)
				(copperpour not_allowed)
				(footprints allowed)
			)
			(placement
				(enabled no)
				(sheetname "")
			)
			(fill
				(thermal_gap 0.5)
				(thermal_bridge_width 0.5)
				(island_removal_mode 0)
			)
			(polygon
				(pts
					(arc
						(start 119.881142 -73.500234)
						(mid 119.119142 -73.500234)
						(end 119.881142 -73.500234)
					)
				)
			)
		)
		(zone
			(layer "F.Cu")
			(hatch none 0.5)
			(connect_pads
				(clearance 0)
			)
			(min_thickness 0.25)
			(keepout
				(tracks allowed)
				(vias not_allowed)
				(pads allowed)
				(copperpour not_allowed)
				(footprints allowed)
			)
			(placement
				(enabled no)
				(sheetname "")
			)
			(fill
				(thermal_gap 0.5)
				(thermal_bridge_width 0.5)
				(island_removal_mode 0)
			)
			(polygon
				(pts
					(arc
						(start 119.881142 -72.500236)
						(mid 119.119142 -72.500236)
						(end 119.881142 -72.500236)
					)
				)
			)
		)
		(zone
			(layer "F.Cu")
			(hatch none 0.5)
			(connect_pads
				(clearance 0)
			)
			(min_thickness 0.25)
			(keepout
				(tracks allowed)
				(vias not_allowed)
				(pads allowed)
				(copperpour not_allowed)
				(footprints allowed)
			)
			(placement
				(enabled no)
				(sheetname "")
			)
			(fill
				(thermal_gap 0.5)
				(thermal_bridge_width 0.5)
				(island_removal_mode 0)
			)
			(polygon
				(pts
					(arc
						(start 119.881142 -71.500238)
						(mid 119.119142 -71.500238)
						(end 119.881142 -71.500238)
					)
				)
			)
		)
		(zone
			(layer "F.Cu")
			(hatch none 0.5)
			(connect_pads
				(clearance 0)
			)
			(min_thickness 0.25)
			(keepout
				(tracks allowed)
				(vias not_allowed)
				(pads allowed)
				(copperpour not_allowed)
				(footprints allowed)
			)
			(placement
				(enabled no)
				(sheetname "")
			)
			(fill
				(thermal_gap 0.5)
				(thermal_bridge_width 0.5)
				(island_removal_mode 0)
			)
			(polygon
				(pts
					(arc
						(start 119.881142 -70.50024)
						(mid 119.119142 -70.50024)
						(end 119.881142 -70.50024)
					)
				)
			)
		)
		(zone
			(layer "F.Cu")
			(hatch none 0.5)
			(connect_pads
				(clearance 0)
			)
			(min_thickness 0.25)
			(keepout
				(tracks allowed)
				(vias not_allowed)
				(pads allowed)
				(copperpour not_allowed)
				(footprints allowed)
			)
			(placement
				(enabled no)
				(sheetname "")
			)
			(fill
				(thermal_gap 0.5)
				(thermal_bridge_width 0.5)
				(island_removal_mode 0)
			)
			(polygon
				(pts
					(arc
						(start 119.881142 -69.500242)
						(mid 119.119142 -69.500242)
						(end 119.881142 -69.500242)
					)
				)
			)
		)
		(zone
			(layer "F.Cu")
			(hatch none 0.5)
			(connect_pads
				(clearance 0)
			)
			(min_thickness 0.25)
			(keepout
				(tracks allowed)
				(vias not_allowed)
				(pads allowed)
				(copperpour not_allowed)
				(footprints allowed)
			)
			(placement
				(enabled no)
				(sheetname "")
			)
			(fill
				(thermal_gap 0.5)
				(thermal_bridge_width 0.5)
				(island_removal_mode 0)
			)
			(polygon
				(pts
					(arc
						(start 119.881142 -68.500244)
						(mid 119.119142 -68.500244)
						(end 119.881142 -68.500244)
					)
				)
			)
		)
		(zone
			(layer "F.Cu")
			(hatch none 0.5)
			(connect_pads
				(clearance 0)
			)
			(min_thickness 0.25)
			(keepout
				(tracks allowed)
				(vias not_allowed)
				(pads allowed)
				(copperpour not_allowed)
				(footprints allowed)
			)
			(placement
				(enabled no)
				(sheetname "")
			)
			(fill
				(thermal_gap 0.5)
				(thermal_bridge_width 0.5)
				(island_removal_mode 0)
			)
			(polygon
				(pts
					(arc
						(start 119.881142 -67.500246)
						(mid 119.119142 -67.500246)
						(end 119.881142 -67.500246)
					)
				)
			)
		)
		(zone
			(layer "F.Cu")
			(hatch none 0.5)
			(connect_pads
				(clearance 0)
			)
			(min_thickness 0.25)
			(keepout
				(tracks allowed)
				(vias not_allowed)
				(pads allowed)
				(copperpour not_allowed)
				(footprints allowed)
			)
			(placement
				(enabled no)
				(sheetname "")
			)
			(fill
				(thermal_gap 0.5)
				(thermal_bridge_width 0.5)
				(island_removal_mode 0)
			)
			(polygon
				(pts
					(arc
						(start 119.881142 -66.499994)
						(mid 119.119142 -66.499994)
						(end 119.881142 -66.499994)
					)
				)
			)
		)
		(zone
			(layer "F.Cu")
			(hatch none 0.5)
			(connect_pads
				(clearance 0)
			)
			(min_thickness 0.25)
			(keepout
				(tracks allowed)
				(vias not_allowed)
				(pads allowed)
				(copperpour not_allowed)
				(footprints allowed)
			)
			(placement
				(enabled no)
				(sheetname "")
			)
			(fill
				(thermal_gap 0.5)
				(thermal_bridge_width 0.5)
				(island_removal_mode 0)
			)
			(polygon
				(pts
					(arc
						(start 119.881142 -65.499996)
						(mid 119.119142 -65.499996)
						(end 119.881142 -65.499996)
					)
				)
			)
		)
		(zone
			(layer "F.Cu")
			(hatch none 0.5)
			(connect_pads
				(clearance 0)
			)
			(min_thickness 0.25)
			(keepout
				(tracks allowed)
				(vias not_allowed)
				(pads allowed)
				(copperpour not_allowed)
				(footprints allowed)
			)
			(placement
				(enabled no)
				(sheetname "")
			)
			(fill
				(thermal_gap 0.5)
				(thermal_bridge_width 0.5)
				(island_removal_mode 0)
			)
			(polygon
				(pts
					(arc
						(start 119.881142 -64.499998)
						(mid 119.119142 -64.499998)
						(end 119.881142 -64.499998)
					)
				)
			)
		)
		(zone
			(layer "F.Cu")
			(hatch none 0.5)
			(connect_pads
				(clearance 0)
			)
			(min_thickness 0.25)
			(keepout
				(tracks allowed)
				(vias not_allowed)
				(pads allowed)
				(copperpour not_allowed)
				(footprints allowed)
			)
			(placement
				(enabled no)
				(sheetname "")
			)
			(fill
				(thermal_gap 0.5)
				(thermal_bridge_width 0.5)
				(island_removal_mode 0)
			)
			(polygon
				(pts
					(arc
						(start 119.881142 -63.5)
						(mid 119.119142 -63.5)
						(end 119.881142 -63.5)
					)
				)
			)
		)
		(zone
			(layer "F.Cu")
			(hatch none 0.5)
			(connect_pads
				(clearance 0)
			)
			(min_thickness 0.25)
			(keepout
				(tracks allowed)
				(vias not_allowed)
				(pads allowed)
				(copperpour not_allowed)
				(footprints allowed)
			)
			(placement
				(enabled no)
				(sheetname "")
			)
			(fill
				(thermal_gap 0.5)
				(thermal_bridge_width 0.5)
				(island_removal_mode 0)
			)
			(polygon
				(pts
					(arc
						(start 119.881142 -62.500002)
						(mid 119.119142 -62.500002)
						(end 119.881142 -62.500002)
					)
				)
			)
		)
		(zone
			(layer "F.Cu")
			(hatch none 0.5)
			(connect_pads
				(clearance 0)
			)
			(min_thickness 0.25)
			(keepout
				(tracks allowed)
				(vias not_allowed)
				(pads allowed)
				(copperpour not_allowed)
				(footprints allowed)
			)
			(placement
				(enabled no)
				(sheetname "")
			)
			(fill
				(thermal_gap 0.5)
				(thermal_bridge_width 0.5)
				(island_removal_mode 0)
			)
			(polygon
				(pts
					(arc
						(start 119.881142 -61.500004)
						(mid 119.119142 -61.500004)
						(end 119.881142 -61.500004)
					)
				)
			)
		)
		(zone
			(layer "F.Cu")
			(hatch none 0.5)
			(connect_pads
				(clearance 0)
			)
			(min_thickness 0.25)
			(keepout
				(tracks allowed)
				(vias not_allowed)
				(pads allowed)
				(copperpour not_allowed)
				(footprints allowed)
			)
			(placement
				(enabled no)
				(sheetname "")
			)
			(fill
				(thermal_gap 0.5)
				(thermal_bridge_width 0.5)
				(island_removal_mode 0)
			)
			(polygon
				(pts
					(arc
						(start 119.881142 -60.500006)
						(mid 119.119142 -60.500006)
						(end 119.881142 -60.500006)
					)
				)
			)
		)
		(zone
			(layer "F.Cu")
			(hatch none 0.5)
			(connect_pads
				(clearance 0)
			)
			(min_thickness 0.25)
			(keepout
				(tracks allowed)
				(vias not_allowed)
				(pads allowed)
				(copperpour not_allowed)
				(footprints allowed)
			)
			(placement
				(enabled no)
				(sheetname "")
			)
			(fill
				(thermal_gap 0.5)
				(thermal_bridge_width 0.5)
				(island_removal_mode 0)
			)
			(polygon
				(pts
					(arc
						(start 119.881142 -59.500008)
						(mid 119.119142 -59.500008)
						(end 119.881142 -59.500008)
					)
				)
			)
		)
		(zone
			(layer "F.Cu")
			(hatch none 0.5)
			(connect_pads
				(clearance 0)
			)
			(min_thickness 0.25)
			(keepout
				(tracks allowed)
				(vias not_allowed)
				(pads allowed)
				(copperpour not_allowed)
				(footprints allowed)
			)
			(placement
				(enabled no)
				(sheetname "")
			)
			(fill
				(thermal_gap 0.5)
				(thermal_bridge_width 0.5)
				(island_removal_mode 0)
			)
			(polygon
				(pts
					(arc
						(start 119.881142 -58.50001)
						(mid 119.119142 -58.50001)
						(end 119.881142 -58.50001)
					)
				)
			)
		)
		(zone
			(layer "F.Cu")
			(hatch none 0.5)
			(connect_pads
				(clearance 0)
			)
			(min_thickness 0.25)
			(keepout
				(tracks allowed)
				(vias not_allowed)
				(pads allowed)
				(copperpour not_allowed)
				(footprints allowed)
			)
			(placement
				(enabled no)
				(sheetname "")
			)
			(fill
				(thermal_gap 0.5)
				(thermal_bridge_width 0.5)
				(island_removal_mode 0)
			)
			(polygon
				(pts
					(arc
						(start 119.881142 -57.500012)
						(mid 119.119142 -57.500012)
						(end 119.881142 -57.500012)
					)
				)
			)
		)
		(zone
			(layer "F.Cu")
			(hatch none 0.5)
			(connect_pads
				(clearance 0)
			)
			(min_thickness 0.25)
			(keepout
				(tracks allowed)
				(vias not_allowed)
				(pads allowed)
				(copperpour not_allowed)
				(footprints allowed)
			)
			(placement
				(enabled no)
				(sheetname "")
			)
			(fill
				(thermal_gap 0.5)
				(thermal_bridge_width 0.5)
				(island_removal_mode 0)
			)
			(polygon
				(pts
					(arc
						(start 119.881142 -56.500014)
						(mid 119.119142 -56.500014)
						(end 119.881142 -56.500014)
					)
				)
			)
		)
		(zone
			(layer "F.Cu")
			(hatch none 0.5)
			(connect_pads
				(clearance 0)
			)
			(min_thickness 0.25)
			(keepout
				(tracks allowed)
				(vias not_allowed)
				(pads allowed)
				(copperpour not_allowed)
				(footprints allowed)
			)
			(placement
				(enabled no)
				(sheetname "")
			)
			(fill
				(thermal_gap 0.5)
				(thermal_bridge_width 0.5)
				(island_removal_mode 0)
			)
			(polygon
				(pts
					(arc
						(start 119.881142 -55.500016)
						(mid 119.119142 -55.500016)
						(end 119.881142 -55.500016)
					)
				)
			)
		)
		(zone
			(layer "F.Cu")
			(hatch none 0.5)
			(connect_pads
				(clearance 0)
			)
			(min_thickness 0.25)
			(keepout
				(tracks allowed)
				(vias not_allowed)
				(pads allowed)
				(copperpour not_allowed)
				(footprints allowed)
			)
			(placement
				(enabled no)
				(sheetname "")
			)
			(fill
				(thermal_gap 0.5)
				(thermal_bridge_width 0.5)
				(island_removal_mode 0)
			)
			(polygon
				(pts
					(arc
						(start 119.881142 -54.500018)
						(mid 119.119142 -54.500018)
						(end 119.881142 -54.500018)
					)
				)
			)
		)
		(zone
			(layer "F.Cu")
			(hatch none 0.5)
			(connect_pads
				(clearance 0)
			)
			(min_thickness 0.25)
			(keepout
				(tracks allowed)
				(vias not_allowed)
				(pads allowed)
				(copperpour not_allowed)
				(footprints allowed)
			)
			(placement
				(enabled no)
				(sheetname "")
			)
			(fill
				(thermal_gap 0.5)
				(thermal_bridge_width 0.5)
				(island_removal_mode 0)
			)
			(polygon
				(pts
					(arc
						(start 119.881142 -53.50002)
						(mid 119.119142 -53.50002)
						(end 119.881142 -53.50002)
					)
				)
			)
		)
		(zone
			(layer "F.Cu")
			(hatch none 0.5)
			(connect_pads
				(clearance 0)
			)
			(min_thickness 0.25)
			(keepout
				(tracks allowed)
				(vias not_allowed)
				(pads allowed)
				(copperpour not_allowed)
				(footprints allowed)
			)
			(placement
				(enabled no)
				(sheetname "")
			)
			(fill
				(thermal_gap 0.5)
				(thermal_bridge_width 0.5)
				(island_removal_mode 0)
			)
			(polygon
				(pts
					(arc
						(start 119.881142 -52.500022)
						(mid 119.119142 -52.500022)
						(end 119.881142 -52.500022)
					)
				)
			)
		)
		(zone
			(layer "F.Cu")
			(hatch none 0.5)
			(connect_pads
				(clearance 0)
			)
			(min_thickness 0.25)
			(keepout
				(tracks allowed)
				(vias not_allowed)
				(pads allowed)
				(copperpour not_allowed)
				(footprints allowed)
			)
			(placement
				(enabled no)
				(sheetname "")
			)
			(fill
				(thermal_gap 0.5)
				(thermal_bridge_width 0.5)
				(island_removal_mode 0)
			)
			(polygon
				(pts
					(arc
						(start 119.881142 -51.500024)
						(mid 119.119142 -51.500024)
						(end 119.881142 -51.500024)
					)
				)
			)
		)
		(zone
			(layer "F.Cu")
			(hatch none 0.5)
			(connect_pads
				(clearance 0)
			)
			(min_thickness 0.25)
			(keepout
				(tracks allowed)
				(vias not_allowed)
				(pads allowed)
				(copperpour not_allowed)
				(footprints allowed)
			)
			(placement
				(enabled no)
				(sheetname "")
			)
			(fill
				(thermal_gap 0.5)
				(thermal_bridge_width 0.5)
				(island_removal_mode 0)
			)
			(polygon
				(pts
					(arc
						(start 120.88114 -82.500216)
						(mid 120.11914 -82.500216)
						(end 120.88114 -82.500216)
					)
				)
			)
		)
		(zone
			(layer "F.Cu")
			(hatch none 0.5)
			(connect_pads
				(clearance 0)
			)
			(min_thickness 0.25)
			(keepout
				(tracks allowed)
				(vias not_allowed)
				(pads allowed)
				(copperpour not_allowed)
				(footprints allowed)
			)
			(placement
				(enabled no)
				(sheetname "")
			)
			(fill
				(thermal_gap 0.5)
				(thermal_bridge_width 0.5)
				(island_removal_mode 0)
			)
			(polygon
				(pts
					(arc
						(start 120.88114 -81.500218)
						(mid 120.11914 -81.500218)
						(end 120.88114 -81.500218)
					)
				)
			)
		)
		(zone
			(layer "F.Cu")
			(hatch none 0.5)
			(connect_pads
				(clearance 0)
			)
			(min_thickness 0.25)
			(keepout
				(tracks allowed)
				(vias not_allowed)
				(pads allowed)
				(copperpour not_allowed)
				(footprints allowed)
			)
			(placement
				(enabled no)
				(sheetname "")
			)
			(fill
				(thermal_gap 0.5)
				(thermal_bridge_width 0.5)
				(island_removal_mode 0)
			)
			(polygon
				(pts
					(arc
						(start 120.88114 -80.50022)
						(mid 120.11914 -80.50022)
						(end 120.88114 -80.50022)
					)
				)
			)
		)
		(zone
			(layer "F.Cu")
			(hatch none 0.5)
			(connect_pads
				(clearance 0)
			)
			(min_thickness 0.25)
			(keepout
				(tracks allowed)
				(vias not_allowed)
				(pads allowed)
				(copperpour not_allowed)
				(footprints allowed)
			)
			(placement
				(enabled no)
				(sheetname "")
			)
			(fill
				(thermal_gap 0.5)
				(thermal_bridge_width 0.5)
				(island_removal_mode 0)
			)
			(polygon
				(pts
					(arc
						(start 120.88114 -79.500222)
						(mid 120.11914 -79.500222)
						(end 120.88114 -79.500222)
					)
				)
			)
		)
		(zone
			(layer "F.Cu")
			(hatch none 0.5)
			(connect_pads
				(clearance 0)
			)
			(min_thickness 0.25)
			(keepout
				(tracks allowed)
				(vias not_allowed)
				(pads allowed)
				(copperpour not_allowed)
				(footprints allowed)
			)
			(placement
				(enabled no)
				(sheetname "")
			)
			(fill
				(thermal_gap 0.5)
				(thermal_bridge_width 0.5)
				(island_removal_mode 0)
			)
			(polygon
				(pts
					(arc
						(start 120.88114 -78.500224)
						(mid 120.11914 -78.500224)
						(end 120.88114 -78.500224)
					)
				)
			)
		)
		(zone
			(layer "F.Cu")
			(hatch none 0.5)
			(connect_pads
				(clearance 0)
			)
			(min_thickness 0.25)
			(keepout
				(tracks allowed)
				(vias not_allowed)
				(pads allowed)
				(copperpour not_allowed)
				(footprints allowed)
			)
			(placement
				(enabled no)
				(sheetname "")
			)
			(fill
				(thermal_gap 0.5)
				(thermal_bridge_width 0.5)
				(island_removal_mode 0)
			)
			(polygon
				(pts
					(arc
						(start 120.88114 -77.500226)
						(mid 120.11914 -77.500226)
						(end 120.88114 -77.500226)
					)
				)
			)
		)
		(zone
			(layer "F.Cu")
			(hatch none 0.5)
			(connect_pads
				(clearance 0)
			)
			(min_thickness 0.25)
			(keepout
				(tracks allowed)
				(vias not_allowed)
				(pads allowed)
				(copperpour not_allowed)
				(footprints allowed)
			)
			(placement
				(enabled no)
				(sheetname "")
			)
			(fill
				(thermal_gap 0.5)
				(thermal_bridge_width 0.5)
				(island_removal_mode 0)
			)
			(polygon
				(pts
					(arc
						(start 120.88114 -76.500228)
						(mid 120.11914 -76.500228)
						(end 120.88114 -76.500228)
					)
				)
			)
		)
		(zone
			(layer "F.Cu")
			(hatch none 0.5)
			(connect_pads
				(clearance 0)
			)
			(min_thickness 0.25)
			(keepout
				(tracks allowed)
				(vias not_allowed)
				(pads allowed)
				(copperpour not_allowed)
				(footprints allowed)
			)
			(placement
				(enabled no)
				(sheetname "")
			)
			(fill
				(thermal_gap 0.5)
				(thermal_bridge_width 0.5)
				(island_removal_mode 0)
			)
			(polygon
				(pts
					(arc
						(start 120.88114 -75.50023)
						(mid 120.11914 -75.50023)
						(end 120.88114 -75.50023)
					)
				)
			)
		)
		(zone
			(layer "F.Cu")
			(hatch none 0.5)
			(connect_pads
				(clearance 0)
			)
			(min_thickness 0.25)
			(keepout
				(tracks allowed)
				(vias not_allowed)
				(pads allowed)
				(copperpour not_allowed)
				(footprints allowed)
			)
			(placement
				(enabled no)
				(sheetname "")
			)
			(fill
				(thermal_gap 0.5)
				(thermal_bridge_width 0.5)
				(island_removal_mode 0)
			)
			(polygon
				(pts
					(arc
						(start 120.88114 -74.500232)
						(mid 120.11914 -74.500232)
						(end 120.88114 -74.500232)
					)
				)
			)
		)
		(zone
			(layer "F.Cu")
			(hatch none 0.5)
			(connect_pads
				(clearance 0)
			)
			(min_thickness 0.25)
			(keepout
				(tracks allowed)
				(vias not_allowed)
				(pads allowed)
				(copperpour not_allowed)
				(footprints allowed)
			)
			(placement
				(enabled no)
				(sheetname "")
			)
			(fill
				(thermal_gap 0.5)
				(thermal_bridge_width 0.5)
				(island_removal_mode 0)
			)
			(polygon
				(pts
					(arc
						(start 120.88114 -73.500234)
						(mid 120.11914 -73.500234)
						(end 120.88114 -73.500234)
					)
				)
			)
		)
		(zone
			(layer "F.Cu")
			(hatch none 0.5)
			(connect_pads
				(clearance 0)
			)
			(min_thickness 0.25)
			(keepout
				(tracks allowed)
				(vias not_allowed)
				(pads allowed)
				(copperpour not_allowed)
				(footprints allowed)
			)
			(placement
				(enabled no)
				(sheetname "")
			)
			(fill
				(thermal_gap 0.5)
				(thermal_bridge_width 0.5)
				(island_removal_mode 0)
			)
			(polygon
				(pts
					(arc
						(start 120.88114 -72.500236)
						(mid 120.11914 -72.500236)
						(end 120.88114 -72.500236)
					)
				)
			)
		)
		(zone
			(layer "F.Cu")
			(hatch none 0.5)
			(connect_pads
				(clearance 0)
			)
			(min_thickness 0.25)
			(keepout
				(tracks allowed)
				(vias not_allowed)
				(pads allowed)
				(copperpour not_allowed)
				(footprints allowed)
			)
			(placement
				(enabled no)
				(sheetname "")
			)
			(fill
				(thermal_gap 0.5)
				(thermal_bridge_width 0.5)
				(island_removal_mode 0)
			)
			(polygon
				(pts
					(arc
						(start 120.88114 -71.500238)
						(mid 120.11914 -71.500238)
						(end 120.88114 -71.500238)
					)
				)
			)
		)
		(zone
			(layer "F.Cu")
			(hatch none 0.5)
			(connect_pads
				(clearance 0)
			)
			(min_thickness 0.25)
			(keepout
				(tracks allowed)
				(vias not_allowed)
				(pads allowed)
				(copperpour not_allowed)
				(footprints allowed)
			)
			(placement
				(enabled no)
				(sheetname "")
			)
			(fill
				(thermal_gap 0.5)
				(thermal_bridge_width 0.5)
				(island_removal_mode 0)
			)
			(polygon
				(pts
					(arc
						(start 120.88114 -70.50024)
						(mid 120.11914 -70.50024)
						(end 120.88114 -70.50024)
					)
				)
			)
		)
		(zone
			(layer "F.Cu")
			(hatch none 0.5)
			(connect_pads
				(clearance 0)
			)
			(min_thickness 0.25)
			(keepout
				(tracks allowed)
				(vias not_allowed)
				(pads allowed)
				(copperpour not_allowed)
				(footprints allowed)
			)
			(placement
				(enabled no)
				(sheetname "")
			)
			(fill
				(thermal_gap 0.5)
				(thermal_bridge_width 0.5)
				(island_removal_mode 0)
			)
			(polygon
				(pts
					(arc
						(start 120.88114 -69.500242)
						(mid 120.11914 -69.500242)
						(end 120.88114 -69.500242)
					)
				)
			)
		)
		(zone
			(layer "F.Cu")
			(hatch none 0.5)
			(connect_pads
				(clearance 0)
			)
			(min_thickness 0.25)
			(keepout
				(tracks allowed)
				(vias not_allowed)
				(pads allowed)
				(copperpour not_allowed)
				(footprints allowed)
			)
			(placement
				(enabled no)
				(sheetname "")
			)
			(fill
				(thermal_gap 0.5)
				(thermal_bridge_width 0.5)
				(island_removal_mode 0)
			)
			(polygon
				(pts
					(arc
						(start 120.88114 -68.500244)
						(mid 120.11914 -68.500244)
						(end 120.88114 -68.500244)
					)
				)
			)
		)
		(zone
			(layer "F.Cu")
			(hatch none 0.5)
			(connect_pads
				(clearance 0)
			)
			(min_thickness 0.25)
			(keepout
				(tracks allowed)
				(vias not_allowed)
				(pads allowed)
				(copperpour not_allowed)
				(footprints allowed)
			)
			(placement
				(enabled no)
				(sheetname "")
			)
			(fill
				(thermal_gap 0.5)
				(thermal_bridge_width 0.5)
				(island_removal_mode 0)
			)
			(polygon
				(pts
					(arc
						(start 120.88114 -67.500246)
						(mid 120.11914 -67.500246)
						(end 120.88114 -67.500246)
					)
				)
			)
		)
		(zone
			(layer "F.Cu")
			(hatch none 0.5)
			(connect_pads
				(clearance 0)
			)
			(min_thickness 0.25)
			(keepout
				(tracks allowed)
				(vias not_allowed)
				(pads allowed)
				(copperpour not_allowed)
				(footprints allowed)
			)
			(placement
				(enabled no)
				(sheetname "")
			)
			(fill
				(thermal_gap 0.5)
				(thermal_bridge_width 0.5)
				(island_removal_mode 0)
			)
			(polygon
				(pts
					(arc
						(start 120.88114 -66.499994)
						(mid 120.11914 -66.499994)
						(end 120.88114 -66.499994)
					)
				)
			)
		)
		(zone
			(layer "F.Cu")
			(hatch none 0.5)
			(connect_pads
				(clearance 0)
			)
			(min_thickness 0.25)
			(keepout
				(tracks allowed)
				(vias not_allowed)
				(pads allowed)
				(copperpour not_allowed)
				(footprints allowed)
			)
			(placement
				(enabled no)
				(sheetname "")
			)
			(fill
				(thermal_gap 0.5)
				(thermal_bridge_width 0.5)
				(island_removal_mode 0)
			)
			(polygon
				(pts
					(arc
						(start 120.88114 -65.499996)
						(mid 120.11914 -65.499996)
						(end 120.88114 -65.499996)
					)
				)
			)
		)
		(zone
			(layer "F.Cu")
			(hatch none 0.5)
			(connect_pads
				(clearance 0)
			)
			(min_thickness 0.25)
			(keepout
				(tracks allowed)
				(vias not_allowed)
				(pads allowed)
				(copperpour not_allowed)
				(footprints allowed)
			)
			(placement
				(enabled no)
				(sheetname "")
			)
			(fill
				(thermal_gap 0.5)
				(thermal_bridge_width 0.5)
				(island_removal_mode 0)
			)
			(polygon
				(pts
					(arc
						(start 120.88114 -64.499998)
						(mid 120.11914 -64.499998)
						(end 120.88114 -64.499998)
					)
				)
			)
		)
		(zone
			(layer "F.Cu")
			(hatch none 0.5)
			(connect_pads
				(clearance 0)
			)
			(min_thickness 0.25)
			(keepout
				(tracks allowed)
				(vias not_allowed)
				(pads allowed)
				(copperpour not_allowed)
				(footprints allowed)
			)
			(placement
				(enabled no)
				(sheetname "")
			)
			(fill
				(thermal_gap 0.5)
				(thermal_bridge_width 0.5)
				(island_removal_mode 0)
			)
			(polygon
				(pts
					(arc
						(start 120.88114 -63.5)
						(mid 120.11914 -63.5)
						(end 120.88114 -63.5)
					)
				)
			)
		)
		(zone
			(layer "F.Cu")
			(hatch none 0.5)
			(connect_pads
				(clearance 0)
			)
			(min_thickness 0.25)
			(keepout
				(tracks allowed)
				(vias not_allowed)
				(pads allowed)
				(copperpour not_allowed)
				(footprints allowed)
			)
			(placement
				(enabled no)
				(sheetname "")
			)
			(fill
				(thermal_gap 0.5)
				(thermal_bridge_width 0.5)
				(island_removal_mode 0)
			)
			(polygon
				(pts
					(arc
						(start 120.88114 -62.500002)
						(mid 120.11914 -62.500002)
						(end 120.88114 -62.500002)
					)
				)
			)
		)
		(zone
			(layer "F.Cu")
			(hatch none 0.5)
			(connect_pads
				(clearance 0)
			)
			(min_thickness 0.25)
			(keepout
				(tracks allowed)
				(vias not_allowed)
				(pads allowed)
				(copperpour not_allowed)
				(footprints allowed)
			)
			(placement
				(enabled no)
				(sheetname "")
			)
			(fill
				(thermal_gap 0.5)
				(thermal_bridge_width 0.5)
				(island_removal_mode 0)
			)
			(polygon
				(pts
					(arc
						(start 120.88114 -61.500004)
						(mid 120.11914 -61.500004)
						(end 120.88114 -61.500004)
					)
				)
			)
		)
		(zone
			(layer "F.Cu")
			(hatch none 0.5)
			(connect_pads
				(clearance 0)
			)
			(min_thickness 0.25)
			(keepout
				(tracks allowed)
				(vias not_allowed)
				(pads allowed)
				(copperpour not_allowed)
				(footprints allowed)
			)
			(placement
				(enabled no)
				(sheetname "")
			)
			(fill
				(thermal_gap 0.5)
				(thermal_bridge_width 0.5)
				(island_removal_mode 0)
			)
			(polygon
				(pts
					(arc
						(start 120.88114 -60.500006)
						(mid 120.11914 -60.500006)
						(end 120.88114 -60.500006)
					)
				)
			)
		)
		(zone
			(layer "F.Cu")
			(hatch none 0.5)
			(connect_pads
				(clearance 0)
			)
			(min_thickness 0.25)
			(keepout
				(tracks allowed)
				(vias not_allowed)
				(pads allowed)
				(copperpour not_allowed)
				(footprints allowed)
			)
			(placement
				(enabled no)
				(sheetname "")
			)
			(fill
				(thermal_gap 0.5)
				(thermal_bridge_width 0.5)
				(island_removal_mode 0)
			)
			(polygon
				(pts
					(arc
						(start 120.88114 -59.500008)
						(mid 120.11914 -59.500008)
						(end 120.88114 -59.500008)
					)
				)
			)
		)
		(zone
			(layer "F.Cu")
			(hatch none 0.5)
			(connect_pads
				(clearance 0)
			)
			(min_thickness 0.25)
			(keepout
				(tracks allowed)
				(vias not_allowed)
				(pads allowed)
				(copperpour not_allowed)
				(footprints allowed)
			)
			(placement
				(enabled no)
				(sheetname "")
			)
			(fill
				(thermal_gap 0.5)
				(thermal_bridge_width 0.5)
				(island_removal_mode 0)
			)
			(polygon
				(pts
					(arc
						(start 120.88114 -58.50001)
						(mid 120.11914 -58.50001)
						(end 120.88114 -58.50001)
					)
				)
			)
		)
		(zone
			(layer "F.Cu")
			(hatch none 0.5)
			(connect_pads
				(clearance 0)
			)
			(min_thickness 0.25)
			(keepout
				(tracks allowed)
				(vias not_allowed)
				(pads allowed)
				(copperpour not_allowed)
				(footprints allowed)
			)
			(placement
				(enabled no)
				(sheetname "")
			)
			(fill
				(thermal_gap 0.5)
				(thermal_bridge_width 0.5)
				(island_removal_mode 0)
			)
			(polygon
				(pts
					(arc
						(start 120.88114 -57.500012)
						(mid 120.11914 -57.500012)
						(end 120.88114 -57.500012)
					)
				)
			)
		)
		(zone
			(layer "F.Cu")
			(hatch none 0.5)
			(connect_pads
				(clearance 0)
			)
			(min_thickness 0.25)
			(keepout
				(tracks allowed)
				(vias not_allowed)
				(pads allowed)
				(copperpour not_allowed)
				(footprints allowed)
			)
			(placement
				(enabled no)
				(sheetname "")
			)
			(fill
				(thermal_gap 0.5)
				(thermal_bridge_width 0.5)
				(island_removal_mode 0)
			)
			(polygon
				(pts
					(arc
						(start 120.88114 -56.500014)
						(mid 120.11914 -56.500014)
						(end 120.88114 -56.500014)
					)
				)
			)
		)
		(zone
			(layer "F.Cu")
			(hatch none 0.5)
			(connect_pads
				(clearance 0)
			)
			(min_thickness 0.25)
			(keepout
				(tracks allowed)
				(vias not_allowed)
				(pads allowed)
				(copperpour not_allowed)
				(footprints allowed)
			)
			(placement
				(enabled no)
				(sheetname "")
			)
			(fill
				(thermal_gap 0.5)
				(thermal_bridge_width 0.5)
				(island_removal_mode 0)
			)
			(polygon
				(pts
					(arc
						(start 120.88114 -55.500016)
						(mid 120.11914 -55.500016)
						(end 120.88114 -55.500016)
					)
				)
			)
		)
		(zone
			(layer "F.Cu")
			(hatch none 0.5)
			(connect_pads
				(clearance 0)
			)
			(min_thickness 0.25)
			(keepout
				(tracks allowed)
				(vias not_allowed)
				(pads allowed)
				(copperpour not_allowed)
				(footprints allowed)
			)
			(placement
				(enabled no)
				(sheetname "")
			)
			(fill
				(thermal_gap 0.5)
				(thermal_bridge_width 0.5)
				(island_removal_mode 0)
			)
			(polygon
				(pts
					(arc
						(start 120.88114 -54.500018)
						(mid 120.11914 -54.500018)
						(end 120.88114 -54.500018)
					)
				)
			)
		)
		(zone
			(layer "F.Cu")
			(hatch none 0.5)
			(connect_pads
				(clearance 0)
			)
			(min_thickness 0.25)
			(keepout
				(tracks allowed)
				(vias not_allowed)
				(pads allowed)
				(copperpour not_allowed)
				(footprints allowed)
			)
			(placement
				(enabled no)
				(sheetname "")
			)
			(fill
				(thermal_gap 0.5)
				(thermal_bridge_width 0.5)
				(island_removal_mode 0)
			)
			(polygon
				(pts
					(arc
						(start 120.88114 -53.50002)
						(mid 120.11914 -53.50002)
						(end 120.88114 -53.50002)
					)
				)
			)
		)
		(zone
			(layer "F.Cu")
			(hatch none 0.5)
			(connect_pads
				(clearance 0)
			)
			(min_thickness 0.25)
			(keepout
				(tracks allowed)
				(vias not_allowed)
				(pads allowed)
				(copperpour not_allowed)
				(footprints allowed)
			)
			(placement
				(enabled no)
				(sheetname "")
			)
			(fill
				(thermal_gap 0.5)
				(thermal_bridge_width 0.5)
				(island_removal_mode 0)
			)
			(polygon
				(pts
					(arc
						(start 120.88114 -52.500022)
						(mid 120.11914 -52.500022)
						(end 120.88114 -52.500022)
					)
				)
			)
		)
		(zone
			(layer "F.Cu")
			(hatch none 0.5)
			(connect_pads
				(clearance 0)
			)
			(min_thickness 0.25)
			(keepout
				(tracks allowed)
				(vias not_allowed)
				(pads allowed)
				(copperpour not_allowed)
				(footprints allowed)
			)
			(placement
				(enabled no)
				(sheetname "")
			)
			(fill
				(thermal_gap 0.5)
				(thermal_bridge_width 0.5)
				(island_removal_mode 0)
			)
			(polygon
				(pts
					(arc
						(start 120.88114 -51.500024)
						(mid 120.11914 -51.500024)
						(end 120.88114 -51.500024)
					)
				)
			)
		)
		(zone
			(layer "F.Cu")
			(hatch none 0.5)
			(connect_pads
				(clearance 0)
			)
			(min_thickness 0.25)
			(keepout
				(tracks allowed)
				(vias not_allowed)
				(pads allowed)
				(copperpour not_allowed)
				(footprints allowed)
			)
			(placement
				(enabled no)
				(sheetname "")
			)
			(fill
				(thermal_gap 0.5)
				(thermal_bridge_width 0.5)
				(island_removal_mode 0)
			)
			(polygon
				(pts
					(arc
						(start 121.881138 -82.500216)
						(mid 121.119138 -82.500216)
						(end 121.881138 -82.500216)
					)
				)
			)
		)
		(zone
			(layer "F.Cu")
			(hatch none 0.5)
			(connect_pads
				(clearance 0)
			)
			(min_thickness 0.25)
			(keepout
				(tracks allowed)
				(vias not_allowed)
				(pads allowed)
				(copperpour not_allowed)
				(footprints allowed)
			)
			(placement
				(enabled no)
				(sheetname "")
			)
			(fill
				(thermal_gap 0.5)
				(thermal_bridge_width 0.5)
				(island_removal_mode 0)
			)
			(polygon
				(pts
					(arc
						(start 121.881138 -81.500218)
						(mid 121.119138 -81.500218)
						(end 121.881138 -81.500218)
					)
				)
			)
		)
		(zone
			(layer "F.Cu")
			(hatch none 0.5)
			(connect_pads
				(clearance 0)
			)
			(min_thickness 0.25)
			(keepout
				(tracks allowed)
				(vias not_allowed)
				(pads allowed)
				(copperpour not_allowed)
				(footprints allowed)
			)
			(placement
				(enabled no)
				(sheetname "")
			)
			(fill
				(thermal_gap 0.5)
				(thermal_bridge_width 0.5)
				(island_removal_mode 0)
			)
			(polygon
				(pts
					(arc
						(start 121.881138 -80.50022)
						(mid 121.119138 -80.50022)
						(end 121.881138 -80.50022)
					)
				)
			)
		)
		(zone
			(layer "F.Cu")
			(hatch none 0.5)
			(connect_pads
				(clearance 0)
			)
			(min_thickness 0.25)
			(keepout
				(tracks allowed)
				(vias not_allowed)
				(pads allowed)
				(copperpour not_allowed)
				(footprints allowed)
			)
			(placement
				(enabled no)
				(sheetname "")
			)
			(fill
				(thermal_gap 0.5)
				(thermal_bridge_width 0.5)
				(island_removal_mode 0)
			)
			(polygon
				(pts
					(arc
						(start 121.881138 -79.500222)
						(mid 121.119138 -79.500222)
						(end 121.881138 -79.500222)
					)
				)
			)
		)
		(zone
			(layer "F.Cu")
			(hatch none 0.5)
			(connect_pads
				(clearance 0)
			)
			(min_thickness 0.25)
			(keepout
				(tracks allowed)
				(vias not_allowed)
				(pads allowed)
				(copperpour not_allowed)
				(footprints allowed)
			)
			(placement
				(enabled no)
				(sheetname "")
			)
			(fill
				(thermal_gap 0.5)
				(thermal_bridge_width 0.5)
				(island_removal_mode 0)
			)
			(polygon
				(pts
					(arc
						(start 121.881138 -78.500224)
						(mid 121.119138 -78.500224)
						(end 121.881138 -78.500224)
					)
				)
			)
		)
		(zone
			(layer "F.Cu")
			(hatch none 0.5)
			(connect_pads
				(clearance 0)
			)
			(min_thickness 0.25)
			(keepout
				(tracks allowed)
				(vias not_allowed)
				(pads allowed)
				(copperpour not_allowed)
				(footprints allowed)
			)
			(placement
				(enabled no)
				(sheetname "")
			)
			(fill
				(thermal_gap 0.5)
				(thermal_bridge_width 0.5)
				(island_removal_mode 0)
			)
			(polygon
				(pts
					(arc
						(start 121.881138 -77.500226)
						(mid 121.119138 -77.500226)
						(end 121.881138 -77.500226)
					)
				)
			)
		)
		(zone
			(layer "F.Cu")
			(hatch none 0.5)
			(connect_pads
				(clearance 0)
			)
			(min_thickness 0.25)
			(keepout
				(tracks allowed)
				(vias not_allowed)
				(pads allowed)
				(copperpour not_allowed)
				(footprints allowed)
			)
			(placement
				(enabled no)
				(sheetname "")
			)
			(fill
				(thermal_gap 0.5)
				(thermal_bridge_width 0.5)
				(island_removal_mode 0)
			)
			(polygon
				(pts
					(arc
						(start 121.881138 -76.500228)
						(mid 121.119138 -76.500228)
						(end 121.881138 -76.500228)
					)
				)
			)
		)
		(zone
			(layer "F.Cu")
			(hatch none 0.5)
			(connect_pads
				(clearance 0)
			)
			(min_thickness 0.25)
			(keepout
				(tracks allowed)
				(vias not_allowed)
				(pads allowed)
				(copperpour not_allowed)
				(footprints allowed)
			)
			(placement
				(enabled no)
				(sheetname "")
			)
			(fill
				(thermal_gap 0.5)
				(thermal_bridge_width 0.5)
				(island_removal_mode 0)
			)
			(polygon
				(pts
					(arc
						(start 121.881138 -75.50023)
						(mid 121.119138 -75.50023)
						(end 121.881138 -75.50023)
					)
				)
			)
		)
		(zone
			(layer "F.Cu")
			(hatch none 0.5)
			(connect_pads
				(clearance 0)
			)
			(min_thickness 0.25)
			(keepout
				(tracks allowed)
				(vias not_allowed)
				(pads allowed)
				(copperpour not_allowed)
				(footprints allowed)
			)
			(placement
				(enabled no)
				(sheetname "")
			)
			(fill
				(thermal_gap 0.5)
				(thermal_bridge_width 0.5)
				(island_removal_mode 0)
			)
			(polygon
				(pts
					(arc
						(start 121.881138 -74.500232)
						(mid 121.119138 -74.500232)
						(end 121.881138 -74.500232)
					)
				)
			)
		)
		(zone
			(layer "F.Cu")
			(hatch none 0.5)
			(connect_pads
				(clearance 0)
			)
			(min_thickness 0.25)
			(keepout
				(tracks allowed)
				(vias not_allowed)
				(pads allowed)
				(copperpour not_allowed)
				(footprints allowed)
			)
			(placement
				(enabled no)
				(sheetname "")
			)
			(fill
				(thermal_gap 0.5)
				(thermal_bridge_width 0.5)
				(island_removal_mode 0)
			)
			(polygon
				(pts
					(arc
						(start 121.881138 -73.500234)
						(mid 121.119138 -73.500234)
						(end 121.881138 -73.500234)
					)
				)
			)
		)
		(zone
			(layer "F.Cu")
			(hatch none 0.5)
			(connect_pads
				(clearance 0)
			)
			(min_thickness 0.25)
			(keepout
				(tracks allowed)
				(vias not_allowed)
				(pads allowed)
				(copperpour not_allowed)
				(footprints allowed)
			)
			(placement
				(enabled no)
				(sheetname "")
			)
			(fill
				(thermal_gap 0.5)
				(thermal_bridge_width 0.5)
				(island_removal_mode 0)
			)
			(polygon
				(pts
					(arc
						(start 121.881138 -72.500236)
						(mid 121.119138 -72.500236)
						(end 121.881138 -72.500236)
					)
				)
			)
		)
		(zone
			(layer "F.Cu")
			(hatch none 0.5)
			(connect_pads
				(clearance 0)
			)
			(min_thickness 0.25)
			(keepout
				(tracks allowed)
				(vias not_allowed)
				(pads allowed)
				(copperpour not_allowed)
				(footprints allowed)
			)
			(placement
				(enabled no)
				(sheetname "")
			)
			(fill
				(thermal_gap 0.5)
				(thermal_bridge_width 0.5)
				(island_removal_mode 0)
			)
			(polygon
				(pts
					(arc
						(start 121.881138 -71.500238)
						(mid 121.119138 -71.500238)
						(end 121.881138 -71.500238)
					)
				)
			)
		)
		(zone
			(layer "F.Cu")
			(hatch none 0.5)
			(connect_pads
				(clearance 0)
			)
			(min_thickness 0.25)
			(keepout
				(tracks allowed)
				(vias not_allowed)
				(pads allowed)
				(copperpour not_allowed)
				(footprints allowed)
			)
			(placement
				(enabled no)
				(sheetname "")
			)
			(fill
				(thermal_gap 0.5)
				(thermal_bridge_width 0.5)
				(island_removal_mode 0)
			)
			(polygon
				(pts
					(arc
						(start 121.881138 -70.50024)
						(mid 121.119138 -70.50024)
						(end 121.881138 -70.50024)
					)
				)
			)
		)
		(zone
			(layer "F.Cu")
			(hatch none 0.5)
			(connect_pads
				(clearance 0)
			)
			(min_thickness 0.25)
			(keepout
				(tracks allowed)
				(vias not_allowed)
				(pads allowed)
				(copperpour not_allowed)
				(footprints allowed)
			)
			(placement
				(enabled no)
				(sheetname "")
			)
			(fill
				(thermal_gap 0.5)
				(thermal_bridge_width 0.5)
				(island_removal_mode 0)
			)
			(polygon
				(pts
					(arc
						(start 121.881138 -69.500242)
						(mid 121.119138 -69.500242)
						(end 121.881138 -69.500242)
					)
				)
			)
		)
		(zone
			(layer "F.Cu")
			(hatch none 0.5)
			(connect_pads
				(clearance 0)
			)
			(min_thickness 0.25)
			(keepout
				(tracks allowed)
				(vias not_allowed)
				(pads allowed)
				(copperpour not_allowed)
				(footprints allowed)
			)
			(placement
				(enabled no)
				(sheetname "")
			)
			(fill
				(thermal_gap 0.5)
				(thermal_bridge_width 0.5)
				(island_removal_mode 0)
			)
			(polygon
				(pts
					(arc
						(start 121.881138 -68.500244)
						(mid 121.119138 -68.500244)
						(end 121.881138 -68.500244)
					)
				)
			)
		)
		(zone
			(layer "F.Cu")
			(hatch none 0.5)
			(connect_pads
				(clearance 0)
			)
			(min_thickness 0.25)
			(keepout
				(tracks allowed)
				(vias not_allowed)
				(pads allowed)
				(copperpour not_allowed)
				(footprints allowed)
			)
			(placement
				(enabled no)
				(sheetname "")
			)
			(fill
				(thermal_gap 0.5)
				(thermal_bridge_width 0.5)
				(island_removal_mode 0)
			)
			(polygon
				(pts
					(arc
						(start 121.881138 -67.500246)
						(mid 121.119138 -67.500246)
						(end 121.881138 -67.500246)
					)
				)
			)
		)
		(zone
			(layer "F.Cu")
			(hatch none 0.5)
			(connect_pads
				(clearance 0)
			)
			(min_thickness 0.25)
			(keepout
				(tracks allowed)
				(vias not_allowed)
				(pads allowed)
				(copperpour not_allowed)
				(footprints allowed)
			)
			(placement
				(enabled no)
				(sheetname "")
			)
			(fill
				(thermal_gap 0.5)
				(thermal_bridge_width 0.5)
				(island_removal_mode 0)
			)
			(polygon
				(pts
					(arc
						(start 121.881138 -66.499994)
						(mid 121.119138 -66.499994)
						(end 121.881138 -66.499994)
					)
				)
			)
		)
		(zone
			(layer "F.Cu")
			(hatch none 0.5)
			(connect_pads
				(clearance 0)
			)
			(min_thickness 0.25)
			(keepout
				(tracks allowed)
				(vias not_allowed)
				(pads allowed)
				(copperpour not_allowed)
				(footprints allowed)
			)
			(placement
				(enabled no)
				(sheetname "")
			)
			(fill
				(thermal_gap 0.5)
				(thermal_bridge_width 0.5)
				(island_removal_mode 0)
			)
			(polygon
				(pts
					(arc
						(start 121.881138 -65.499996)
						(mid 121.119138 -65.499996)
						(end 121.881138 -65.499996)
					)
				)
			)
		)
		(zone
			(layer "F.Cu")
			(hatch none 0.5)
			(connect_pads
				(clearance 0)
			)
			(min_thickness 0.25)
			(keepout
				(tracks allowed)
				(vias not_allowed)
				(pads allowed)
				(copperpour not_allowed)
				(footprints allowed)
			)
			(placement
				(enabled no)
				(sheetname "")
			)
			(fill
				(thermal_gap 0.5)
				(thermal_bridge_width 0.5)
				(island_removal_mode 0)
			)
			(polygon
				(pts
					(arc
						(start 121.881138 -64.499998)
						(mid 121.119138 -64.499998)
						(end 121.881138 -64.499998)
					)
				)
			)
		)
		(zone
			(layer "F.Cu")
			(hatch none 0.5)
			(connect_pads
				(clearance 0)
			)
			(min_thickness 0.25)
			(keepout
				(tracks allowed)
				(vias not_allowed)
				(pads allowed)
				(copperpour not_allowed)
				(footprints allowed)
			)
			(placement
				(enabled no)
				(sheetname "")
			)
			(fill
				(thermal_gap 0.5)
				(thermal_bridge_width 0.5)
				(island_removal_mode 0)
			)
			(polygon
				(pts
					(arc
						(start 121.881138 -63.5)
						(mid 121.119138 -63.5)
						(end 121.881138 -63.5)
					)
				)
			)
		)
		(zone
			(layer "F.Cu")
			(hatch none 0.5)
			(connect_pads
				(clearance 0)
			)
			(min_thickness 0.25)
			(keepout
				(tracks allowed)
				(vias not_allowed)
				(pads allowed)
				(copperpour not_allowed)
				(footprints allowed)
			)
			(placement
				(enabled no)
				(sheetname "")
			)
			(fill
				(thermal_gap 0.5)
				(thermal_bridge_width 0.5)
				(island_removal_mode 0)
			)
			(polygon
				(pts
					(arc
						(start 121.881138 -62.500002)
						(mid 121.119138 -62.500002)
						(end 121.881138 -62.500002)
					)
				)
			)
		)
		(zone
			(layer "F.Cu")
			(hatch none 0.5)
			(connect_pads
				(clearance 0)
			)
			(min_thickness 0.25)
			(keepout
				(tracks allowed)
				(vias not_allowed)
				(pads allowed)
				(copperpour not_allowed)
				(footprints allowed)
			)
			(placement
				(enabled no)
				(sheetname "")
			)
			(fill
				(thermal_gap 0.5)
				(thermal_bridge_width 0.5)
				(island_removal_mode 0)
			)
			(polygon
				(pts
					(arc
						(start 121.881138 -61.500004)
						(mid 121.119138 -61.500004)
						(end 121.881138 -61.500004)
					)
				)
			)
		)
		(zone
			(layer "F.Cu")
			(hatch none 0.5)
			(connect_pads
				(clearance 0)
			)
			(min_thickness 0.25)
			(keepout
				(tracks allowed)
				(vias not_allowed)
				(pads allowed)
				(copperpour not_allowed)
				(footprints allowed)
			)
			(placement
				(enabled no)
				(sheetname "")
			)
			(fill
				(thermal_gap 0.5)
				(thermal_bridge_width 0.5)
				(island_removal_mode 0)
			)
			(polygon
				(pts
					(arc
						(start 121.881138 -60.500006)
						(mid 121.119138 -60.500006)
						(end 121.881138 -60.500006)
					)
				)
			)
		)
		(zone
			(layer "F.Cu")
			(hatch none 0.5)
			(connect_pads
				(clearance 0)
			)
			(min_thickness 0.25)
			(keepout
				(tracks allowed)
				(vias not_allowed)
				(pads allowed)
				(copperpour not_allowed)
				(footprints allowed)
			)
			(placement
				(enabled no)
				(sheetname "")
			)
			(fill
				(thermal_gap 0.5)
				(thermal_bridge_width 0.5)
				(island_removal_mode 0)
			)
			(polygon
				(pts
					(arc
						(start 121.881138 -59.500008)
						(mid 121.119138 -59.500008)
						(end 121.881138 -59.500008)
					)
				)
			)
		)
		(zone
			(layer "F.Cu")
			(hatch none 0.5)
			(connect_pads
				(clearance 0)
			)
			(min_thickness 0.25)
			(keepout
				(tracks allowed)
				(vias not_allowed)
				(pads allowed)
				(copperpour not_allowed)
				(footprints allowed)
			)
			(placement
				(enabled no)
				(sheetname "")
			)
			(fill
				(thermal_gap 0.5)
				(thermal_bridge_width 0.5)
				(island_removal_mode 0)
			)
			(polygon
				(pts
					(arc
						(start 121.881138 -58.50001)
						(mid 121.119138 -58.50001)
						(end 121.881138 -58.50001)
					)
				)
			)
		)
		(zone
			(layer "F.Cu")
			(hatch none 0.5)
			(connect_pads
				(clearance 0)
			)
			(min_thickness 0.25)
			(keepout
				(tracks allowed)
				(vias not_allowed)
				(pads allowed)
				(copperpour not_allowed)
				(footprints allowed)
			)
			(placement
				(enabled no)
				(sheetname "")
			)
			(fill
				(thermal_gap 0.5)
				(thermal_bridge_width 0.5)
				(island_removal_mode 0)
			)
			(polygon
				(pts
					(arc
						(start 121.881138 -57.500012)
						(mid 121.119138 -57.500012)
						(end 121.881138 -57.500012)
					)
				)
			)
		)
		(zone
			(layer "F.Cu")
			(hatch none 0.5)
			(connect_pads
				(clearance 0)
			)
			(min_thickness 0.25)
			(keepout
				(tracks allowed)
				(vias not_allowed)
				(pads allowed)
				(copperpour not_allowed)
				(footprints allowed)
			)
			(placement
				(enabled no)
				(sheetname "")
			)
			(fill
				(thermal_gap 0.5)
				(thermal_bridge_width 0.5)
				(island_removal_mode 0)
			)
			(polygon
				(pts
					(arc
						(start 121.881138 -56.500014)
						(mid 121.119138 -56.500014)
						(end 121.881138 -56.500014)
					)
				)
			)
		)
		(zone
			(layer "F.Cu")
			(hatch none 0.5)
			(connect_pads
				(clearance 0)
			)
			(min_thickness 0.25)
			(keepout
				(tracks allowed)
				(vias not_allowed)
				(pads allowed)
				(copperpour not_allowed)
				(footprints allowed)
			)
			(placement
				(enabled no)
				(sheetname "")
			)
			(fill
				(thermal_gap 0.5)
				(thermal_bridge_width 0.5)
				(island_removal_mode 0)
			)
			(polygon
				(pts
					(arc
						(start 121.881138 -55.500016)
						(mid 121.119138 -55.500016)
						(end 121.881138 -55.500016)
					)
				)
			)
		)
		(zone
			(layer "F.Cu")
			(hatch none 0.5)
			(connect_pads
				(clearance 0)
			)
			(min_thickness 0.25)
			(keepout
				(tracks allowed)
				(vias not_allowed)
				(pads allowed)
				(copperpour not_allowed)
				(footprints allowed)
			)
			(placement
				(enabled no)
				(sheetname "")
			)
			(fill
				(thermal_gap 0.5)
				(thermal_bridge_width 0.5)
				(island_removal_mode 0)
			)
			(polygon
				(pts
					(arc
						(start 121.881138 -54.500018)
						(mid 121.119138 -54.500018)
						(end 121.881138 -54.500018)
					)
				)
			)
		)
		(zone
			(layer "F.Cu")
			(hatch none 0.5)
			(connect_pads
				(clearance 0)
			)
			(min_thickness 0.25)
			(keepout
				(tracks allowed)
				(vias not_allowed)
				(pads allowed)
				(copperpour not_allowed)
				(footprints allowed)
			)
			(placement
				(enabled no)
				(sheetname "")
			)
			(fill
				(thermal_gap 0.5)
				(thermal_bridge_width 0.5)
				(island_removal_mode 0)
			)
			(polygon
				(pts
					(arc
						(start 121.881138 -53.50002)
						(mid 121.119138 -53.50002)
						(end 121.881138 -53.50002)
					)
				)
			)
		)
		(zone
			(layer "F.Cu")
			(hatch none 0.5)
			(connect_pads
				(clearance 0)
			)
			(min_thickness 0.25)
			(keepout
				(tracks allowed)
				(vias not_allowed)
				(pads allowed)
				(copperpour not_allowed)
				(footprints allowed)
			)
			(placement
				(enabled no)
				(sheetname "")
			)
			(fill
				(thermal_gap 0.5)
				(thermal_bridge_width 0.5)
				(island_removal_mode 0)
			)
			(polygon
				(pts
					(arc
						(start 121.881138 -52.500022)
						(mid 121.119138 -52.500022)
						(end 121.881138 -52.500022)
					)
				)
			)
		)
		(zone
			(layer "F.Cu")
			(hatch none 0.5)
			(connect_pads
				(clearance 0)
			)
			(min_thickness 0.25)
			(keepout
				(tracks allowed)
				(vias not_allowed)
				(pads allowed)
				(copperpour not_allowed)
				(footprints allowed)
			)
			(placement
				(enabled no)
				(sheetname "")
			)
			(fill
				(thermal_gap 0.5)
				(thermal_bridge_width 0.5)
				(island_removal_mode 0)
			)
			(polygon
				(pts
					(arc
						(start 121.881138 -51.500024)
						(mid 121.119138 -51.500024)
						(end 121.881138 -51.500024)
					)
				)
			)
		)
		(zone
			(layer "F.Cu")
			(hatch none 0.5)
			(connect_pads
				(clearance 0)
			)
			(min_thickness 0.25)
			(keepout
				(tracks allowed)
				(vias not_allowed)
				(pads allowed)
				(copperpour not_allowed)
				(footprints allowed)
			)
			(placement
				(enabled no)
				(sheetname "")
			)
			(fill
				(thermal_gap 0.5)
				(thermal_bridge_width 0.5)
				(island_removal_mode 0)
			)
			(polygon
				(pts
					(arc
						(start 122.881136 -82.500216)
						(mid 122.119136 -82.500216)
						(end 122.881136 -82.500216)
					)
				)
			)
		)
		(zone
			(layer "F.Cu")
			(hatch none 0.5)
			(connect_pads
				(clearance 0)
			)
			(min_thickness 0.25)
			(keepout
				(tracks allowed)
				(vias not_allowed)
				(pads allowed)
				(copperpour not_allowed)
				(footprints allowed)
			)
			(placement
				(enabled no)
				(sheetname "")
			)
			(fill
				(thermal_gap 0.5)
				(thermal_bridge_width 0.5)
				(island_removal_mode 0)
			)
			(polygon
				(pts
					(arc
						(start 122.881136 -81.500218)
						(mid 122.119136 -81.500218)
						(end 122.881136 -81.500218)
					)
				)
			)
		)
		(zone
			(layer "F.Cu")
			(hatch none 0.5)
			(connect_pads
				(clearance 0)
			)
			(min_thickness 0.25)
			(keepout
				(tracks allowed)
				(vias not_allowed)
				(pads allowed)
				(copperpour not_allowed)
				(footprints allowed)
			)
			(placement
				(enabled no)
				(sheetname "")
			)
			(fill
				(thermal_gap 0.5)
				(thermal_bridge_width 0.5)
				(island_removal_mode 0)
			)
			(polygon
				(pts
					(arc
						(start 122.881136 -80.50022)
						(mid 122.119136 -80.50022)
						(end 122.881136 -80.50022)
					)
				)
			)
		)
		(zone
			(layer "F.Cu")
			(hatch none 0.5)
			(connect_pads
				(clearance 0)
			)
			(min_thickness 0.25)
			(keepout
				(tracks allowed)
				(vias not_allowed)
				(pads allowed)
				(copperpour not_allowed)
				(footprints allowed)
			)
			(placement
				(enabled no)
				(sheetname "")
			)
			(fill
				(thermal_gap 0.5)
				(thermal_bridge_width 0.5)
				(island_removal_mode 0)
			)
			(polygon
				(pts
					(arc
						(start 122.881136 -79.500222)
						(mid 122.119136 -79.500222)
						(end 122.881136 -79.500222)
					)
				)
			)
		)
		(zone
			(layer "F.Cu")
			(hatch none 0.5)
			(connect_pads
				(clearance 0)
			)
			(min_thickness 0.25)
			(keepout
				(tracks allowed)
				(vias not_allowed)
				(pads allowed)
				(copperpour not_allowed)
				(footprints allowed)
			)
			(placement
				(enabled no)
				(sheetname "")
			)
			(fill
				(thermal_gap 0.5)
				(thermal_bridge_width 0.5)
				(island_removal_mode 0)
			)
			(polygon
				(pts
					(arc
						(start 122.881136 -78.500224)
						(mid 122.119136 -78.500224)
						(end 122.881136 -78.500224)
					)
				)
			)
		)
		(zone
			(layer "F.Cu")
			(hatch none 0.5)
			(connect_pads
				(clearance 0)
			)
			(min_thickness 0.25)
			(keepout
				(tracks allowed)
				(vias not_allowed)
				(pads allowed)
				(copperpour not_allowed)
				(footprints allowed)
			)
			(placement
				(enabled no)
				(sheetname "")
			)
			(fill
				(thermal_gap 0.5)
				(thermal_bridge_width 0.5)
				(island_removal_mode 0)
			)
			(polygon
				(pts
					(arc
						(start 122.881136 -77.500226)
						(mid 122.119136 -77.500226)
						(end 122.881136 -77.500226)
					)
				)
			)
		)
		(zone
			(layer "F.Cu")
			(hatch none 0.5)
			(connect_pads
				(clearance 0)
			)
			(min_thickness 0.25)
			(keepout
				(tracks allowed)
				(vias not_allowed)
				(pads allowed)
				(copperpour not_allowed)
				(footprints allowed)
			)
			(placement
				(enabled no)
				(sheetname "")
			)
			(fill
				(thermal_gap 0.5)
				(thermal_bridge_width 0.5)
				(island_removal_mode 0)
			)
			(polygon
				(pts
					(arc
						(start 122.881136 -76.500228)
						(mid 122.119136 -76.500228)
						(end 122.881136 -76.500228)
					)
				)
			)
		)
		(zone
			(layer "F.Cu")
			(hatch none 0.5)
			(connect_pads
				(clearance 0)
			)
			(min_thickness 0.25)
			(keepout
				(tracks allowed)
				(vias not_allowed)
				(pads allowed)
				(copperpour not_allowed)
				(footprints allowed)
			)
			(placement
				(enabled no)
				(sheetname "")
			)
			(fill
				(thermal_gap 0.5)
				(thermal_bridge_width 0.5)
				(island_removal_mode 0)
			)
			(polygon
				(pts
					(arc
						(start 122.881136 -75.50023)
						(mid 122.119136 -75.50023)
						(end 122.881136 -75.50023)
					)
				)
			)
		)
		(zone
			(layer "F.Cu")
			(hatch none 0.5)
			(connect_pads
				(clearance 0)
			)
			(min_thickness 0.25)
			(keepout
				(tracks allowed)
				(vias not_allowed)
				(pads allowed)
				(copperpour not_allowed)
				(footprints allowed)
			)
			(placement
				(enabled no)
				(sheetname "")
			)
			(fill
				(thermal_gap 0.5)
				(thermal_bridge_width 0.5)
				(island_removal_mode 0)
			)
			(polygon
				(pts
					(arc
						(start 122.881136 -74.500232)
						(mid 122.119136 -74.500232)
						(end 122.881136 -74.500232)
					)
				)
			)
		)
		(zone
			(layer "F.Cu")
			(hatch none 0.5)
			(connect_pads
				(clearance 0)
			)
			(min_thickness 0.25)
			(keepout
				(tracks allowed)
				(vias not_allowed)
				(pads allowed)
				(copperpour not_allowed)
				(footprints allowed)
			)
			(placement
				(enabled no)
				(sheetname "")
			)
			(fill
				(thermal_gap 0.5)
				(thermal_bridge_width 0.5)
				(island_removal_mode 0)
			)
			(polygon
				(pts
					(arc
						(start 122.881136 -73.500234)
						(mid 122.119136 -73.500234)
						(end 122.881136 -73.500234)
					)
				)
			)
		)
		(zone
			(layer "F.Cu")
			(hatch none 0.5)
			(connect_pads
				(clearance 0)
			)
			(min_thickness 0.25)
			(keepout
				(tracks allowed)
				(vias not_allowed)
				(pads allowed)
				(copperpour not_allowed)
				(footprints allowed)
			)
			(placement
				(enabled no)
				(sheetname "")
			)
			(fill
				(thermal_gap 0.5)
				(thermal_bridge_width 0.5)
				(island_removal_mode 0)
			)
			(polygon
				(pts
					(arc
						(start 122.881136 -72.500236)
						(mid 122.119136 -72.500236)
						(end 122.881136 -72.500236)
					)
				)
			)
		)
		(zone
			(layer "F.Cu")
			(hatch none 0.5)
			(connect_pads
				(clearance 0)
			)
			(min_thickness 0.25)
			(keepout
				(tracks allowed)
				(vias not_allowed)
				(pads allowed)
				(copperpour not_allowed)
				(footprints allowed)
			)
			(placement
				(enabled no)
				(sheetname "")
			)
			(fill
				(thermal_gap 0.5)
				(thermal_bridge_width 0.5)
				(island_removal_mode 0)
			)
			(polygon
				(pts
					(arc
						(start 122.881136 -71.500238)
						(mid 122.119136 -71.500238)
						(end 122.881136 -71.500238)
					)
				)
			)
		)
		(zone
			(layer "F.Cu")
			(hatch none 0.5)
			(connect_pads
				(clearance 0)
			)
			(min_thickness 0.25)
			(keepout
				(tracks allowed)
				(vias not_allowed)
				(pads allowed)
				(copperpour not_allowed)
				(footprints allowed)
			)
			(placement
				(enabled no)
				(sheetname "")
			)
			(fill
				(thermal_gap 0.5)
				(thermal_bridge_width 0.5)
				(island_removal_mode 0)
			)
			(polygon
				(pts
					(arc
						(start 122.881136 -70.50024)
						(mid 122.119136 -70.50024)
						(end 122.881136 -70.50024)
					)
				)
			)
		)
		(zone
			(layer "F.Cu")
			(hatch none 0.5)
			(connect_pads
				(clearance 0)
			)
			(min_thickness 0.25)
			(keepout
				(tracks allowed)
				(vias not_allowed)
				(pads allowed)
				(copperpour not_allowed)
				(footprints allowed)
			)
			(placement
				(enabled no)
				(sheetname "")
			)
			(fill
				(thermal_gap 0.5)
				(thermal_bridge_width 0.5)
				(island_removal_mode 0)
			)
			(polygon
				(pts
					(arc
						(start 122.881136 -69.500242)
						(mid 122.119136 -69.500242)
						(end 122.881136 -69.500242)
					)
				)
			)
		)
		(zone
			(layer "F.Cu")
			(hatch none 0.5)
			(connect_pads
				(clearance 0)
			)
			(min_thickness 0.25)
			(keepout
				(tracks allowed)
				(vias not_allowed)
				(pads allowed)
				(copperpour not_allowed)
				(footprints allowed)
			)
			(placement
				(enabled no)
				(sheetname "")
			)
			(fill
				(thermal_gap 0.5)
				(thermal_bridge_width 0.5)
				(island_removal_mode 0)
			)
			(polygon
				(pts
					(arc
						(start 122.881136 -68.500244)
						(mid 122.119136 -68.500244)
						(end 122.881136 -68.500244)
					)
				)
			)
		)
		(zone
			(layer "F.Cu")
			(hatch none 0.5)
			(connect_pads
				(clearance 0)
			)
			(min_thickness 0.25)
			(keepout
				(tracks allowed)
				(vias not_allowed)
				(pads allowed)
				(copperpour not_allowed)
				(footprints allowed)
			)
			(placement
				(enabled no)
				(sheetname "")
			)
			(fill
				(thermal_gap 0.5)
				(thermal_bridge_width 0.5)
				(island_removal_mode 0)
			)
			(polygon
				(pts
					(arc
						(start 122.881136 -67.500246)
						(mid 122.119136 -67.500246)
						(end 122.881136 -67.500246)
					)
				)
			)
		)
		(zone
			(layer "F.Cu")
			(hatch none 0.5)
			(connect_pads
				(clearance 0)
			)
			(min_thickness 0.25)
			(keepout
				(tracks allowed)
				(vias not_allowed)
				(pads allowed)
				(copperpour not_allowed)
				(footprints allowed)
			)
			(placement
				(enabled no)
				(sheetname "")
			)
			(fill
				(thermal_gap 0.5)
				(thermal_bridge_width 0.5)
				(island_removal_mode 0)
			)
			(polygon
				(pts
					(arc
						(start 122.881136 -66.499994)
						(mid 122.119136 -66.499994)
						(end 122.881136 -66.499994)
					)
				)
			)
		)
		(zone
			(layer "F.Cu")
			(hatch none 0.5)
			(connect_pads
				(clearance 0)
			)
			(min_thickness 0.25)
			(keepout
				(tracks allowed)
				(vias not_allowed)
				(pads allowed)
				(copperpour not_allowed)
				(footprints allowed)
			)
			(placement
				(enabled no)
				(sheetname "")
			)
			(fill
				(thermal_gap 0.5)
				(thermal_bridge_width 0.5)
				(island_removal_mode 0)
			)
			(polygon
				(pts
					(arc
						(start 122.881136 -65.499996)
						(mid 122.119136 -65.499996)
						(end 122.881136 -65.499996)
					)
				)
			)
		)
		(zone
			(layer "F.Cu")
			(hatch none 0.5)
			(connect_pads
				(clearance 0)
			)
			(min_thickness 0.25)
			(keepout
				(tracks allowed)
				(vias not_allowed)
				(pads allowed)
				(copperpour not_allowed)
				(footprints allowed)
			)
			(placement
				(enabled no)
				(sheetname "")
			)
			(fill
				(thermal_gap 0.5)
				(thermal_bridge_width 0.5)
				(island_removal_mode 0)
			)
			(polygon
				(pts
					(arc
						(start 122.881136 -64.499998)
						(mid 122.119136 -64.499998)
						(end 122.881136 -64.499998)
					)
				)
			)
		)
		(zone
			(layer "F.Cu")
			(hatch none 0.5)
			(connect_pads
				(clearance 0)
			)
			(min_thickness 0.25)
			(keepout
				(tracks allowed)
				(vias not_allowed)
				(pads allowed)
				(copperpour not_allowed)
				(footprints allowed)
			)
			(placement
				(enabled no)
				(sheetname "")
			)
			(fill
				(thermal_gap 0.5)
				(thermal_bridge_width 0.5)
				(island_removal_mode 0)
			)
			(polygon
				(pts
					(arc
						(start 122.881136 -63.5)
						(mid 122.119136 -63.5)
						(end 122.881136 -63.5)
					)
				)
			)
		)
		(zone
			(layer "F.Cu")
			(hatch none 0.5)
			(connect_pads
				(clearance 0)
			)
			(min_thickness 0.25)
			(keepout
				(tracks allowed)
				(vias not_allowed)
				(pads allowed)
				(copperpour not_allowed)
				(footprints allowed)
			)
			(placement
				(enabled no)
				(sheetname "")
			)
			(fill
				(thermal_gap 0.5)
				(thermal_bridge_width 0.5)
				(island_removal_mode 0)
			)
			(polygon
				(pts
					(arc
						(start 122.881136 -62.500002)
						(mid 122.119136 -62.500002)
						(end 122.881136 -62.500002)
					)
				)
			)
		)
		(zone
			(layer "F.Cu")
			(hatch none 0.5)
			(connect_pads
				(clearance 0)
			)
			(min_thickness 0.25)
			(keepout
				(tracks allowed)
				(vias not_allowed)
				(pads allowed)
				(copperpour not_allowed)
				(footprints allowed)
			)
			(placement
				(enabled no)
				(sheetname "")
			)
			(fill
				(thermal_gap 0.5)
				(thermal_bridge_width 0.5)
				(island_removal_mode 0)
			)
			(polygon
				(pts
					(arc
						(start 122.881136 -61.500004)
						(mid 122.119136 -61.500004)
						(end 122.881136 -61.500004)
					)
				)
			)
		)
		(zone
			(layer "F.Cu")
			(hatch none 0.5)
			(connect_pads
				(clearance 0)
			)
			(min_thickness 0.25)
			(keepout
				(tracks allowed)
				(vias not_allowed)
				(pads allowed)
				(copperpour not_allowed)
				(footprints allowed)
			)
			(placement
				(enabled no)
				(sheetname "")
			)
			(fill
				(thermal_gap 0.5)
				(thermal_bridge_width 0.5)
				(island_removal_mode 0)
			)
			(polygon
				(pts
					(arc
						(start 122.881136 -60.500006)
						(mid 122.119136 -60.500006)
						(end 122.881136 -60.500006)
					)
				)
			)
		)
		(zone
			(layer "F.Cu")
			(hatch none 0.5)
			(connect_pads
				(clearance 0)
			)
			(min_thickness 0.25)
			(keepout
				(tracks allowed)
				(vias not_allowed)
				(pads allowed)
				(copperpour not_allowed)
				(footprints allowed)
			)
			(placement
				(enabled no)
				(sheetname "")
			)
			(fill
				(thermal_gap 0.5)
				(thermal_bridge_width 0.5)
				(island_removal_mode 0)
			)
			(polygon
				(pts
					(arc
						(start 122.881136 -59.500008)
						(mid 122.119136 -59.500008)
						(end 122.881136 -59.500008)
					)
				)
			)
		)
		(zone
			(layer "F.Cu")
			(hatch none 0.5)
			(connect_pads
				(clearance 0)
			)
			(min_thickness 0.25)
			(keepout
				(tracks allowed)
				(vias not_allowed)
				(pads allowed)
				(copperpour not_allowed)
				(footprints allowed)
			)
			(placement
				(enabled no)
				(sheetname "")
			)
			(fill
				(thermal_gap 0.5)
				(thermal_bridge_width 0.5)
				(island_removal_mode 0)
			)
			(polygon
				(pts
					(arc
						(start 122.881136 -58.50001)
						(mid 122.119136 -58.50001)
						(end 122.881136 -58.50001)
					)
				)
			)
		)
		(zone
			(layer "F.Cu")
			(hatch none 0.5)
			(connect_pads
				(clearance 0)
			)
			(min_thickness 0.25)
			(keepout
				(tracks allowed)
				(vias not_allowed)
				(pads allowed)
				(copperpour not_allowed)
				(footprints allowed)
			)
			(placement
				(enabled no)
				(sheetname "")
			)
			(fill
				(thermal_gap 0.5)
				(thermal_bridge_width 0.5)
				(island_removal_mode 0)
			)
			(polygon
				(pts
					(arc
						(start 122.881136 -57.500012)
						(mid 122.119136 -57.500012)
						(end 122.881136 -57.500012)
					)
				)
			)
		)
		(zone
			(layer "F.Cu")
			(hatch none 0.5)
			(connect_pads
				(clearance 0)
			)
			(min_thickness 0.25)
			(keepout
				(tracks allowed)
				(vias not_allowed)
				(pads allowed)
				(copperpour not_allowed)
				(footprints allowed)
			)
			(placement
				(enabled no)
				(sheetname "")
			)
			(fill
				(thermal_gap 0.5)
				(thermal_bridge_width 0.5)
				(island_removal_mode 0)
			)
			(polygon
				(pts
					(arc
						(start 122.881136 -56.500014)
						(mid 122.119136 -56.500014)
						(end 122.881136 -56.500014)
					)
				)
			)
		)
		(zone
			(layer "F.Cu")
			(hatch none 0.5)
			(connect_pads
				(clearance 0)
			)
			(min_thickness 0.25)
			(keepout
				(tracks allowed)
				(vias not_allowed)
				(pads allowed)
				(copperpour not_allowed)
				(footprints allowed)
			)
			(placement
				(enabled no)
				(sheetname "")
			)
			(fill
				(thermal_gap 0.5)
				(thermal_bridge_width 0.5)
				(island_removal_mode 0)
			)
			(polygon
				(pts
					(arc
						(start 122.881136 -55.500016)
						(mid 122.119136 -55.500016)
						(end 122.881136 -55.500016)
					)
				)
			)
		)
		(zone
			(layer "F.Cu")
			(hatch none 0.5)
			(connect_pads
				(clearance 0)
			)
			(min_thickness 0.25)
			(keepout
				(tracks allowed)
				(vias not_allowed)
				(pads allowed)
				(copperpour not_allowed)
				(footprints allowed)
			)
			(placement
				(enabled no)
				(sheetname "")
			)
			(fill
				(thermal_gap 0.5)
				(thermal_bridge_width 0.5)
				(island_removal_mode 0)
			)
			(polygon
				(pts
					(arc
						(start 122.881136 -54.500018)
						(mid 122.119136 -54.500018)
						(end 122.881136 -54.500018)
					)
				)
			)
		)
		(zone
			(layer "F.Cu")
			(hatch none 0.5)
			(connect_pads
				(clearance 0)
			)
			(min_thickness 0.25)
			(keepout
				(tracks allowed)
				(vias not_allowed)
				(pads allowed)
				(copperpour not_allowed)
				(footprints allowed)
			)
			(placement
				(enabled no)
				(sheetname "")
			)
			(fill
				(thermal_gap 0.5)
				(thermal_bridge_width 0.5)
				(island_removal_mode 0)
			)
			(polygon
				(pts
					(arc
						(start 122.881136 -53.50002)
						(mid 122.119136 -53.50002)
						(end 122.881136 -53.50002)
					)
				)
			)
		)
		(zone
			(layer "F.Cu")
			(hatch none 0.5)
			(connect_pads
				(clearance 0)
			)
			(min_thickness 0.25)
			(keepout
				(tracks allowed)
				(vias not_allowed)
				(pads allowed)
				(copperpour not_allowed)
				(footprints allowed)
			)
			(placement
				(enabled no)
				(sheetname "")
			)
			(fill
				(thermal_gap 0.5)
				(thermal_bridge_width 0.5)
				(island_removal_mode 0)
			)
			(polygon
				(pts
					(arc
						(start 122.881136 -52.500022)
						(mid 122.119136 -52.500022)
						(end 122.881136 -52.500022)
					)
				)
			)
		)
		(zone
			(layer "F.Cu")
			(hatch none 0.5)
			(connect_pads
				(clearance 0)
			)
			(min_thickness 0.25)
			(keepout
				(tracks allowed)
				(vias not_allowed)
				(pads allowed)
				(copperpour not_allowed)
				(footprints allowed)
			)
			(placement
				(enabled no)
				(sheetname "")
			)
			(fill
				(thermal_gap 0.5)
				(thermal_bridge_width 0.5)
				(island_removal_mode 0)
			)
			(polygon
				(pts
					(arc
						(start 122.881136 -51.500024)
						(mid 122.119136 -51.500024)
						(end 122.881136 -51.500024)
					)
				)
			)
		)
		(zone
			(layer "F.Cu")
			(hatch none 0.5)
			(connect_pads
				(clearance 0)
			)
			(min_thickness 0.25)
			(keepout
				(tracks allowed)
				(vias not_allowed)
				(pads allowed)
				(copperpour not_allowed)
				(footprints allowed)
			)
			(placement
				(enabled no)
				(sheetname "")
			)
			(fill
				(thermal_gap 0.5)
				(thermal_bridge_width 0.5)
				(island_removal_mode 0)
			)
			(polygon
				(pts
					(arc
						(start 123.881134 -82.500216)
						(mid 123.119134 -82.500216)
						(end 123.881134 -82.500216)
					)
				)
			)
		)
		(zone
			(layer "F.Cu")
			(hatch none 0.5)
			(connect_pads
				(clearance 0)
			)
			(min_thickness 0.25)
			(keepout
				(tracks allowed)
				(vias not_allowed)
				(pads allowed)
				(copperpour not_allowed)
				(footprints allowed)
			)
			(placement
				(enabled no)
				(sheetname "")
			)
			(fill
				(thermal_gap 0.5)
				(thermal_bridge_width 0.5)
				(island_removal_mode 0)
			)
			(polygon
				(pts
					(arc
						(start 123.881134 -81.500218)
						(mid 123.119134 -81.500218)
						(end 123.881134 -81.500218)
					)
				)
			)
		)
		(zone
			(layer "F.Cu")
			(hatch none 0.5)
			(connect_pads
				(clearance 0)
			)
			(min_thickness 0.25)
			(keepout
				(tracks allowed)
				(vias not_allowed)
				(pads allowed)
				(copperpour not_allowed)
				(footprints allowed)
			)
			(placement
				(enabled no)
				(sheetname "")
			)
			(fill
				(thermal_gap 0.5)
				(thermal_bridge_width 0.5)
				(island_removal_mode 0)
			)
			(polygon
				(pts
					(arc
						(start 123.881134 -80.50022)
						(mid 123.119134 -80.50022)
						(end 123.881134 -80.50022)
					)
				)
			)
		)
		(zone
			(layer "F.Cu")
			(hatch none 0.5)
			(connect_pads
				(clearance 0)
			)
			(min_thickness 0.25)
			(keepout
				(tracks allowed)
				(vias not_allowed)
				(pads allowed)
				(copperpour not_allowed)
				(footprints allowed)
			)
			(placement
				(enabled no)
				(sheetname "")
			)
			(fill
				(thermal_gap 0.5)
				(thermal_bridge_width 0.5)
				(island_removal_mode 0)
			)
			(polygon
				(pts
					(arc
						(start 123.881134 -79.500222)
						(mid 123.119134 -79.500222)
						(end 123.881134 -79.500222)
					)
				)
			)
		)
		(zone
			(layer "F.Cu")
			(hatch none 0.5)
			(connect_pads
				(clearance 0)
			)
			(min_thickness 0.25)
			(keepout
				(tracks allowed)
				(vias not_allowed)
				(pads allowed)
				(copperpour not_allowed)
				(footprints allowed)
			)
			(placement
				(enabled no)
				(sheetname "")
			)
			(fill
				(thermal_gap 0.5)
				(thermal_bridge_width 0.5)
				(island_removal_mode 0)
			)
			(polygon
				(pts
					(arc
						(start 123.881134 -78.500224)
						(mid 123.119134 -78.500224)
						(end 123.881134 -78.500224)
					)
				)
			)
		)
		(zone
			(layer "F.Cu")
			(hatch none 0.5)
			(connect_pads
				(clearance 0)
			)
			(min_thickness 0.25)
			(keepout
				(tracks allowed)
				(vias not_allowed)
				(pads allowed)
				(copperpour not_allowed)
				(footprints allowed)
			)
			(placement
				(enabled no)
				(sheetname "")
			)
			(fill
				(thermal_gap 0.5)
				(thermal_bridge_width 0.5)
				(island_removal_mode 0)
			)
			(polygon
				(pts
					(arc
						(start 123.881134 -77.500226)
						(mid 123.119134 -77.500226)
						(end 123.881134 -77.500226)
					)
				)
			)
		)
		(zone
			(layer "F.Cu")
			(hatch none 0.5)
			(connect_pads
				(clearance 0)
			)
			(min_thickness 0.25)
			(keepout
				(tracks allowed)
				(vias not_allowed)
				(pads allowed)
				(copperpour not_allowed)
				(footprints allowed)
			)
			(placement
				(enabled no)
				(sheetname "")
			)
			(fill
				(thermal_gap 0.5)
				(thermal_bridge_width 0.5)
				(island_removal_mode 0)
			)
			(polygon
				(pts
					(arc
						(start 123.881134 -76.500228)
						(mid 123.119134 -76.500228)
						(end 123.881134 -76.500228)
					)
				)
			)
		)
		(zone
			(layer "F.Cu")
			(hatch none 0.5)
			(connect_pads
				(clearance 0)
			)
			(min_thickness 0.25)
			(keepout
				(tracks allowed)
				(vias not_allowed)
				(pads allowed)
				(copperpour not_allowed)
				(footprints allowed)
			)
			(placement
				(enabled no)
				(sheetname "")
			)
			(fill
				(thermal_gap 0.5)
				(thermal_bridge_width 0.5)
				(island_removal_mode 0)
			)
			(polygon
				(pts
					(arc
						(start 123.881134 -75.50023)
						(mid 123.119134 -75.50023)
						(end 123.881134 -75.50023)
					)
				)
			)
		)
		(zone
			(layer "F.Cu")
			(hatch none 0.5)
			(connect_pads
				(clearance 0)
			)
			(min_thickness 0.25)
			(keepout
				(tracks allowed)
				(vias not_allowed)
				(pads allowed)
				(copperpour not_allowed)
				(footprints allowed)
			)
			(placement
				(enabled no)
				(sheetname "")
			)
			(fill
				(thermal_gap 0.5)
				(thermal_bridge_width 0.5)
				(island_removal_mode 0)
			)
			(polygon
				(pts
					(arc
						(start 123.881134 -74.500232)
						(mid 123.119134 -74.500232)
						(end 123.881134 -74.500232)
					)
				)
			)
		)
		(zone
			(layer "F.Cu")
			(hatch none 0.5)
			(connect_pads
				(clearance 0)
			)
			(min_thickness 0.25)
			(keepout
				(tracks allowed)
				(vias not_allowed)
				(pads allowed)
				(copperpour not_allowed)
				(footprints allowed)
			)
			(placement
				(enabled no)
				(sheetname "")
			)
			(fill
				(thermal_gap 0.5)
				(thermal_bridge_width 0.5)
				(island_removal_mode 0)
			)
			(polygon
				(pts
					(arc
						(start 123.881134 -73.500234)
						(mid 123.119134 -73.500234)
						(end 123.881134 -73.500234)
					)
				)
			)
		)
		(zone
			(layer "F.Cu")
			(hatch none 0.5)
			(connect_pads
				(clearance 0)
			)
			(min_thickness 0.25)
			(keepout
				(tracks allowed)
				(vias not_allowed)
				(pads allowed)
				(copperpour not_allowed)
				(footprints allowed)
			)
			(placement
				(enabled no)
				(sheetname "")
			)
			(fill
				(thermal_gap 0.5)
				(thermal_bridge_width 0.5)
				(island_removal_mode 0)
			)
			(polygon
				(pts
					(arc
						(start 123.881134 -72.500236)
						(mid 123.119134 -72.500236)
						(end 123.881134 -72.500236)
					)
				)
			)
		)
		(zone
			(layer "F.Cu")
			(hatch none 0.5)
			(connect_pads
				(clearance 0)
			)
			(min_thickness 0.25)
			(keepout
				(tracks allowed)
				(vias not_allowed)
				(pads allowed)
				(copperpour not_allowed)
				(footprints allowed)
			)
			(placement
				(enabled no)
				(sheetname "")
			)
			(fill
				(thermal_gap 0.5)
				(thermal_bridge_width 0.5)
				(island_removal_mode 0)
			)
			(polygon
				(pts
					(arc
						(start 123.881134 -71.500238)
						(mid 123.119134 -71.500238)
						(end 123.881134 -71.500238)
					)
				)
			)
		)
		(zone
			(layer "F.Cu")
			(hatch none 0.5)
			(connect_pads
				(clearance 0)
			)
			(min_thickness 0.25)
			(keepout
				(tracks allowed)
				(vias not_allowed)
				(pads allowed)
				(copperpour not_allowed)
				(footprints allowed)
			)
			(placement
				(enabled no)
				(sheetname "")
			)
			(fill
				(thermal_gap 0.5)
				(thermal_bridge_width 0.5)
				(island_removal_mode 0)
			)
			(polygon
				(pts
					(arc
						(start 123.881134 -70.50024)
						(mid 123.119134 -70.50024)
						(end 123.881134 -70.50024)
					)
				)
			)
		)
		(zone
			(layer "F.Cu")
			(hatch none 0.5)
			(connect_pads
				(clearance 0)
			)
			(min_thickness 0.25)
			(keepout
				(tracks allowed)
				(vias not_allowed)
				(pads allowed)
				(copperpour not_allowed)
				(footprints allowed)
			)
			(placement
				(enabled no)
				(sheetname "")
			)
			(fill
				(thermal_gap 0.5)
				(thermal_bridge_width 0.5)
				(island_removal_mode 0)
			)
			(polygon
				(pts
					(arc
						(start 123.881134 -69.500242)
						(mid 123.119134 -69.500242)
						(end 123.881134 -69.500242)
					)
				)
			)
		)
		(zone
			(layer "F.Cu")
			(hatch none 0.5)
			(connect_pads
				(clearance 0)
			)
			(min_thickness 0.25)
			(keepout
				(tracks allowed)
				(vias not_allowed)
				(pads allowed)
				(copperpour not_allowed)
				(footprints allowed)
			)
			(placement
				(enabled no)
				(sheetname "")
			)
			(fill
				(thermal_gap 0.5)
				(thermal_bridge_width 0.5)
				(island_removal_mode 0)
			)
			(polygon
				(pts
					(arc
						(start 123.881134 -68.500244)
						(mid 123.119134 -68.500244)
						(end 123.881134 -68.500244)
					)
				)
			)
		)
		(zone
			(layer "F.Cu")
			(hatch none 0.5)
			(connect_pads
				(clearance 0)
			)
			(min_thickness 0.25)
			(keepout
				(tracks allowed)
				(vias not_allowed)
				(pads allowed)
				(copperpour not_allowed)
				(footprints allowed)
			)
			(placement
				(enabled no)
				(sheetname "")
			)
			(fill
				(thermal_gap 0.5)
				(thermal_bridge_width 0.5)
				(island_removal_mode 0)
			)
			(polygon
				(pts
					(arc
						(start 123.881134 -67.500246)
						(mid 123.119134 -67.500246)
						(end 123.881134 -67.500246)
					)
				)
			)
		)
		(zone
			(layer "F.Cu")
			(hatch none 0.5)
			(connect_pads
				(clearance 0)
			)
			(min_thickness 0.25)
			(keepout
				(tracks allowed)
				(vias not_allowed)
				(pads allowed)
				(copperpour not_allowed)
				(footprints allowed)
			)
			(placement
				(enabled no)
				(sheetname "")
			)
			(fill
				(thermal_gap 0.5)
				(thermal_bridge_width 0.5)
				(island_removal_mode 0)
			)
			(polygon
				(pts
					(arc
						(start 123.881134 -66.499994)
						(mid 123.119134 -66.499994)
						(end 123.881134 -66.499994)
					)
				)
			)
		)
		(zone
			(layer "F.Cu")
			(hatch none 0.5)
			(connect_pads
				(clearance 0)
			)
			(min_thickness 0.25)
			(keepout
				(tracks allowed)
				(vias not_allowed)
				(pads allowed)
				(copperpour not_allowed)
				(footprints allowed)
			)
			(placement
				(enabled no)
				(sheetname "")
			)
			(fill
				(thermal_gap 0.5)
				(thermal_bridge_width 0.5)
				(island_removal_mode 0)
			)
			(polygon
				(pts
					(arc
						(start 123.881134 -65.499996)
						(mid 123.119134 -65.499996)
						(end 123.881134 -65.499996)
					)
				)
			)
		)
		(zone
			(layer "F.Cu")
			(hatch none 0.5)
			(connect_pads
				(clearance 0)
			)
			(min_thickness 0.25)
			(keepout
				(tracks allowed)
				(vias not_allowed)
				(pads allowed)
				(copperpour not_allowed)
				(footprints allowed)
			)
			(placement
				(enabled no)
				(sheetname "")
			)
			(fill
				(thermal_gap 0.5)
				(thermal_bridge_width 0.5)
				(island_removal_mode 0)
			)
			(polygon
				(pts
					(arc
						(start 123.881134 -64.499998)
						(mid 123.119134 -64.499998)
						(end 123.881134 -64.499998)
					)
				)
			)
		)
		(zone
			(layer "F.Cu")
			(hatch none 0.5)
			(connect_pads
				(clearance 0)
			)
			(min_thickness 0.25)
			(keepout
				(tracks allowed)
				(vias not_allowed)
				(pads allowed)
				(copperpour not_allowed)
				(footprints allowed)
			)
			(placement
				(enabled no)
				(sheetname "")
			)
			(fill
				(thermal_gap 0.5)
				(thermal_bridge_width 0.5)
				(island_removal_mode 0)
			)
			(polygon
				(pts
					(arc
						(start 123.881134 -63.5)
						(mid 123.119134 -63.5)
						(end 123.881134 -63.5)
					)
				)
			)
		)
		(zone
			(layer "F.Cu")
			(hatch none 0.5)
			(connect_pads
				(clearance 0)
			)
			(min_thickness 0.25)
			(keepout
				(tracks allowed)
				(vias not_allowed)
				(pads allowed)
				(copperpour not_allowed)
				(footprints allowed)
			)
			(placement
				(enabled no)
				(sheetname "")
			)
			(fill
				(thermal_gap 0.5)
				(thermal_bridge_width 0.5)
				(island_removal_mode 0)
			)
			(polygon
				(pts
					(arc
						(start 123.881134 -62.500002)
						(mid 123.119134 -62.500002)
						(end 123.881134 -62.500002)
					)
				)
			)
		)
		(zone
			(layer "F.Cu")
			(hatch none 0.5)
			(connect_pads
				(clearance 0)
			)
			(min_thickness 0.25)
			(keepout
				(tracks allowed)
				(vias not_allowed)
				(pads allowed)
				(copperpour not_allowed)
				(footprints allowed)
			)
			(placement
				(enabled no)
				(sheetname "")
			)
			(fill
				(thermal_gap 0.5)
				(thermal_bridge_width 0.5)
				(island_removal_mode 0)
			)
			(polygon
				(pts
					(arc
						(start 123.881134 -61.500004)
						(mid 123.119134 -61.500004)
						(end 123.881134 -61.500004)
					)
				)
			)
		)
		(zone
			(layer "F.Cu")
			(hatch none 0.5)
			(connect_pads
				(clearance 0)
			)
			(min_thickness 0.25)
			(keepout
				(tracks allowed)
				(vias not_allowed)
				(pads allowed)
				(copperpour not_allowed)
				(footprints allowed)
			)
			(placement
				(enabled no)
				(sheetname "")
			)
			(fill
				(thermal_gap 0.5)
				(thermal_bridge_width 0.5)
				(island_removal_mode 0)
			)
			(polygon
				(pts
					(arc
						(start 123.881134 -60.500006)
						(mid 123.119134 -60.500006)
						(end 123.881134 -60.500006)
					)
				)
			)
		)
		(zone
			(layer "F.Cu")
			(hatch none 0.5)
			(connect_pads
				(clearance 0)
			)
			(min_thickness 0.25)
			(keepout
				(tracks allowed)
				(vias not_allowed)
				(pads allowed)
				(copperpour not_allowed)
				(footprints allowed)
			)
			(placement
				(enabled no)
				(sheetname "")
			)
			(fill
				(thermal_gap 0.5)
				(thermal_bridge_width 0.5)
				(island_removal_mode 0)
			)
			(polygon
				(pts
					(arc
						(start 123.881134 -59.500008)
						(mid 123.119134 -59.500008)
						(end 123.881134 -59.500008)
					)
				)
			)
		)
		(zone
			(layer "F.Cu")
			(hatch none 0.5)
			(connect_pads
				(clearance 0)
			)
			(min_thickness 0.25)
			(keepout
				(tracks allowed)
				(vias not_allowed)
				(pads allowed)
				(copperpour not_allowed)
				(footprints allowed)
			)
			(placement
				(enabled no)
				(sheetname "")
			)
			(fill
				(thermal_gap 0.5)
				(thermal_bridge_width 0.5)
				(island_removal_mode 0)
			)
			(polygon
				(pts
					(arc
						(start 123.881134 -58.50001)
						(mid 123.119134 -58.50001)
						(end 123.881134 -58.50001)
					)
				)
			)
		)
		(zone
			(layer "F.Cu")
			(hatch none 0.5)
			(connect_pads
				(clearance 0)
			)
			(min_thickness 0.25)
			(keepout
				(tracks allowed)
				(vias not_allowed)
				(pads allowed)
				(copperpour not_allowed)
				(footprints allowed)
			)
			(placement
				(enabled no)
				(sheetname "")
			)
			(fill
				(thermal_gap 0.5)
				(thermal_bridge_width 0.5)
				(island_removal_mode 0)
			)
			(polygon
				(pts
					(arc
						(start 123.881134 -57.500012)
						(mid 123.119134 -57.500012)
						(end 123.881134 -57.500012)
					)
				)
			)
		)
		(zone
			(layer "F.Cu")
			(hatch none 0.5)
			(connect_pads
				(clearance 0)
			)
			(min_thickness 0.25)
			(keepout
				(tracks allowed)
				(vias not_allowed)
				(pads allowed)
				(copperpour not_allowed)
				(footprints allowed)
			)
			(placement
				(enabled no)
				(sheetname "")
			)
			(fill
				(thermal_gap 0.5)
				(thermal_bridge_width 0.5)
				(island_removal_mode 0)
			)
			(polygon
				(pts
					(arc
						(start 123.881134 -56.500014)
						(mid 123.119134 -56.500014)
						(end 123.881134 -56.500014)
					)
				)
			)
		)
		(zone
			(layer "F.Cu")
			(hatch none 0.5)
			(connect_pads
				(clearance 0)
			)
			(min_thickness 0.25)
			(keepout
				(tracks allowed)
				(vias not_allowed)
				(pads allowed)
				(copperpour not_allowed)
				(footprints allowed)
			)
			(placement
				(enabled no)
				(sheetname "")
			)
			(fill
				(thermal_gap 0.5)
				(thermal_bridge_width 0.5)
				(island_removal_mode 0)
			)
			(polygon
				(pts
					(arc
						(start 123.881134 -55.500016)
						(mid 123.119134 -55.500016)
						(end 123.881134 -55.500016)
					)
				)
			)
		)
		(zone
			(layer "F.Cu")
			(hatch none 0.5)
			(connect_pads
				(clearance 0)
			)
			(min_thickness 0.25)
			(keepout
				(tracks allowed)
				(vias not_allowed)
				(pads allowed)
				(copperpour not_allowed)
				(footprints allowed)
			)
			(placement
				(enabled no)
				(sheetname "")
			)
			(fill
				(thermal_gap 0.5)
				(thermal_bridge_width 0.5)
				(island_removal_mode 0)
			)
			(polygon
				(pts
					(arc
						(start 123.881134 -54.500018)
						(mid 123.119134 -54.500018)
						(end 123.881134 -54.500018)
					)
				)
			)
		)
		(zone
			(layer "F.Cu")
			(hatch none 0.5)
			(connect_pads
				(clearance 0)
			)
			(min_thickness 0.25)
			(keepout
				(tracks allowed)
				(vias not_allowed)
				(pads allowed)
				(copperpour not_allowed)
				(footprints allowed)
			)
			(placement
				(enabled no)
				(sheetname "")
			)
			(fill
				(thermal_gap 0.5)
				(thermal_bridge_width 0.5)
				(island_removal_mode 0)
			)
			(polygon
				(pts
					(arc
						(start 123.881134 -53.50002)
						(mid 123.119134 -53.50002)
						(end 123.881134 -53.50002)
					)
				)
			)
		)
		(zone
			(layer "F.Cu")
			(hatch none 0.5)
			(connect_pads
				(clearance 0)
			)
			(min_thickness 0.25)
			(keepout
				(tracks allowed)
				(vias not_allowed)
				(pads allowed)
				(copperpour not_allowed)
				(footprints allowed)
			)
			(placement
				(enabled no)
				(sheetname "")
			)
			(fill
				(thermal_gap 0.5)
				(thermal_bridge_width 0.5)
				(island_removal_mode 0)
			)
			(polygon
				(pts
					(arc
						(start 123.881134 -52.500022)
						(mid 123.119134 -52.500022)
						(end 123.881134 -52.500022)
					)
				)
			)
		)
		(zone
			(layer "F.Cu")
			(hatch none 0.5)
			(connect_pads
				(clearance 0)
			)
			(min_thickness 0.25)
			(keepout
				(tracks allowed)
				(vias not_allowed)
				(pads allowed)
				(copperpour not_allowed)
				(footprints allowed)
			)
			(placement
				(enabled no)
				(sheetname "")
			)
			(fill
				(thermal_gap 0.5)
				(thermal_bridge_width 0.5)
				(island_removal_mode 0)
			)
			(polygon
				(pts
					(arc
						(start 123.881134 -51.500024)
						(mid 123.119134 -51.500024)
						(end 123.881134 -51.500024)
					)
				)
			)
		)
		(zone
			(layer "F.Cu")
			(hatch none 0.5)
			(connect_pads
				(clearance 0)
			)
			(min_thickness 0.25)
			(keepout
				(tracks allowed)
				(vias not_allowed)
				(pads allowed)
				(copperpour not_allowed)
				(footprints allowed)
			)
			(placement
				(enabled no)
				(sheetname "")
			)
			(fill
				(thermal_gap 0.5)
				(thermal_bridge_width 0.5)
				(island_removal_mode 0)
			)
			(polygon
				(pts
					(arc
						(start 124.881132 -82.500216)
						(mid 124.119132 -82.500216)
						(end 124.881132 -82.500216)
					)
				)
			)
		)
		(zone
			(layer "F.Cu")
			(hatch none 0.5)
			(connect_pads
				(clearance 0)
			)
			(min_thickness 0.25)
			(keepout
				(tracks allowed)
				(vias not_allowed)
				(pads allowed)
				(copperpour not_allowed)
				(footprints allowed)
			)
			(placement
				(enabled no)
				(sheetname "")
			)
			(fill
				(thermal_gap 0.5)
				(thermal_bridge_width 0.5)
				(island_removal_mode 0)
			)
			(polygon
				(pts
					(arc
						(start 124.881132 -81.500218)
						(mid 124.119132 -81.500218)
						(end 124.881132 -81.500218)
					)
				)
			)
		)
		(zone
			(layer "F.Cu")
			(hatch none 0.5)
			(connect_pads
				(clearance 0)
			)
			(min_thickness 0.25)
			(keepout
				(tracks allowed)
				(vias not_allowed)
				(pads allowed)
				(copperpour not_allowed)
				(footprints allowed)
			)
			(placement
				(enabled no)
				(sheetname "")
			)
			(fill
				(thermal_gap 0.5)
				(thermal_bridge_width 0.5)
				(island_removal_mode 0)
			)
			(polygon
				(pts
					(arc
						(start 124.881132 -80.50022)
						(mid 124.119132 -80.50022)
						(end 124.881132 -80.50022)
					)
				)
			)
		)
		(zone
			(layer "F.Cu")
			(hatch none 0.5)
			(connect_pads
				(clearance 0)
			)
			(min_thickness 0.25)
			(keepout
				(tracks allowed)
				(vias not_allowed)
				(pads allowed)
				(copperpour not_allowed)
				(footprints allowed)
			)
			(placement
				(enabled no)
				(sheetname "")
			)
			(fill
				(thermal_gap 0.5)
				(thermal_bridge_width 0.5)
				(island_removal_mode 0)
			)
			(polygon
				(pts
					(arc
						(start 124.881132 -79.500222)
						(mid 124.119132 -79.500222)
						(end 124.881132 -79.500222)
					)
				)
			)
		)
		(zone
			(layer "F.Cu")
			(hatch none 0.5)
			(connect_pads
				(clearance 0)
			)
			(min_thickness 0.25)
			(keepout
				(tracks allowed)
				(vias not_allowed)
				(pads allowed)
				(copperpour not_allowed)
				(footprints allowed)
			)
			(placement
				(enabled no)
				(sheetname "")
			)
			(fill
				(thermal_gap 0.5)
				(thermal_bridge_width 0.5)
				(island_removal_mode 0)
			)
			(polygon
				(pts
					(arc
						(start 124.881132 -78.500224)
						(mid 124.119132 -78.500224)
						(end 124.881132 -78.500224)
					)
				)
			)
		)
		(zone
			(layer "F.Cu")
			(hatch none 0.5)
			(connect_pads
				(clearance 0)
			)
			(min_thickness 0.25)
			(keepout
				(tracks allowed)
				(vias not_allowed)
				(pads allowed)
				(copperpour not_allowed)
				(footprints allowed)
			)
			(placement
				(enabled no)
				(sheetname "")
			)
			(fill
				(thermal_gap 0.5)
				(thermal_bridge_width 0.5)
				(island_removal_mode 0)
			)
			(polygon
				(pts
					(arc
						(start 124.881132 -77.500226)
						(mid 124.119132 -77.500226)
						(end 124.881132 -77.500226)
					)
				)
			)
		)
		(zone
			(layer "F.Cu")
			(hatch none 0.5)
			(connect_pads
				(clearance 0)
			)
			(min_thickness 0.25)
			(keepout
				(tracks allowed)
				(vias not_allowed)
				(pads allowed)
				(copperpour not_allowed)
				(footprints allowed)
			)
			(placement
				(enabled no)
				(sheetname "")
			)
			(fill
				(thermal_gap 0.5)
				(thermal_bridge_width 0.5)
				(island_removal_mode 0)
			)
			(polygon
				(pts
					(arc
						(start 124.881132 -76.500228)
						(mid 124.119132 -76.500228)
						(end 124.881132 -76.500228)
					)
				)
			)
		)
		(zone
			(layer "F.Cu")
			(hatch none 0.5)
			(connect_pads
				(clearance 0)
			)
			(min_thickness 0.25)
			(keepout
				(tracks allowed)
				(vias not_allowed)
				(pads allowed)
				(copperpour not_allowed)
				(footprints allowed)
			)
			(placement
				(enabled no)
				(sheetname "")
			)
			(fill
				(thermal_gap 0.5)
				(thermal_bridge_width 0.5)
				(island_removal_mode 0)
			)
			(polygon
				(pts
					(arc
						(start 124.881132 -75.50023)
						(mid 124.119132 -75.50023)
						(end 124.881132 -75.50023)
					)
				)
			)
		)
		(zone
			(layer "F.Cu")
			(hatch none 0.5)
			(connect_pads
				(clearance 0)
			)
			(min_thickness 0.25)
			(keepout
				(tracks allowed)
				(vias not_allowed)
				(pads allowed)
				(copperpour not_allowed)
				(footprints allowed)
			)
			(placement
				(enabled no)
				(sheetname "")
			)
			(fill
				(thermal_gap 0.5)
				(thermal_bridge_width 0.5)
				(island_removal_mode 0)
			)
			(polygon
				(pts
					(arc
						(start 124.881132 -74.500232)
						(mid 124.119132 -74.500232)
						(end 124.881132 -74.500232)
					)
				)
			)
		)
		(zone
			(layer "F.Cu")
			(hatch none 0.5)
			(connect_pads
				(clearance 0)
			)
			(min_thickness 0.25)
			(keepout
				(tracks allowed)
				(vias not_allowed)
				(pads allowed)
				(copperpour not_allowed)
				(footprints allowed)
			)
			(placement
				(enabled no)
				(sheetname "")
			)
			(fill
				(thermal_gap 0.5)
				(thermal_bridge_width 0.5)
				(island_removal_mode 0)
			)
			(polygon
				(pts
					(arc
						(start 124.881132 -73.500234)
						(mid 124.119132 -73.500234)
						(end 124.881132 -73.500234)
					)
				)
			)
		)
		(zone
			(layer "F.Cu")
			(hatch none 0.5)
			(connect_pads
				(clearance 0)
			)
			(min_thickness 0.25)
			(keepout
				(tracks allowed)
				(vias not_allowed)
				(pads allowed)
				(copperpour not_allowed)
				(footprints allowed)
			)
			(placement
				(enabled no)
				(sheetname "")
			)
			(fill
				(thermal_gap 0.5)
				(thermal_bridge_width 0.5)
				(island_removal_mode 0)
			)
			(polygon
				(pts
					(arc
						(start 124.881132 -72.500236)
						(mid 124.119132 -72.500236)
						(end 124.881132 -72.500236)
					)
				)
			)
		)
		(zone
			(layer "F.Cu")
			(hatch none 0.5)
			(connect_pads
				(clearance 0)
			)
			(min_thickness 0.25)
			(keepout
				(tracks allowed)
				(vias not_allowed)
				(pads allowed)
				(copperpour not_allowed)
				(footprints allowed)
			)
			(placement
				(enabled no)
				(sheetname "")
			)
			(fill
				(thermal_gap 0.5)
				(thermal_bridge_width 0.5)
				(island_removal_mode 0)
			)
			(polygon
				(pts
					(arc
						(start 124.881132 -71.500238)
						(mid 124.119132 -71.500238)
						(end 124.881132 -71.500238)
					)
				)
			)
		)
		(zone
			(layer "F.Cu")
			(hatch none 0.5)
			(connect_pads
				(clearance 0)
			)
			(min_thickness 0.25)
			(keepout
				(tracks allowed)
				(vias not_allowed)
				(pads allowed)
				(copperpour not_allowed)
				(footprints allowed)
			)
			(placement
				(enabled no)
				(sheetname "")
			)
			(fill
				(thermal_gap 0.5)
				(thermal_bridge_width 0.5)
				(island_removal_mode 0)
			)
			(polygon
				(pts
					(arc
						(start 124.881132 -70.50024)
						(mid 124.119132 -70.50024)
						(end 124.881132 -70.50024)
					)
				)
			)
		)
		(zone
			(layer "F.Cu")
			(hatch none 0.5)
			(connect_pads
				(clearance 0)
			)
			(min_thickness 0.25)
			(keepout
				(tracks allowed)
				(vias not_allowed)
				(pads allowed)
				(copperpour not_allowed)
				(footprints allowed)
			)
			(placement
				(enabled no)
				(sheetname "")
			)
			(fill
				(thermal_gap 0.5)
				(thermal_bridge_width 0.5)
				(island_removal_mode 0)
			)
			(polygon
				(pts
					(arc
						(start 124.881132 -69.500242)
						(mid 124.119132 -69.500242)
						(end 124.881132 -69.500242)
					)
				)
			)
		)
		(zone
			(layer "F.Cu")
			(hatch none 0.5)
			(connect_pads
				(clearance 0)
			)
			(min_thickness 0.25)
			(keepout
				(tracks allowed)
				(vias not_allowed)
				(pads allowed)
				(copperpour not_allowed)
				(footprints allowed)
			)
			(placement
				(enabled no)
				(sheetname "")
			)
			(fill
				(thermal_gap 0.5)
				(thermal_bridge_width 0.5)
				(island_removal_mode 0)
			)
			(polygon
				(pts
					(arc
						(start 124.881132 -68.500244)
						(mid 124.119132 -68.500244)
						(end 124.881132 -68.500244)
					)
				)
			)
		)
		(zone
			(layer "F.Cu")
			(hatch none 0.5)
			(connect_pads
				(clearance 0)
			)
			(min_thickness 0.25)
			(keepout
				(tracks allowed)
				(vias not_allowed)
				(pads allowed)
				(copperpour not_allowed)
				(footprints allowed)
			)
			(placement
				(enabled no)
				(sheetname "")
			)
			(fill
				(thermal_gap 0.5)
				(thermal_bridge_width 0.5)
				(island_removal_mode 0)
			)
			(polygon
				(pts
					(arc
						(start 124.881132 -67.500246)
						(mid 124.119132 -67.500246)
						(end 124.881132 -67.500246)
					)
				)
			)
		)
		(zone
			(layer "F.Cu")
			(hatch none 0.5)
			(connect_pads
				(clearance 0)
			)
			(min_thickness 0.25)
			(keepout
				(tracks allowed)
				(vias not_allowed)
				(pads allowed)
				(copperpour not_allowed)
				(footprints allowed)
			)
			(placement
				(enabled no)
				(sheetname "")
			)
			(fill
				(thermal_gap 0.5)
				(thermal_bridge_width 0.5)
				(island_removal_mode 0)
			)
			(polygon
				(pts
					(arc
						(start 124.881132 -66.499994)
						(mid 124.119132 -66.499994)
						(end 124.881132 -66.499994)
					)
				)
			)
		)
		(zone
			(layer "F.Cu")
			(hatch none 0.5)
			(connect_pads
				(clearance 0)
			)
			(min_thickness 0.25)
			(keepout
				(tracks allowed)
				(vias not_allowed)
				(pads allowed)
				(copperpour not_allowed)
				(footprints allowed)
			)
			(placement
				(enabled no)
				(sheetname "")
			)
			(fill
				(thermal_gap 0.5)
				(thermal_bridge_width 0.5)
				(island_removal_mode 0)
			)
			(polygon
				(pts
					(arc
						(start 124.881132 -65.499996)
						(mid 124.119132 -65.499996)
						(end 124.881132 -65.499996)
					)
				)
			)
		)
		(zone
			(layer "F.Cu")
			(hatch none 0.5)
			(connect_pads
				(clearance 0)
			)
			(min_thickness 0.25)
			(keepout
				(tracks allowed)
				(vias not_allowed)
				(pads allowed)
				(copperpour not_allowed)
				(footprints allowed)
			)
			(placement
				(enabled no)
				(sheetname "")
			)
			(fill
				(thermal_gap 0.5)
				(thermal_bridge_width 0.5)
				(island_removal_mode 0)
			)
			(polygon
				(pts
					(arc
						(start 124.881132 -64.499998)
						(mid 124.119132 -64.499998)
						(end 124.881132 -64.499998)
					)
				)
			)
		)
		(zone
			(layer "F.Cu")
			(hatch none 0.5)
			(connect_pads
				(clearance 0)
			)
			(min_thickness 0.25)
			(keepout
				(tracks allowed)
				(vias not_allowed)
				(pads allowed)
				(copperpour not_allowed)
				(footprints allowed)
			)
			(placement
				(enabled no)
				(sheetname "")
			)
			(fill
				(thermal_gap 0.5)
				(thermal_bridge_width 0.5)
				(island_removal_mode 0)
			)
			(polygon
				(pts
					(arc
						(start 124.881132 -63.5)
						(mid 124.119132 -63.5)
						(end 124.881132 -63.5)
					)
				)
			)
		)
		(zone
			(layer "F.Cu")
			(hatch none 0.5)
			(connect_pads
				(clearance 0)
			)
			(min_thickness 0.25)
			(keepout
				(tracks allowed)
				(vias not_allowed)
				(pads allowed)
				(copperpour not_allowed)
				(footprints allowed)
			)
			(placement
				(enabled no)
				(sheetname "")
			)
			(fill
				(thermal_gap 0.5)
				(thermal_bridge_width 0.5)
				(island_removal_mode 0)
			)
			(polygon
				(pts
					(arc
						(start 124.881132 -62.500002)
						(mid 124.119132 -62.500002)
						(end 124.881132 -62.500002)
					)
				)
			)
		)
		(zone
			(layer "F.Cu")
			(hatch none 0.5)
			(connect_pads
				(clearance 0)
			)
			(min_thickness 0.25)
			(keepout
				(tracks allowed)
				(vias not_allowed)
				(pads allowed)
				(copperpour not_allowed)
				(footprints allowed)
			)
			(placement
				(enabled no)
				(sheetname "")
			)
			(fill
				(thermal_gap 0.5)
				(thermal_bridge_width 0.5)
				(island_removal_mode 0)
			)
			(polygon
				(pts
					(arc
						(start 124.881132 -61.500004)
						(mid 124.119132 -61.500004)
						(end 124.881132 -61.500004)
					)
				)
			)
		)
		(zone
			(layer "F.Cu")
			(hatch none 0.5)
			(connect_pads
				(clearance 0)
			)
			(min_thickness 0.25)
			(keepout
				(tracks allowed)
				(vias not_allowed)
				(pads allowed)
				(copperpour not_allowed)
				(footprints allowed)
			)
			(placement
				(enabled no)
				(sheetname "")
			)
			(fill
				(thermal_gap 0.5)
				(thermal_bridge_width 0.5)
				(island_removal_mode 0)
			)
			(polygon
				(pts
					(arc
						(start 124.881132 -60.500006)
						(mid 124.119132 -60.500006)
						(end 124.881132 -60.500006)
					)
				)
			)
		)
		(zone
			(layer "F.Cu")
			(hatch none 0.5)
			(connect_pads
				(clearance 0)
			)
			(min_thickness 0.25)
			(keepout
				(tracks allowed)
				(vias not_allowed)
				(pads allowed)
				(copperpour not_allowed)
				(footprints allowed)
			)
			(placement
				(enabled no)
				(sheetname "")
			)
			(fill
				(thermal_gap 0.5)
				(thermal_bridge_width 0.5)
				(island_removal_mode 0)
			)
			(polygon
				(pts
					(arc
						(start 124.881132 -59.500008)
						(mid 124.119132 -59.500008)
						(end 124.881132 -59.500008)
					)
				)
			)
		)
		(zone
			(layer "F.Cu")
			(hatch none 0.5)
			(connect_pads
				(clearance 0)
			)
			(min_thickness 0.25)
			(keepout
				(tracks allowed)
				(vias not_allowed)
				(pads allowed)
				(copperpour not_allowed)
				(footprints allowed)
			)
			(placement
				(enabled no)
				(sheetname "")
			)
			(fill
				(thermal_gap 0.5)
				(thermal_bridge_width 0.5)
				(island_removal_mode 0)
			)
			(polygon
				(pts
					(arc
						(start 124.881132 -58.50001)
						(mid 124.119132 -58.50001)
						(end 124.881132 -58.50001)
					)
				)
			)
		)
		(zone
			(layer "F.Cu")
			(hatch none 0.5)
			(connect_pads
				(clearance 0)
			)
			(min_thickness 0.25)
			(keepout
				(tracks allowed)
				(vias not_allowed)
				(pads allowed)
				(copperpour not_allowed)
				(footprints allowed)
			)
			(placement
				(enabled no)
				(sheetname "")
			)
			(fill
				(thermal_gap 0.5)
				(thermal_bridge_width 0.5)
				(island_removal_mode 0)
			)
			(polygon
				(pts
					(arc
						(start 124.881132 -57.500012)
						(mid 124.119132 -57.500012)
						(end 124.881132 -57.500012)
					)
				)
			)
		)
		(zone
			(layer "F.Cu")
			(hatch none 0.5)
			(connect_pads
				(clearance 0)
			)
			(min_thickness 0.25)
			(keepout
				(tracks allowed)
				(vias not_allowed)
				(pads allowed)
				(copperpour not_allowed)
				(footprints allowed)
			)
			(placement
				(enabled no)
				(sheetname "")
			)
			(fill
				(thermal_gap 0.5)
				(thermal_bridge_width 0.5)
				(island_removal_mode 0)
			)
			(polygon
				(pts
					(arc
						(start 124.881132 -56.500014)
						(mid 124.119132 -56.500014)
						(end 124.881132 -56.500014)
					)
				)
			)
		)
		(zone
			(layer "F.Cu")
			(hatch none 0.5)
			(connect_pads
				(clearance 0)
			)
			(min_thickness 0.25)
			(keepout
				(tracks allowed)
				(vias not_allowed)
				(pads allowed)
				(copperpour not_allowed)
				(footprints allowed)
			)
			(placement
				(enabled no)
				(sheetname "")
			)
			(fill
				(thermal_gap 0.5)
				(thermal_bridge_width 0.5)
				(island_removal_mode 0)
			)
			(polygon
				(pts
					(arc
						(start 124.881132 -55.500016)
						(mid 124.119132 -55.500016)
						(end 124.881132 -55.500016)
					)
				)
			)
		)
		(zone
			(layer "F.Cu")
			(hatch none 0.5)
			(connect_pads
				(clearance 0)
			)
			(min_thickness 0.25)
			(keepout
				(tracks allowed)
				(vias not_allowed)
				(pads allowed)
				(copperpour not_allowed)
				(footprints allowed)
			)
			(placement
				(enabled no)
				(sheetname "")
			)
			(fill
				(thermal_gap 0.5)
				(thermal_bridge_width 0.5)
				(island_removal_mode 0)
			)
			(polygon
				(pts
					(arc
						(start 124.881132 -54.500018)
						(mid 124.119132 -54.500018)
						(end 124.881132 -54.500018)
					)
				)
			)
		)
		(zone
			(layer "F.Cu")
			(hatch none 0.5)
			(connect_pads
				(clearance 0)
			)
			(min_thickness 0.25)
			(keepout
				(tracks allowed)
				(vias not_allowed)
				(pads allowed)
				(copperpour not_allowed)
				(footprints allowed)
			)
			(placement
				(enabled no)
				(sheetname "")
			)
			(fill
				(thermal_gap 0.5)
				(thermal_bridge_width 0.5)
				(island_removal_mode 0)
			)
			(polygon
				(pts
					(arc
						(start 124.881132 -53.50002)
						(mid 124.119132 -53.50002)
						(end 124.881132 -53.50002)
					)
				)
			)
		)
		(zone
			(layer "F.Cu")
			(hatch none 0.5)
			(connect_pads
				(clearance 0)
			)
			(min_thickness 0.25)
			(keepout
				(tracks allowed)
				(vias not_allowed)
				(pads allowed)
				(copperpour not_allowed)
				(footprints allowed)
			)
			(placement
				(enabled no)
				(sheetname "")
			)
			(fill
				(thermal_gap 0.5)
				(thermal_bridge_width 0.5)
				(island_removal_mode 0)
			)
			(polygon
				(pts
					(arc
						(start 124.881132 -52.500022)
						(mid 124.119132 -52.500022)
						(end 124.881132 -52.500022)
					)
				)
			)
		)
		(zone
			(layer "F.Cu")
			(hatch none 0.5)
			(connect_pads
				(clearance 0)
			)
			(min_thickness 0.25)
			(keepout
				(tracks allowed)
				(vias not_allowed)
				(pads allowed)
				(copperpour not_allowed)
				(footprints allowed)
			)
			(placement
				(enabled no)
				(sheetname "")
			)
			(fill
				(thermal_gap 0.5)
				(thermal_bridge_width 0.5)
				(island_removal_mode 0)
			)
			(polygon
				(pts
					(arc
						(start 124.881132 -51.500024)
						(mid 124.119132 -51.500024)
						(end 124.881132 -51.500024)
					)
				)
			)
		)
		(zone
			(layer "F.Cu")
			(hatch none 0.5)
			(connect_pads
				(clearance 0)
			)
			(min_thickness 0.25)
			(keepout
				(tracks allowed)
				(vias not_allowed)
				(pads allowed)
				(copperpour not_allowed)
				(footprints allowed)
			)
			(placement
				(enabled no)
				(sheetname "")
			)
			(fill
				(thermal_gap 0.5)
				(thermal_bridge_width 0.5)
				(island_removal_mode 0)
			)
			(polygon
				(pts
					(arc
						(start 125.88113 -82.500216)
						(mid 125.11913 -82.500216)
						(end 125.88113 -82.500216)
					)
				)
			)
		)
		(zone
			(layer "F.Cu")
			(hatch none 0.5)
			(connect_pads
				(clearance 0)
			)
			(min_thickness 0.25)
			(keepout
				(tracks allowed)
				(vias not_allowed)
				(pads allowed)
				(copperpour not_allowed)
				(footprints allowed)
			)
			(placement
				(enabled no)
				(sheetname "")
			)
			(fill
				(thermal_gap 0.5)
				(thermal_bridge_width 0.5)
				(island_removal_mode 0)
			)
			(polygon
				(pts
					(arc
						(start 125.88113 -81.500218)
						(mid 125.11913 -81.500218)
						(end 125.88113 -81.500218)
					)
				)
			)
		)
		(zone
			(layer "F.Cu")
			(hatch none 0.5)
			(connect_pads
				(clearance 0)
			)
			(min_thickness 0.25)
			(keepout
				(tracks allowed)
				(vias not_allowed)
				(pads allowed)
				(copperpour not_allowed)
				(footprints allowed)
			)
			(placement
				(enabled no)
				(sheetname "")
			)
			(fill
				(thermal_gap 0.5)
				(thermal_bridge_width 0.5)
				(island_removal_mode 0)
			)
			(polygon
				(pts
					(arc
						(start 125.88113 -80.50022)
						(mid 125.11913 -80.50022)
						(end 125.88113 -80.50022)
					)
				)
			)
		)
		(zone
			(layer "F.Cu")
			(hatch none 0.5)
			(connect_pads
				(clearance 0)
			)
			(min_thickness 0.25)
			(keepout
				(tracks allowed)
				(vias not_allowed)
				(pads allowed)
				(copperpour not_allowed)
				(footprints allowed)
			)
			(placement
				(enabled no)
				(sheetname "")
			)
			(fill
				(thermal_gap 0.5)
				(thermal_bridge_width 0.5)
				(island_removal_mode 0)
			)
			(polygon
				(pts
					(arc
						(start 125.88113 -79.500222)
						(mid 125.11913 -79.500222)
						(end 125.88113 -79.500222)
					)
				)
			)
		)
		(zone
			(layer "F.Cu")
			(hatch none 0.5)
			(connect_pads
				(clearance 0)
			)
			(min_thickness 0.25)
			(keepout
				(tracks allowed)
				(vias not_allowed)
				(pads allowed)
				(copperpour not_allowed)
				(footprints allowed)
			)
			(placement
				(enabled no)
				(sheetname "")
			)
			(fill
				(thermal_gap 0.5)
				(thermal_bridge_width 0.5)
				(island_removal_mode 0)
			)
			(polygon
				(pts
					(arc
						(start 125.88113 -78.500224)
						(mid 125.11913 -78.500224)
						(end 125.88113 -78.500224)
					)
				)
			)
		)
		(zone
			(layer "F.Cu")
			(hatch none 0.5)
			(connect_pads
				(clearance 0)
			)
			(min_thickness 0.25)
			(keepout
				(tracks allowed)
				(vias not_allowed)
				(pads allowed)
				(copperpour not_allowed)
				(footprints allowed)
			)
			(placement
				(enabled no)
				(sheetname "")
			)
			(fill
				(thermal_gap 0.5)
				(thermal_bridge_width 0.5)
				(island_removal_mode 0)
			)
			(polygon
				(pts
					(arc
						(start 125.88113 -77.500226)
						(mid 125.11913 -77.500226)
						(end 125.88113 -77.500226)
					)
				)
			)
		)
		(zone
			(layer "F.Cu")
			(hatch none 0.5)
			(connect_pads
				(clearance 0)
			)
			(min_thickness 0.25)
			(keepout
				(tracks allowed)
				(vias not_allowed)
				(pads allowed)
				(copperpour not_allowed)
				(footprints allowed)
			)
			(placement
				(enabled no)
				(sheetname "")
			)
			(fill
				(thermal_gap 0.5)
				(thermal_bridge_width 0.5)
				(island_removal_mode 0)
			)
			(polygon
				(pts
					(arc
						(start 125.88113 -76.500228)
						(mid 125.11913 -76.500228)
						(end 125.88113 -76.500228)
					)
				)
			)
		)
		(zone
			(layer "F.Cu")
			(hatch none 0.5)
			(connect_pads
				(clearance 0)
			)
			(min_thickness 0.25)
			(keepout
				(tracks allowed)
				(vias not_allowed)
				(pads allowed)
				(copperpour not_allowed)
				(footprints allowed)
			)
			(placement
				(enabled no)
				(sheetname "")
			)
			(fill
				(thermal_gap 0.5)
				(thermal_bridge_width 0.5)
				(island_removal_mode 0)
			)
			(polygon
				(pts
					(arc
						(start 125.88113 -75.50023)
						(mid 125.11913 -75.50023)
						(end 125.88113 -75.50023)
					)
				)
			)
		)
		(zone
			(layer "F.Cu")
			(hatch none 0.5)
			(connect_pads
				(clearance 0)
			)
			(min_thickness 0.25)
			(keepout
				(tracks allowed)
				(vias not_allowed)
				(pads allowed)
				(copperpour not_allowed)
				(footprints allowed)
			)
			(placement
				(enabled no)
				(sheetname "")
			)
			(fill
				(thermal_gap 0.5)
				(thermal_bridge_width 0.5)
				(island_removal_mode 0)
			)
			(polygon
				(pts
					(arc
						(start 125.88113 -74.500232)
						(mid 125.11913 -74.500232)
						(end 125.88113 -74.500232)
					)
				)
			)
		)
		(zone
			(layer "F.Cu")
			(hatch none 0.5)
			(connect_pads
				(clearance 0)
			)
			(min_thickness 0.25)
			(keepout
				(tracks allowed)
				(vias not_allowed)
				(pads allowed)
				(copperpour not_allowed)
				(footprints allowed)
			)
			(placement
				(enabled no)
				(sheetname "")
			)
			(fill
				(thermal_gap 0.5)
				(thermal_bridge_width 0.5)
				(island_removal_mode 0)
			)
			(polygon
				(pts
					(arc
						(start 125.88113 -73.500234)
						(mid 125.11913 -73.500234)
						(end 125.88113 -73.500234)
					)
				)
			)
		)
		(zone
			(layer "F.Cu")
			(hatch none 0.5)
			(connect_pads
				(clearance 0)
			)
			(min_thickness 0.25)
			(keepout
				(tracks allowed)
				(vias not_allowed)
				(pads allowed)
				(copperpour not_allowed)
				(footprints allowed)
			)
			(placement
				(enabled no)
				(sheetname "")
			)
			(fill
				(thermal_gap 0.5)
				(thermal_bridge_width 0.5)
				(island_removal_mode 0)
			)
			(polygon
				(pts
					(arc
						(start 125.88113 -72.500236)
						(mid 125.11913 -72.500236)
						(end 125.88113 -72.500236)
					)
				)
			)
		)
		(zone
			(layer "F.Cu")
			(hatch none 0.5)
			(connect_pads
				(clearance 0)
			)
			(min_thickness 0.25)
			(keepout
				(tracks allowed)
				(vias not_allowed)
				(pads allowed)
				(copperpour not_allowed)
				(footprints allowed)
			)
			(placement
				(enabled no)
				(sheetname "")
			)
			(fill
				(thermal_gap 0.5)
				(thermal_bridge_width 0.5)
				(island_removal_mode 0)
			)
			(polygon
				(pts
					(arc
						(start 125.88113 -71.500238)
						(mid 125.11913 -71.500238)
						(end 125.88113 -71.500238)
					)
				)
			)
		)
		(zone
			(layer "F.Cu")
			(hatch none 0.5)
			(connect_pads
				(clearance 0)
			)
			(min_thickness 0.25)
			(keepout
				(tracks allowed)
				(vias not_allowed)
				(pads allowed)
				(copperpour not_allowed)
				(footprints allowed)
			)
			(placement
				(enabled no)
				(sheetname "")
			)
			(fill
				(thermal_gap 0.5)
				(thermal_bridge_width 0.5)
				(island_removal_mode 0)
			)
			(polygon
				(pts
					(arc
						(start 125.88113 -70.50024)
						(mid 125.11913 -70.50024)
						(end 125.88113 -70.50024)
					)
				)
			)
		)
		(zone
			(layer "F.Cu")
			(hatch none 0.5)
			(connect_pads
				(clearance 0)
			)
			(min_thickness 0.25)
			(keepout
				(tracks allowed)
				(vias not_allowed)
				(pads allowed)
				(copperpour not_allowed)
				(footprints allowed)
			)
			(placement
				(enabled no)
				(sheetname "")
			)
			(fill
				(thermal_gap 0.5)
				(thermal_bridge_width 0.5)
				(island_removal_mode 0)
			)
			(polygon
				(pts
					(arc
						(start 125.88113 -69.500242)
						(mid 125.11913 -69.500242)
						(end 125.88113 -69.500242)
					)
				)
			)
		)
		(zone
			(layer "F.Cu")
			(hatch none 0.5)
			(connect_pads
				(clearance 0)
			)
			(min_thickness 0.25)
			(keepout
				(tracks allowed)
				(vias not_allowed)
				(pads allowed)
				(copperpour not_allowed)
				(footprints allowed)
			)
			(placement
				(enabled no)
				(sheetname "")
			)
			(fill
				(thermal_gap 0.5)
				(thermal_bridge_width 0.5)
				(island_removal_mode 0)
			)
			(polygon
				(pts
					(arc
						(start 125.88113 -68.500244)
						(mid 125.11913 -68.500244)
						(end 125.88113 -68.500244)
					)
				)
			)
		)
		(zone
			(layer "F.Cu")
			(hatch none 0.5)
			(connect_pads
				(clearance 0)
			)
			(min_thickness 0.25)
			(keepout
				(tracks allowed)
				(vias not_allowed)
				(pads allowed)
				(copperpour not_allowed)
				(footprints allowed)
			)
			(placement
				(enabled no)
				(sheetname "")
			)
			(fill
				(thermal_gap 0.5)
				(thermal_bridge_width 0.5)
				(island_removal_mode 0)
			)
			(polygon
				(pts
					(arc
						(start 125.88113 -67.500246)
						(mid 125.11913 -67.500246)
						(end 125.88113 -67.500246)
					)
				)
			)
		)
		(zone
			(layer "F.Cu")
			(hatch none 0.5)
			(connect_pads
				(clearance 0)
			)
			(min_thickness 0.25)
			(keepout
				(tracks allowed)
				(vias not_allowed)
				(pads allowed)
				(copperpour not_allowed)
				(footprints allowed)
			)
			(placement
				(enabled no)
				(sheetname "")
			)
			(fill
				(thermal_gap 0.5)
				(thermal_bridge_width 0.5)
				(island_removal_mode 0)
			)
			(polygon
				(pts
					(arc
						(start 125.88113 -66.499994)
						(mid 125.11913 -66.499994)
						(end 125.88113 -66.499994)
					)
				)
			)
		)
		(zone
			(layer "F.Cu")
			(hatch none 0.5)
			(connect_pads
				(clearance 0)
			)
			(min_thickness 0.25)
			(keepout
				(tracks allowed)
				(vias not_allowed)
				(pads allowed)
				(copperpour not_allowed)
				(footprints allowed)
			)
			(placement
				(enabled no)
				(sheetname "")
			)
			(fill
				(thermal_gap 0.5)
				(thermal_bridge_width 0.5)
				(island_removal_mode 0)
			)
			(polygon
				(pts
					(arc
						(start 125.88113 -65.499996)
						(mid 125.11913 -65.499996)
						(end 125.88113 -65.499996)
					)
				)
			)
		)
		(zone
			(layer "F.Cu")
			(hatch none 0.5)
			(connect_pads
				(clearance 0)
			)
			(min_thickness 0.25)
			(keepout
				(tracks allowed)
				(vias not_allowed)
				(pads allowed)
				(copperpour not_allowed)
				(footprints allowed)
			)
			(placement
				(enabled no)
				(sheetname "")
			)
			(fill
				(thermal_gap 0.5)
				(thermal_bridge_width 0.5)
				(island_removal_mode 0)
			)
			(polygon
				(pts
					(arc
						(start 125.88113 -64.499998)
						(mid 125.11913 -64.499998)
						(end 125.88113 -64.499998)
					)
				)
			)
		)
		(zone
			(layer "F.Cu")
			(hatch none 0.5)
			(connect_pads
				(clearance 0)
			)
			(min_thickness 0.25)
			(keepout
				(tracks allowed)
				(vias not_allowed)
				(pads allowed)
				(copperpour not_allowed)
				(footprints allowed)
			)
			(placement
				(enabled no)
				(sheetname "")
			)
			(fill
				(thermal_gap 0.5)
				(thermal_bridge_width 0.5)
				(island_removal_mode 0)
			)
			(polygon
				(pts
					(arc
						(start 125.88113 -63.5)
						(mid 125.11913 -63.5)
						(end 125.88113 -63.5)
					)
				)
			)
		)
		(zone
			(layer "F.Cu")
			(hatch none 0.5)
			(connect_pads
				(clearance 0)
			)
			(min_thickness 0.25)
			(keepout
				(tracks allowed)
				(vias not_allowed)
				(pads allowed)
				(copperpour not_allowed)
				(footprints allowed)
			)
			(placement
				(enabled no)
				(sheetname "")
			)
			(fill
				(thermal_gap 0.5)
				(thermal_bridge_width 0.5)
				(island_removal_mode 0)
			)
			(polygon
				(pts
					(arc
						(start 125.88113 -62.500002)
						(mid 125.11913 -62.500002)
						(end 125.88113 -62.500002)
					)
				)
			)
		)
		(zone
			(layer "F.Cu")
			(hatch none 0.5)
			(connect_pads
				(clearance 0)
			)
			(min_thickness 0.25)
			(keepout
				(tracks allowed)
				(vias not_allowed)
				(pads allowed)
				(copperpour not_allowed)
				(footprints allowed)
			)
			(placement
				(enabled no)
				(sheetname "")
			)
			(fill
				(thermal_gap 0.5)
				(thermal_bridge_width 0.5)
				(island_removal_mode 0)
			)
			(polygon
				(pts
					(arc
						(start 125.88113 -61.500004)
						(mid 125.11913 -61.500004)
						(end 125.88113 -61.500004)
					)
				)
			)
		)
		(zone
			(layer "F.Cu")
			(hatch none 0.5)
			(connect_pads
				(clearance 0)
			)
			(min_thickness 0.25)
			(keepout
				(tracks allowed)
				(vias not_allowed)
				(pads allowed)
				(copperpour not_allowed)
				(footprints allowed)
			)
			(placement
				(enabled no)
				(sheetname "")
			)
			(fill
				(thermal_gap 0.5)
				(thermal_bridge_width 0.5)
				(island_removal_mode 0)
			)
			(polygon
				(pts
					(arc
						(start 125.88113 -60.500006)
						(mid 125.11913 -60.500006)
						(end 125.88113 -60.500006)
					)
				)
			)
		)
		(zone
			(layer "F.Cu")
			(hatch none 0.5)
			(connect_pads
				(clearance 0)
			)
			(min_thickness 0.25)
			(keepout
				(tracks allowed)
				(vias not_allowed)
				(pads allowed)
				(copperpour not_allowed)
				(footprints allowed)
			)
			(placement
				(enabled no)
				(sheetname "")
			)
			(fill
				(thermal_gap 0.5)
				(thermal_bridge_width 0.5)
				(island_removal_mode 0)
			)
			(polygon
				(pts
					(arc
						(start 125.88113 -59.500008)
						(mid 125.11913 -59.500008)
						(end 125.88113 -59.500008)
					)
				)
			)
		)
		(zone
			(layer "F.Cu")
			(hatch none 0.5)
			(connect_pads
				(clearance 0)
			)
			(min_thickness 0.25)
			(keepout
				(tracks allowed)
				(vias not_allowed)
				(pads allowed)
				(copperpour not_allowed)
				(footprints allowed)
			)
			(placement
				(enabled no)
				(sheetname "")
			)
			(fill
				(thermal_gap 0.5)
				(thermal_bridge_width 0.5)
				(island_removal_mode 0)
			)
			(polygon
				(pts
					(arc
						(start 125.88113 -58.50001)
						(mid 125.11913 -58.50001)
						(end 125.88113 -58.50001)
					)
				)
			)
		)
		(zone
			(layer "F.Cu")
			(hatch none 0.5)
			(connect_pads
				(clearance 0)
			)
			(min_thickness 0.25)
			(keepout
				(tracks allowed)
				(vias not_allowed)
				(pads allowed)
				(copperpour not_allowed)
				(footprints allowed)
			)
			(placement
				(enabled no)
				(sheetname "")
			)
			(fill
				(thermal_gap 0.5)
				(thermal_bridge_width 0.5)
				(island_removal_mode 0)
			)
			(polygon
				(pts
					(arc
						(start 125.88113 -57.500012)
						(mid 125.11913 -57.500012)
						(end 125.88113 -57.500012)
					)
				)
			)
		)
		(zone
			(layer "F.Cu")
			(hatch none 0.5)
			(connect_pads
				(clearance 0)
			)
			(min_thickness 0.25)
			(keepout
				(tracks allowed)
				(vias not_allowed)
				(pads allowed)
				(copperpour not_allowed)
				(footprints allowed)
			)
			(placement
				(enabled no)
				(sheetname "")
			)
			(fill
				(thermal_gap 0.5)
				(thermal_bridge_width 0.5)
				(island_removal_mode 0)
			)
			(polygon
				(pts
					(arc
						(start 125.88113 -56.500014)
						(mid 125.11913 -56.500014)
						(end 125.88113 -56.500014)
					)
				)
			)
		)
		(zone
			(layer "F.Cu")
			(hatch none 0.5)
			(connect_pads
				(clearance 0)
			)
			(min_thickness 0.25)
			(keepout
				(tracks allowed)
				(vias not_allowed)
				(pads allowed)
				(copperpour not_allowed)
				(footprints allowed)
			)
			(placement
				(enabled no)
				(sheetname "")
			)
			(fill
				(thermal_gap 0.5)
				(thermal_bridge_width 0.5)
				(island_removal_mode 0)
			)
			(polygon
				(pts
					(arc
						(start 125.88113 -55.500016)
						(mid 125.11913 -55.500016)
						(end 125.88113 -55.500016)
					)
				)
			)
		)
		(zone
			(layer "F.Cu")
			(hatch none 0.5)
			(connect_pads
				(clearance 0)
			)
			(min_thickness 0.25)
			(keepout
				(tracks allowed)
				(vias not_allowed)
				(pads allowed)
				(copperpour not_allowed)
				(footprints allowed)
			)
			(placement
				(enabled no)
				(sheetname "")
			)
			(fill
				(thermal_gap 0.5)
				(thermal_bridge_width 0.5)
				(island_removal_mode 0)
			)
			(polygon
				(pts
					(arc
						(start 125.88113 -54.500018)
						(mid 125.11913 -54.500018)
						(end 125.88113 -54.500018)
					)
				)
			)
		)
		(zone
			(layer "F.Cu")
			(hatch none 0.5)
			(connect_pads
				(clearance 0)
			)
			(min_thickness 0.25)
			(keepout
				(tracks allowed)
				(vias not_allowed)
				(pads allowed)
				(copperpour not_allowed)
				(footprints allowed)
			)
			(placement
				(enabled no)
				(sheetname "")
			)
			(fill
				(thermal_gap 0.5)
				(thermal_bridge_width 0.5)
				(island_removal_mode 0)
			)
			(polygon
				(pts
					(arc
						(start 125.88113 -53.50002)
						(mid 125.11913 -53.50002)
						(end 125.88113 -53.50002)
					)
				)
			)
		)
		(zone
			(layer "F.Cu")
			(hatch none 0.5)
			(connect_pads
				(clearance 0)
			)
			(min_thickness 0.25)
			(keepout
				(tracks allowed)
				(vias not_allowed)
				(pads allowed)
				(copperpour not_allowed)
				(footprints allowed)
			)
			(placement
				(enabled no)
				(sheetname "")
			)
			(fill
				(thermal_gap 0.5)
				(thermal_bridge_width 0.5)
				(island_removal_mode 0)
			)
			(polygon
				(pts
					(arc
						(start 125.88113 -52.500022)
						(mid 125.11913 -52.500022)
						(end 125.88113 -52.500022)
					)
				)
			)
		)
		(zone
			(layer "F.Cu")
			(hatch none 0.5)
			(connect_pads
				(clearance 0)
			)
			(min_thickness 0.25)
			(keepout
				(tracks allowed)
				(vias not_allowed)
				(pads allowed)
				(copperpour not_allowed)
				(footprints allowed)
			)
			(placement
				(enabled no)
				(sheetname "")
			)
			(fill
				(thermal_gap 0.5)
				(thermal_bridge_width 0.5)
				(island_removal_mode 0)
			)
			(polygon
				(pts
					(arc
						(start 125.88113 -51.500024)
						(mid 125.11913 -51.500024)
						(end 125.88113 -51.500024)
					)
				)
			)
		)
		(zone
			(layer "F.Cu")
			(hatch none 0.5)
			(connect_pads
				(clearance 0)
			)
			(min_thickness 0.25)
			(keepout
				(tracks allowed)
				(vias not_allowed)
				(pads allowed)
				(copperpour not_allowed)
				(footprints allowed)
			)
			(placement
				(enabled no)
				(sheetname "")
			)
			(fill
				(thermal_gap 0.5)
				(thermal_bridge_width 0.5)
				(island_removal_mode 0)
			)
			(polygon
				(pts
					(arc
						(start 126.881128 -82.500216)
						(mid 126.119128 -82.500216)
						(end 126.881128 -82.500216)
					)
				)
			)
		)
		(zone
			(layer "F.Cu")
			(hatch none 0.5)
			(connect_pads
				(clearance 0)
			)
			(min_thickness 0.25)
			(keepout
				(tracks allowed)
				(vias not_allowed)
				(pads allowed)
				(copperpour not_allowed)
				(footprints allowed)
			)
			(placement
				(enabled no)
				(sheetname "")
			)
			(fill
				(thermal_gap 0.5)
				(thermal_bridge_width 0.5)
				(island_removal_mode 0)
			)
			(polygon
				(pts
					(arc
						(start 126.881128 -81.500218)
						(mid 126.119128 -81.500218)
						(end 126.881128 -81.500218)
					)
				)
			)
		)
		(zone
			(layer "F.Cu")
			(hatch none 0.5)
			(connect_pads
				(clearance 0)
			)
			(min_thickness 0.25)
			(keepout
				(tracks allowed)
				(vias not_allowed)
				(pads allowed)
				(copperpour not_allowed)
				(footprints allowed)
			)
			(placement
				(enabled no)
				(sheetname "")
			)
			(fill
				(thermal_gap 0.5)
				(thermal_bridge_width 0.5)
				(island_removal_mode 0)
			)
			(polygon
				(pts
					(arc
						(start 126.881128 -80.50022)
						(mid 126.119128 -80.50022)
						(end 126.881128 -80.50022)
					)
				)
			)
		)
		(zone
			(layer "F.Cu")
			(hatch none 0.5)
			(connect_pads
				(clearance 0)
			)
			(min_thickness 0.25)
			(keepout
				(tracks allowed)
				(vias not_allowed)
				(pads allowed)
				(copperpour not_allowed)
				(footprints allowed)
			)
			(placement
				(enabled no)
				(sheetname "")
			)
			(fill
				(thermal_gap 0.5)
				(thermal_bridge_width 0.5)
				(island_removal_mode 0)
			)
			(polygon
				(pts
					(arc
						(start 126.881128 -79.500222)
						(mid 126.119128 -79.500222)
						(end 126.881128 -79.500222)
					)
				)
			)
		)
		(zone
			(layer "F.Cu")
			(hatch none 0.5)
			(connect_pads
				(clearance 0)
			)
			(min_thickness 0.25)
			(keepout
				(tracks allowed)
				(vias not_allowed)
				(pads allowed)
				(copperpour not_allowed)
				(footprints allowed)
			)
			(placement
				(enabled no)
				(sheetname "")
			)
			(fill
				(thermal_gap 0.5)
				(thermal_bridge_width 0.5)
				(island_removal_mode 0)
			)
			(polygon
				(pts
					(arc
						(start 126.881128 -78.500224)
						(mid 126.119128 -78.500224)
						(end 126.881128 -78.500224)
					)
				)
			)
		)
		(zone
			(layer "F.Cu")
			(hatch none 0.5)
			(connect_pads
				(clearance 0)
			)
			(min_thickness 0.25)
			(keepout
				(tracks allowed)
				(vias not_allowed)
				(pads allowed)
				(copperpour not_allowed)
				(footprints allowed)
			)
			(placement
				(enabled no)
				(sheetname "")
			)
			(fill
				(thermal_gap 0.5)
				(thermal_bridge_width 0.5)
				(island_removal_mode 0)
			)
			(polygon
				(pts
					(arc
						(start 126.881128 -77.500226)
						(mid 126.119128 -77.500226)
						(end 126.881128 -77.500226)
					)
				)
			)
		)
		(zone
			(layer "F.Cu")
			(hatch none 0.5)
			(connect_pads
				(clearance 0)
			)
			(min_thickness 0.25)
			(keepout
				(tracks allowed)
				(vias not_allowed)
				(pads allowed)
				(copperpour not_allowed)
				(footprints allowed)
			)
			(placement
				(enabled no)
				(sheetname "")
			)
			(fill
				(thermal_gap 0.5)
				(thermal_bridge_width 0.5)
				(island_removal_mode 0)
			)
			(polygon
				(pts
					(arc
						(start 126.881128 -76.500228)
						(mid 126.119128 -76.500228)
						(end 126.881128 -76.500228)
					)
				)
			)
		)
		(zone
			(layer "F.Cu")
			(hatch none 0.5)
			(connect_pads
				(clearance 0)
			)
			(min_thickness 0.25)
			(keepout
				(tracks allowed)
				(vias not_allowed)
				(pads allowed)
				(copperpour not_allowed)
				(footprints allowed)
			)
			(placement
				(enabled no)
				(sheetname "")
			)
			(fill
				(thermal_gap 0.5)
				(thermal_bridge_width 0.5)
				(island_removal_mode 0)
			)
			(polygon
				(pts
					(arc
						(start 126.881128 -75.50023)
						(mid 126.119128 -75.50023)
						(end 126.881128 -75.50023)
					)
				)
			)
		)
		(zone
			(layer "F.Cu")
			(hatch none 0.5)
			(connect_pads
				(clearance 0)
			)
			(min_thickness 0.25)
			(keepout
				(tracks allowed)
				(vias not_allowed)
				(pads allowed)
				(copperpour not_allowed)
				(footprints allowed)
			)
			(placement
				(enabled no)
				(sheetname "")
			)
			(fill
				(thermal_gap 0.5)
				(thermal_bridge_width 0.5)
				(island_removal_mode 0)
			)
			(polygon
				(pts
					(arc
						(start 126.881128 -74.500232)
						(mid 126.119128 -74.500232)
						(end 126.881128 -74.500232)
					)
				)
			)
		)
		(zone
			(layer "F.Cu")
			(hatch none 0.5)
			(connect_pads
				(clearance 0)
			)
			(min_thickness 0.25)
			(keepout
				(tracks allowed)
				(vias not_allowed)
				(pads allowed)
				(copperpour not_allowed)
				(footprints allowed)
			)
			(placement
				(enabled no)
				(sheetname "")
			)
			(fill
				(thermal_gap 0.5)
				(thermal_bridge_width 0.5)
				(island_removal_mode 0)
			)
			(polygon
				(pts
					(arc
						(start 126.881128 -73.500234)
						(mid 126.119128 -73.500234)
						(end 126.881128 -73.500234)
					)
				)
			)
		)
		(zone
			(layer "F.Cu")
			(hatch none 0.5)
			(connect_pads
				(clearance 0)
			)
			(min_thickness 0.25)
			(keepout
				(tracks allowed)
				(vias not_allowed)
				(pads allowed)
				(copperpour not_allowed)
				(footprints allowed)
			)
			(placement
				(enabled no)
				(sheetname "")
			)
			(fill
				(thermal_gap 0.5)
				(thermal_bridge_width 0.5)
				(island_removal_mode 0)
			)
			(polygon
				(pts
					(arc
						(start 126.881128 -72.500236)
						(mid 126.119128 -72.500236)
						(end 126.881128 -72.500236)
					)
				)
			)
		)
		(zone
			(layer "F.Cu")
			(hatch none 0.5)
			(connect_pads
				(clearance 0)
			)
			(min_thickness 0.25)
			(keepout
				(tracks allowed)
				(vias not_allowed)
				(pads allowed)
				(copperpour not_allowed)
				(footprints allowed)
			)
			(placement
				(enabled no)
				(sheetname "")
			)
			(fill
				(thermal_gap 0.5)
				(thermal_bridge_width 0.5)
				(island_removal_mode 0)
			)
			(polygon
				(pts
					(arc
						(start 126.881128 -71.500238)
						(mid 126.119128 -71.500238)
						(end 126.881128 -71.500238)
					)
				)
			)
		)
		(zone
			(layer "F.Cu")
			(hatch none 0.5)
			(connect_pads
				(clearance 0)
			)
			(min_thickness 0.25)
			(keepout
				(tracks allowed)
				(vias not_allowed)
				(pads allowed)
				(copperpour not_allowed)
				(footprints allowed)
			)
			(placement
				(enabled no)
				(sheetname "")
			)
			(fill
				(thermal_gap 0.5)
				(thermal_bridge_width 0.5)
				(island_removal_mode 0)
			)
			(polygon
				(pts
					(arc
						(start 126.881128 -70.50024)
						(mid 126.119128 -70.50024)
						(end 126.881128 -70.50024)
					)
				)
			)
		)
		(zone
			(layer "F.Cu")
			(hatch none 0.5)
			(connect_pads
				(clearance 0)
			)
			(min_thickness 0.25)
			(keepout
				(tracks allowed)
				(vias not_allowed)
				(pads allowed)
				(copperpour not_allowed)
				(footprints allowed)
			)
			(placement
				(enabled no)
				(sheetname "")
			)
			(fill
				(thermal_gap 0.5)
				(thermal_bridge_width 0.5)
				(island_removal_mode 0)
			)
			(polygon
				(pts
					(arc
						(start 126.881128 -69.500242)
						(mid 126.119128 -69.500242)
						(end 126.881128 -69.500242)
					)
				)
			)
		)
		(zone
			(layer "F.Cu")
			(hatch none 0.5)
			(connect_pads
				(clearance 0)
			)
			(min_thickness 0.25)
			(keepout
				(tracks allowed)
				(vias not_allowed)
				(pads allowed)
				(copperpour not_allowed)
				(footprints allowed)
			)
			(placement
				(enabled no)
				(sheetname "")
			)
			(fill
				(thermal_gap 0.5)
				(thermal_bridge_width 0.5)
				(island_removal_mode 0)
			)
			(polygon
				(pts
					(arc
						(start 126.881128 -68.500244)
						(mid 126.119128 -68.500244)
						(end 126.881128 -68.500244)
					)
				)
			)
		)
		(zone
			(layer "F.Cu")
			(hatch none 0.5)
			(connect_pads
				(clearance 0)
			)
			(min_thickness 0.25)
			(keepout
				(tracks allowed)
				(vias not_allowed)
				(pads allowed)
				(copperpour not_allowed)
				(footprints allowed)
			)
			(placement
				(enabled no)
				(sheetname "")
			)
			(fill
				(thermal_gap 0.5)
				(thermal_bridge_width 0.5)
				(island_removal_mode 0)
			)
			(polygon
				(pts
					(arc
						(start 126.881128 -67.500246)
						(mid 126.119128 -67.500246)
						(end 126.881128 -67.500246)
					)
				)
			)
		)
		(zone
			(layer "F.Cu")
			(hatch none 0.5)
			(connect_pads
				(clearance 0)
			)
			(min_thickness 0.25)
			(keepout
				(tracks allowed)
				(vias not_allowed)
				(pads allowed)
				(copperpour not_allowed)
				(footprints allowed)
			)
			(placement
				(enabled no)
				(sheetname "")
			)
			(fill
				(thermal_gap 0.5)
				(thermal_bridge_width 0.5)
				(island_removal_mode 0)
			)
			(polygon
				(pts
					(arc
						(start 126.881128 -66.499994)
						(mid 126.119128 -66.499994)
						(end 126.881128 -66.499994)
					)
				)
			)
		)
		(zone
			(layer "F.Cu")
			(hatch none 0.5)
			(connect_pads
				(clearance 0)
			)
			(min_thickness 0.25)
			(keepout
				(tracks allowed)
				(vias not_allowed)
				(pads allowed)
				(copperpour not_allowed)
				(footprints allowed)
			)
			(placement
				(enabled no)
				(sheetname "")
			)
			(fill
				(thermal_gap 0.5)
				(thermal_bridge_width 0.5)
				(island_removal_mode 0)
			)
			(polygon
				(pts
					(arc
						(start 126.881128 -65.499996)
						(mid 126.119128 -65.499996)
						(end 126.881128 -65.499996)
					)
				)
			)
		)
		(zone
			(layer "F.Cu")
			(hatch none 0.5)
			(connect_pads
				(clearance 0)
			)
			(min_thickness 0.25)
			(keepout
				(tracks allowed)
				(vias not_allowed)
				(pads allowed)
				(copperpour not_allowed)
				(footprints allowed)
			)
			(placement
				(enabled no)
				(sheetname "")
			)
			(fill
				(thermal_gap 0.5)
				(thermal_bridge_width 0.5)
				(island_removal_mode 0)
			)
			(polygon
				(pts
					(arc
						(start 126.881128 -64.499998)
						(mid 126.119128 -64.499998)
						(end 126.881128 -64.499998)
					)
				)
			)
		)
		(zone
			(layer "F.Cu")
			(hatch none 0.5)
			(connect_pads
				(clearance 0)
			)
			(min_thickness 0.25)
			(keepout
				(tracks allowed)
				(vias not_allowed)
				(pads allowed)
				(copperpour not_allowed)
				(footprints allowed)
			)
			(placement
				(enabled no)
				(sheetname "")
			)
			(fill
				(thermal_gap 0.5)
				(thermal_bridge_width 0.5)
				(island_removal_mode 0)
			)
			(polygon
				(pts
					(arc
						(start 126.881128 -63.5)
						(mid 126.119128 -63.5)
						(end 126.881128 -63.5)
					)
				)
			)
		)
		(zone
			(layer "F.Cu")
			(hatch none 0.5)
			(connect_pads
				(clearance 0)
			)
			(min_thickness 0.25)
			(keepout
				(tracks allowed)
				(vias not_allowed)
				(pads allowed)
				(copperpour not_allowed)
				(footprints allowed)
			)
			(placement
				(enabled no)
				(sheetname "")
			)
			(fill
				(thermal_gap 0.5)
				(thermal_bridge_width 0.5)
				(island_removal_mode 0)
			)
			(polygon
				(pts
					(arc
						(start 126.881128 -62.500002)
						(mid 126.119128 -62.500002)
						(end 126.881128 -62.500002)
					)
				)
			)
		)
		(zone
			(layer "F.Cu")
			(hatch none 0.5)
			(connect_pads
				(clearance 0)
			)
			(min_thickness 0.25)
			(keepout
				(tracks allowed)
				(vias not_allowed)
				(pads allowed)
				(copperpour not_allowed)
				(footprints allowed)
			)
			(placement
				(enabled no)
				(sheetname "")
			)
			(fill
				(thermal_gap 0.5)
				(thermal_bridge_width 0.5)
				(island_removal_mode 0)
			)
			(polygon
				(pts
					(arc
						(start 126.881128 -61.500004)
						(mid 126.119128 -61.500004)
						(end 126.881128 -61.500004)
					)
				)
			)
		)
		(zone
			(layer "F.Cu")
			(hatch none 0.5)
			(connect_pads
				(clearance 0)
			)
			(min_thickness 0.25)
			(keepout
				(tracks allowed)
				(vias not_allowed)
				(pads allowed)
				(copperpour not_allowed)
				(footprints allowed)
			)
			(placement
				(enabled no)
				(sheetname "")
			)
			(fill
				(thermal_gap 0.5)
				(thermal_bridge_width 0.5)
				(island_removal_mode 0)
			)
			(polygon
				(pts
					(arc
						(start 126.881128 -60.500006)
						(mid 126.119128 -60.500006)
						(end 126.881128 -60.500006)
					)
				)
			)
		)
		(zone
			(layer "F.Cu")
			(hatch none 0.5)
			(connect_pads
				(clearance 0)
			)
			(min_thickness 0.25)
			(keepout
				(tracks allowed)
				(vias not_allowed)
				(pads allowed)
				(copperpour not_allowed)
				(footprints allowed)
			)
			(placement
				(enabled no)
				(sheetname "")
			)
			(fill
				(thermal_gap 0.5)
				(thermal_bridge_width 0.5)
				(island_removal_mode 0)
			)
			(polygon
				(pts
					(arc
						(start 126.881128 -59.500008)
						(mid 126.119128 -59.500008)
						(end 126.881128 -59.500008)
					)
				)
			)
		)
		(zone
			(layer "F.Cu")
			(hatch none 0.5)
			(connect_pads
				(clearance 0)
			)
			(min_thickness 0.25)
			(keepout
				(tracks allowed)
				(vias not_allowed)
				(pads allowed)
				(copperpour not_allowed)
				(footprints allowed)
			)
			(placement
				(enabled no)
				(sheetname "")
			)
			(fill
				(thermal_gap 0.5)
				(thermal_bridge_width 0.5)
				(island_removal_mode 0)
			)
			(polygon
				(pts
					(arc
						(start 126.881128 -58.50001)
						(mid 126.119128 -58.50001)
						(end 126.881128 -58.50001)
					)
				)
			)
		)
		(zone
			(layer "F.Cu")
			(hatch none 0.5)
			(connect_pads
				(clearance 0)
			)
			(min_thickness 0.25)
			(keepout
				(tracks allowed)
				(vias not_allowed)
				(pads allowed)
				(copperpour not_allowed)
				(footprints allowed)
			)
			(placement
				(enabled no)
				(sheetname "")
			)
			(fill
				(thermal_gap 0.5)
				(thermal_bridge_width 0.5)
				(island_removal_mode 0)
			)
			(polygon
				(pts
					(arc
						(start 126.881128 -57.500012)
						(mid 126.119128 -57.500012)
						(end 126.881128 -57.500012)
					)
				)
			)
		)
		(zone
			(layer "F.Cu")
			(hatch none 0.5)
			(connect_pads
				(clearance 0)
			)
			(min_thickness 0.25)
			(keepout
				(tracks allowed)
				(vias not_allowed)
				(pads allowed)
				(copperpour not_allowed)
				(footprints allowed)
			)
			(placement
				(enabled no)
				(sheetname "")
			)
			(fill
				(thermal_gap 0.5)
				(thermal_bridge_width 0.5)
				(island_removal_mode 0)
			)
			(polygon
				(pts
					(arc
						(start 126.881128 -56.500014)
						(mid 126.119128 -56.500014)
						(end 126.881128 -56.500014)
					)
				)
			)
		)
		(zone
			(layer "F.Cu")
			(hatch none 0.5)
			(connect_pads
				(clearance 0)
			)
			(min_thickness 0.25)
			(keepout
				(tracks allowed)
				(vias not_allowed)
				(pads allowed)
				(copperpour not_allowed)
				(footprints allowed)
			)
			(placement
				(enabled no)
				(sheetname "")
			)
			(fill
				(thermal_gap 0.5)
				(thermal_bridge_width 0.5)
				(island_removal_mode 0)
			)
			(polygon
				(pts
					(arc
						(start 126.881128 -55.500016)
						(mid 126.119128 -55.500016)
						(end 126.881128 -55.500016)
					)
				)
			)
		)
		(zone
			(layer "F.Cu")
			(hatch none 0.5)
			(connect_pads
				(clearance 0)
			)
			(min_thickness 0.25)
			(keepout
				(tracks allowed)
				(vias not_allowed)
				(pads allowed)
				(copperpour not_allowed)
				(footprints allowed)
			)
			(placement
				(enabled no)
				(sheetname "")
			)
			(fill
				(thermal_gap 0.5)
				(thermal_bridge_width 0.5)
				(island_removal_mode 0)
			)
			(polygon
				(pts
					(arc
						(start 126.881128 -54.500018)
						(mid 126.119128 -54.500018)
						(end 126.881128 -54.500018)
					)
				)
			)
		)
		(zone
			(layer "F.Cu")
			(hatch none 0.5)
			(connect_pads
				(clearance 0)
			)
			(min_thickness 0.25)
			(keepout
				(tracks allowed)
				(vias not_allowed)
				(pads allowed)
				(copperpour not_allowed)
				(footprints allowed)
			)
			(placement
				(enabled no)
				(sheetname "")
			)
			(fill
				(thermal_gap 0.5)
				(thermal_bridge_width 0.5)
				(island_removal_mode 0)
			)
			(polygon
				(pts
					(arc
						(start 126.881128 -53.50002)
						(mid 126.119128 -53.50002)
						(end 126.881128 -53.50002)
					)
				)
			)
		)
		(zone
			(layer "F.Cu")
			(hatch none 0.5)
			(connect_pads
				(clearance 0)
			)
			(min_thickness 0.25)
			(keepout
				(tracks allowed)
				(vias not_allowed)
				(pads allowed)
				(copperpour not_allowed)
				(footprints allowed)
			)
			(placement
				(enabled no)
				(sheetname "")
			)
			(fill
				(thermal_gap 0.5)
				(thermal_bridge_width 0.5)
				(island_removal_mode 0)
			)
			(polygon
				(pts
					(arc
						(start 126.881128 -52.500022)
						(mid 126.119128 -52.500022)
						(end 126.881128 -52.500022)
					)
				)
			)
		)
		(zone
			(layer "F.Cu")
			(hatch none 0.5)
			(connect_pads
				(clearance 0)
			)
			(min_thickness 0.25)
			(keepout
				(tracks allowed)
				(vias not_allowed)
				(pads allowed)
				(copperpour not_allowed)
				(footprints allowed)
			)
			(placement
				(enabled no)
				(sheetname "")
			)
			(fill
				(thermal_gap 0.5)
				(thermal_bridge_width 0.5)
				(island_removal_mode 0)
			)
			(polygon
				(pts
					(arc
						(start 126.881128 -51.500024)
						(mid 126.119128 -51.500024)
						(end 126.881128 -51.500024)
					)
				)
			)
		)
		(zone
			(layer "F.Cu")
			(hatch none 0.5)
			(connect_pads
				(clearance 0)
			)
			(min_thickness 0.25)
			(keepout
				(tracks allowed)
				(vias not_allowed)
				(pads allowed)
				(copperpour not_allowed)
				(footprints allowed)
			)
			(placement
				(enabled no)
				(sheetname "")
			)
			(fill
				(thermal_gap 0.5)
				(thermal_bridge_width 0.5)
				(island_removal_mode 0)
			)
			(polygon
				(pts
					(arc
						(start 127.881126 -82.500216)
						(mid 127.119126 -82.500216)
						(end 127.881126 -82.500216)
					)
				)
			)
		)
		(zone
			(layer "F.Cu")
			(hatch none 0.5)
			(connect_pads
				(clearance 0)
			)
			(min_thickness 0.25)
			(keepout
				(tracks allowed)
				(vias not_allowed)
				(pads allowed)
				(copperpour not_allowed)
				(footprints allowed)
			)
			(placement
				(enabled no)
				(sheetname "")
			)
			(fill
				(thermal_gap 0.5)
				(thermal_bridge_width 0.5)
				(island_removal_mode 0)
			)
			(polygon
				(pts
					(arc
						(start 127.881126 -81.500218)
						(mid 127.119126 -81.500218)
						(end 127.881126 -81.500218)
					)
				)
			)
		)
		(zone
			(layer "F.Cu")
			(hatch none 0.5)
			(connect_pads
				(clearance 0)
			)
			(min_thickness 0.25)
			(keepout
				(tracks allowed)
				(vias not_allowed)
				(pads allowed)
				(copperpour not_allowed)
				(footprints allowed)
			)
			(placement
				(enabled no)
				(sheetname "")
			)
			(fill
				(thermal_gap 0.5)
				(thermal_bridge_width 0.5)
				(island_removal_mode 0)
			)
			(polygon
				(pts
					(arc
						(start 127.881126 -80.50022)
						(mid 127.119126 -80.50022)
						(end 127.881126 -80.50022)
					)
				)
			)
		)
		(zone
			(layer "F.Cu")
			(hatch none 0.5)
			(connect_pads
				(clearance 0)
			)
			(min_thickness 0.25)
			(keepout
				(tracks allowed)
				(vias not_allowed)
				(pads allowed)
				(copperpour not_allowed)
				(footprints allowed)
			)
			(placement
				(enabled no)
				(sheetname "")
			)
			(fill
				(thermal_gap 0.5)
				(thermal_bridge_width 0.5)
				(island_removal_mode 0)
			)
			(polygon
				(pts
					(arc
						(start 127.881126 -79.500222)
						(mid 127.119126 -79.500222)
						(end 127.881126 -79.500222)
					)
				)
			)
		)
		(zone
			(layer "F.Cu")
			(hatch none 0.5)
			(connect_pads
				(clearance 0)
			)
			(min_thickness 0.25)
			(keepout
				(tracks allowed)
				(vias not_allowed)
				(pads allowed)
				(copperpour not_allowed)
				(footprints allowed)
			)
			(placement
				(enabled no)
				(sheetname "")
			)
			(fill
				(thermal_gap 0.5)
				(thermal_bridge_width 0.5)
				(island_removal_mode 0)
			)
			(polygon
				(pts
					(arc
						(start 127.881126 -78.500224)
						(mid 127.119126 -78.500224)
						(end 127.881126 -78.500224)
					)
				)
			)
		)
		(zone
			(layer "F.Cu")
			(hatch none 0.5)
			(connect_pads
				(clearance 0)
			)
			(min_thickness 0.25)
			(keepout
				(tracks allowed)
				(vias not_allowed)
				(pads allowed)
				(copperpour not_allowed)
				(footprints allowed)
			)
			(placement
				(enabled no)
				(sheetname "")
			)
			(fill
				(thermal_gap 0.5)
				(thermal_bridge_width 0.5)
				(island_removal_mode 0)
			)
			(polygon
				(pts
					(arc
						(start 127.881126 -77.500226)
						(mid 127.119126 -77.500226)
						(end 127.881126 -77.500226)
					)
				)
			)
		)
		(zone
			(layer "F.Cu")
			(hatch none 0.5)
			(connect_pads
				(clearance 0)
			)
			(min_thickness 0.25)
			(keepout
				(tracks allowed)
				(vias not_allowed)
				(pads allowed)
				(copperpour not_allowed)
				(footprints allowed)
			)
			(placement
				(enabled no)
				(sheetname "")
			)
			(fill
				(thermal_gap 0.5)
				(thermal_bridge_width 0.5)
				(island_removal_mode 0)
			)
			(polygon
				(pts
					(arc
						(start 127.881126 -76.500228)
						(mid 127.119126 -76.500228)
						(end 127.881126 -76.500228)
					)
				)
			)
		)
		(zone
			(layer "F.Cu")
			(hatch none 0.5)
			(connect_pads
				(clearance 0)
			)
			(min_thickness 0.25)
			(keepout
				(tracks allowed)
				(vias not_allowed)
				(pads allowed)
				(copperpour not_allowed)
				(footprints allowed)
			)
			(placement
				(enabled no)
				(sheetname "")
			)
			(fill
				(thermal_gap 0.5)
				(thermal_bridge_width 0.5)
				(island_removal_mode 0)
			)
			(polygon
				(pts
					(arc
						(start 127.881126 -75.50023)
						(mid 127.119126 -75.50023)
						(end 127.881126 -75.50023)
					)
				)
			)
		)
		(zone
			(layer "F.Cu")
			(hatch none 0.5)
			(connect_pads
				(clearance 0)
			)
			(min_thickness 0.25)
			(keepout
				(tracks allowed)
				(vias not_allowed)
				(pads allowed)
				(copperpour not_allowed)
				(footprints allowed)
			)
			(placement
				(enabled no)
				(sheetname "")
			)
			(fill
				(thermal_gap 0.5)
				(thermal_bridge_width 0.5)
				(island_removal_mode 0)
			)
			(polygon
				(pts
					(arc
						(start 127.881126 -74.500232)
						(mid 127.119126 -74.500232)
						(end 127.881126 -74.500232)
					)
				)
			)
		)
		(zone
			(layer "F.Cu")
			(hatch none 0.5)
			(connect_pads
				(clearance 0)
			)
			(min_thickness 0.25)
			(keepout
				(tracks allowed)
				(vias not_allowed)
				(pads allowed)
				(copperpour not_allowed)
				(footprints allowed)
			)
			(placement
				(enabled no)
				(sheetname "")
			)
			(fill
				(thermal_gap 0.5)
				(thermal_bridge_width 0.5)
				(island_removal_mode 0)
			)
			(polygon
				(pts
					(arc
						(start 127.881126 -73.500234)
						(mid 127.119126 -73.500234)
						(end 127.881126 -73.500234)
					)
				)
			)
		)
		(zone
			(layer "F.Cu")
			(hatch none 0.5)
			(connect_pads
				(clearance 0)
			)
			(min_thickness 0.25)
			(keepout
				(tracks allowed)
				(vias not_allowed)
				(pads allowed)
				(copperpour not_allowed)
				(footprints allowed)
			)
			(placement
				(enabled no)
				(sheetname "")
			)
			(fill
				(thermal_gap 0.5)
				(thermal_bridge_width 0.5)
				(island_removal_mode 0)
			)
			(polygon
				(pts
					(arc
						(start 127.881126 -72.500236)
						(mid 127.119126 -72.500236)
						(end 127.881126 -72.500236)
					)
				)
			)
		)
		(zone
			(layer "F.Cu")
			(hatch none 0.5)
			(connect_pads
				(clearance 0)
			)
			(min_thickness 0.25)
			(keepout
				(tracks allowed)
				(vias not_allowed)
				(pads allowed)
				(copperpour not_allowed)
				(footprints allowed)
			)
			(placement
				(enabled no)
				(sheetname "")
			)
			(fill
				(thermal_gap 0.5)
				(thermal_bridge_width 0.5)
				(island_removal_mode 0)
			)
			(polygon
				(pts
					(arc
						(start 127.881126 -71.500238)
						(mid 127.119126 -71.500238)
						(end 127.881126 -71.500238)
					)
				)
			)
		)
		(zone
			(layer "F.Cu")
			(hatch none 0.5)
			(connect_pads
				(clearance 0)
			)
			(min_thickness 0.25)
			(keepout
				(tracks allowed)
				(vias not_allowed)
				(pads allowed)
				(copperpour not_allowed)
				(footprints allowed)
			)
			(placement
				(enabled no)
				(sheetname "")
			)
			(fill
				(thermal_gap 0.5)
				(thermal_bridge_width 0.5)
				(island_removal_mode 0)
			)
			(polygon
				(pts
					(arc
						(start 127.881126 -70.50024)
						(mid 127.119126 -70.50024)
						(end 127.881126 -70.50024)
					)
				)
			)
		)
		(zone
			(layer "F.Cu")
			(hatch none 0.5)
			(connect_pads
				(clearance 0)
			)
			(min_thickness 0.25)
			(keepout
				(tracks allowed)
				(vias not_allowed)
				(pads allowed)
				(copperpour not_allowed)
				(footprints allowed)
			)
			(placement
				(enabled no)
				(sheetname "")
			)
			(fill
				(thermal_gap 0.5)
				(thermal_bridge_width 0.5)
				(island_removal_mode 0)
			)
			(polygon
				(pts
					(arc
						(start 127.881126 -69.500242)
						(mid 127.119126 -69.500242)
						(end 127.881126 -69.500242)
					)
				)
			)
		)
		(zone
			(layer "F.Cu")
			(hatch none 0.5)
			(connect_pads
				(clearance 0)
			)
			(min_thickness 0.25)
			(keepout
				(tracks allowed)
				(vias not_allowed)
				(pads allowed)
				(copperpour not_allowed)
				(footprints allowed)
			)
			(placement
				(enabled no)
				(sheetname "")
			)
			(fill
				(thermal_gap 0.5)
				(thermal_bridge_width 0.5)
				(island_removal_mode 0)
			)
			(polygon
				(pts
					(arc
						(start 127.881126 -68.500244)
						(mid 127.119126 -68.500244)
						(end 127.881126 -68.500244)
					)
				)
			)
		)
		(zone
			(layer "F.Cu")
			(hatch none 0.5)
			(connect_pads
				(clearance 0)
			)
			(min_thickness 0.25)
			(keepout
				(tracks allowed)
				(vias not_allowed)
				(pads allowed)
				(copperpour not_allowed)
				(footprints allowed)
			)
			(placement
				(enabled no)
				(sheetname "")
			)
			(fill
				(thermal_gap 0.5)
				(thermal_bridge_width 0.5)
				(island_removal_mode 0)
			)
			(polygon
				(pts
					(arc
						(start 127.881126 -67.500246)
						(mid 127.119126 -67.500246)
						(end 127.881126 -67.500246)
					)
				)
			)
		)
		(zone
			(layer "F.Cu")
			(hatch none 0.5)
			(connect_pads
				(clearance 0)
			)
			(min_thickness 0.25)
			(keepout
				(tracks allowed)
				(vias not_allowed)
				(pads allowed)
				(copperpour not_allowed)
				(footprints allowed)
			)
			(placement
				(enabled no)
				(sheetname "")
			)
			(fill
				(thermal_gap 0.5)
				(thermal_bridge_width 0.5)
				(island_removal_mode 0)
			)
			(polygon
				(pts
					(arc
						(start 127.881126 -66.499994)
						(mid 127.119126 -66.499994)
						(end 127.881126 -66.499994)
					)
				)
			)
		)
		(zone
			(layer "F.Cu")
			(hatch none 0.5)
			(connect_pads
				(clearance 0)
			)
			(min_thickness 0.25)
			(keepout
				(tracks allowed)
				(vias not_allowed)
				(pads allowed)
				(copperpour not_allowed)
				(footprints allowed)
			)
			(placement
				(enabled no)
				(sheetname "")
			)
			(fill
				(thermal_gap 0.5)
				(thermal_bridge_width 0.5)
				(island_removal_mode 0)
			)
			(polygon
				(pts
					(arc
						(start 127.881126 -65.499996)
						(mid 127.119126 -65.499996)
						(end 127.881126 -65.499996)
					)
				)
			)
		)
		(zone
			(layer "F.Cu")
			(hatch none 0.5)
			(connect_pads
				(clearance 0)
			)
			(min_thickness 0.25)
			(keepout
				(tracks allowed)
				(vias not_allowed)
				(pads allowed)
				(copperpour not_allowed)
				(footprints allowed)
			)
			(placement
				(enabled no)
				(sheetname "")
			)
			(fill
				(thermal_gap 0.5)
				(thermal_bridge_width 0.5)
				(island_removal_mode 0)
			)
			(polygon
				(pts
					(arc
						(start 127.881126 -64.499998)
						(mid 127.119126 -64.499998)
						(end 127.881126 -64.499998)
					)
				)
			)
		)
		(zone
			(layer "F.Cu")
			(hatch none 0.5)
			(connect_pads
				(clearance 0)
			)
			(min_thickness 0.25)
			(keepout
				(tracks allowed)
				(vias not_allowed)
				(pads allowed)
				(copperpour not_allowed)
				(footprints allowed)
			)
			(placement
				(enabled no)
				(sheetname "")
			)
			(fill
				(thermal_gap 0.5)
				(thermal_bridge_width 0.5)
				(island_removal_mode 0)
			)
			(polygon
				(pts
					(arc
						(start 127.881126 -63.5)
						(mid 127.119126 -63.5)
						(end 127.881126 -63.5)
					)
				)
			)
		)
		(zone
			(layer "F.Cu")
			(hatch none 0.5)
			(connect_pads
				(clearance 0)
			)
			(min_thickness 0.25)
			(keepout
				(tracks allowed)
				(vias not_allowed)
				(pads allowed)
				(copperpour not_allowed)
				(footprints allowed)
			)
			(placement
				(enabled no)
				(sheetname "")
			)
			(fill
				(thermal_gap 0.5)
				(thermal_bridge_width 0.5)
				(island_removal_mode 0)
			)
			(polygon
				(pts
					(arc
						(start 127.881126 -62.500002)
						(mid 127.119126 -62.500002)
						(end 127.881126 -62.500002)
					)
				)
			)
		)
		(zone
			(layer "F.Cu")
			(hatch none 0.5)
			(connect_pads
				(clearance 0)
			)
			(min_thickness 0.25)
			(keepout
				(tracks allowed)
				(vias not_allowed)
				(pads allowed)
				(copperpour not_allowed)
				(footprints allowed)
			)
			(placement
				(enabled no)
				(sheetname "")
			)
			(fill
				(thermal_gap 0.5)
				(thermal_bridge_width 0.5)
				(island_removal_mode 0)
			)
			(polygon
				(pts
					(arc
						(start 127.881126 -61.500004)
						(mid 127.119126 -61.500004)
						(end 127.881126 -61.500004)
					)
				)
			)
		)
		(zone
			(layer "F.Cu")
			(hatch none 0.5)
			(connect_pads
				(clearance 0)
			)
			(min_thickness 0.25)
			(keepout
				(tracks allowed)
				(vias not_allowed)
				(pads allowed)
				(copperpour not_allowed)
				(footprints allowed)
			)
			(placement
				(enabled no)
				(sheetname "")
			)
			(fill
				(thermal_gap 0.5)
				(thermal_bridge_width 0.5)
				(island_removal_mode 0)
			)
			(polygon
				(pts
					(arc
						(start 127.881126 -60.500006)
						(mid 127.119126 -60.500006)
						(end 127.881126 -60.500006)
					)
				)
			)
		)
		(zone
			(layer "F.Cu")
			(hatch none 0.5)
			(connect_pads
				(clearance 0)
			)
			(min_thickness 0.25)
			(keepout
				(tracks allowed)
				(vias not_allowed)
				(pads allowed)
				(copperpour not_allowed)
				(footprints allowed)
			)
			(placement
				(enabled no)
				(sheetname "")
			)
			(fill
				(thermal_gap 0.5)
				(thermal_bridge_width 0.5)
				(island_removal_mode 0)
			)
			(polygon
				(pts
					(arc
						(start 127.881126 -59.500008)
						(mid 127.119126 -59.500008)
						(end 127.881126 -59.500008)
					)
				)
			)
		)
		(zone
			(layer "F.Cu")
			(hatch none 0.5)
			(connect_pads
				(clearance 0)
			)
			(min_thickness 0.25)
			(keepout
				(tracks allowed)
				(vias not_allowed)
				(pads allowed)
				(copperpour not_allowed)
				(footprints allowed)
			)
			(placement
				(enabled no)
				(sheetname "")
			)
			(fill
				(thermal_gap 0.5)
				(thermal_bridge_width 0.5)
				(island_removal_mode 0)
			)
			(polygon
				(pts
					(arc
						(start 127.881126 -58.50001)
						(mid 127.119126 -58.50001)
						(end 127.881126 -58.50001)
					)
				)
			)
		)
		(zone
			(layer "F.Cu")
			(hatch none 0.5)
			(connect_pads
				(clearance 0)
			)
			(min_thickness 0.25)
			(keepout
				(tracks allowed)
				(vias not_allowed)
				(pads allowed)
				(copperpour not_allowed)
				(footprints allowed)
			)
			(placement
				(enabled no)
				(sheetname "")
			)
			(fill
				(thermal_gap 0.5)
				(thermal_bridge_width 0.5)
				(island_removal_mode 0)
			)
			(polygon
				(pts
					(arc
						(start 127.881126 -57.500012)
						(mid 127.119126 -57.500012)
						(end 127.881126 -57.500012)
					)
				)
			)
		)
		(zone
			(layer "F.Cu")
			(hatch none 0.5)
			(connect_pads
				(clearance 0)
			)
			(min_thickness 0.25)
			(keepout
				(tracks allowed)
				(vias not_allowed)
				(pads allowed)
				(copperpour not_allowed)
				(footprints allowed)
			)
			(placement
				(enabled no)
				(sheetname "")
			)
			(fill
				(thermal_gap 0.5)
				(thermal_bridge_width 0.5)
				(island_removal_mode 0)
			)
			(polygon
				(pts
					(arc
						(start 127.881126 -56.500014)
						(mid 127.119126 -56.500014)
						(end 127.881126 -56.500014)
					)
				)
			)
		)
		(zone
			(layer "F.Cu")
			(hatch none 0.5)
			(connect_pads
				(clearance 0)
			)
			(min_thickness 0.25)
			(keepout
				(tracks allowed)
				(vias not_allowed)
				(pads allowed)
				(copperpour not_allowed)
				(footprints allowed)
			)
			(placement
				(enabled no)
				(sheetname "")
			)
			(fill
				(thermal_gap 0.5)
				(thermal_bridge_width 0.5)
				(island_removal_mode 0)
			)
			(polygon
				(pts
					(arc
						(start 127.881126 -55.500016)
						(mid 127.119126 -55.500016)
						(end 127.881126 -55.500016)
					)
				)
			)
		)
		(zone
			(layer "F.Cu")
			(hatch none 0.5)
			(connect_pads
				(clearance 0)
			)
			(min_thickness 0.25)
			(keepout
				(tracks allowed)
				(vias not_allowed)
				(pads allowed)
				(copperpour not_allowed)
				(footprints allowed)
			)
			(placement
				(enabled no)
				(sheetname "")
			)
			(fill
				(thermal_gap 0.5)
				(thermal_bridge_width 0.5)
				(island_removal_mode 0)
			)
			(polygon
				(pts
					(arc
						(start 127.881126 -54.500018)
						(mid 127.119126 -54.500018)
						(end 127.881126 -54.500018)
					)
				)
			)
		)
		(zone
			(layer "F.Cu")
			(hatch none 0.5)
			(connect_pads
				(clearance 0)
			)
			(min_thickness 0.25)
			(keepout
				(tracks allowed)
				(vias not_allowed)
				(pads allowed)
				(copperpour not_allowed)
				(footprints allowed)
			)
			(placement
				(enabled no)
				(sheetname "")
			)
			(fill
				(thermal_gap 0.5)
				(thermal_bridge_width 0.5)
				(island_removal_mode 0)
			)
			(polygon
				(pts
					(arc
						(start 127.881126 -53.50002)
						(mid 127.119126 -53.50002)
						(end 127.881126 -53.50002)
					)
				)
			)
		)
		(zone
			(layer "F.Cu")
			(hatch none 0.5)
			(connect_pads
				(clearance 0)
			)
			(min_thickness 0.25)
			(keepout
				(tracks allowed)
				(vias not_allowed)
				(pads allowed)
				(copperpour not_allowed)
				(footprints allowed)
			)
			(placement
				(enabled no)
				(sheetname "")
			)
			(fill
				(thermal_gap 0.5)
				(thermal_bridge_width 0.5)
				(island_removal_mode 0)
			)
			(polygon
				(pts
					(arc
						(start 127.881126 -52.500022)
						(mid 127.119126 -52.500022)
						(end 127.881126 -52.500022)
					)
				)
			)
		)
		(zone
			(layer "F.Cu")
			(hatch none 0.5)
			(connect_pads
				(clearance 0)
			)
			(min_thickness 0.25)
			(keepout
				(tracks allowed)
				(vias not_allowed)
				(pads allowed)
				(copperpour not_allowed)
				(footprints allowed)
			)
			(placement
				(enabled no)
				(sheetname "")
			)
			(fill
				(thermal_gap 0.5)
				(thermal_bridge_width 0.5)
				(island_removal_mode 0)
			)
			(polygon
				(pts
					(arc
						(start 127.881126 -51.500024)
						(mid 127.119126 -51.500024)
						(end 127.881126 -51.500024)
					)
				)
			)
		)
		(zone
			(layer "F.Cu")
			(hatch none 0.5)
			(connect_pads
				(clearance 0)
			)
			(min_thickness 0.25)
			(keepout
				(tracks allowed)
				(vias not_allowed)
				(pads allowed)
				(copperpour not_allowed)
				(footprints allowed)
			)
			(placement
				(enabled no)
				(sheetname "")
			)
			(fill
				(thermal_gap 0.5)
				(thermal_bridge_width 0.5)
				(island_removal_mode 0)
			)
			(polygon
				(pts
					(arc
						(start 128.881124 -79.500222)
						(mid 128.119124 -79.500222)
						(end 128.881124 -79.500222)
					)
				)
			)
		)
		(zone
			(layer "F.Cu")
			(hatch none 0.5)
			(connect_pads
				(clearance 0)
			)
			(min_thickness 0.25)
			(keepout
				(tracks allowed)
				(vias not_allowed)
				(pads allowed)
				(copperpour not_allowed)
				(footprints allowed)
			)
			(placement
				(enabled no)
				(sheetname "")
			)
			(fill
				(thermal_gap 0.5)
				(thermal_bridge_width 0.5)
				(island_removal_mode 0)
			)
			(polygon
				(pts
					(arc
						(start 128.881124 -78.500224)
						(mid 128.119124 -78.500224)
						(end 128.881124 -78.500224)
					)
				)
			)
		)
		(zone
			(layer "F.Cu")
			(hatch none 0.5)
			(connect_pads
				(clearance 0)
			)
			(min_thickness 0.25)
			(keepout
				(tracks allowed)
				(vias not_allowed)
				(pads allowed)
				(copperpour not_allowed)
				(footprints allowed)
			)
			(placement
				(enabled no)
				(sheetname "")
			)
			(fill
				(thermal_gap 0.5)
				(thermal_bridge_width 0.5)
				(island_removal_mode 0)
			)
			(polygon
				(pts
					(arc
						(start 128.881124 -77.500226)
						(mid 128.119124 -77.500226)
						(end 128.881124 -77.500226)
					)
				)
			)
		)
		(zone
			(layer "F.Cu")
			(hatch none 0.5)
			(connect_pads
				(clearance 0)
			)
			(min_thickness 0.25)
			(keepout
				(tracks allowed)
				(vias not_allowed)
				(pads allowed)
				(copperpour not_allowed)
				(footprints allowed)
			)
			(placement
				(enabled no)
				(sheetname "")
			)
			(fill
				(thermal_gap 0.5)
				(thermal_bridge_width 0.5)
				(island_removal_mode 0)
			)
			(polygon
				(pts
					(arc
						(start 128.881124 -76.500228)
						(mid 128.119124 -76.500228)
						(end 128.881124 -76.500228)
					)
				)
			)
		)
		(zone
			(layer "F.Cu")
			(hatch none 0.5)
			(connect_pads
				(clearance 0)
			)
			(min_thickness 0.25)
			(keepout
				(tracks allowed)
				(vias not_allowed)
				(pads allowed)
				(copperpour not_allowed)
				(footprints allowed)
			)
			(placement
				(enabled no)
				(sheetname "")
			)
			(fill
				(thermal_gap 0.5)
				(thermal_bridge_width 0.5)
				(island_removal_mode 0)
			)
			(polygon
				(pts
					(arc
						(start 128.881124 -75.50023)
						(mid 128.119124 -75.50023)
						(end 128.881124 -75.50023)
					)
				)
			)
		)
		(zone
			(layer "F.Cu")
			(hatch none 0.5)
			(connect_pads
				(clearance 0)
			)
			(min_thickness 0.25)
			(keepout
				(tracks allowed)
				(vias not_allowed)
				(pads allowed)
				(copperpour not_allowed)
				(footprints allowed)
			)
			(placement
				(enabled no)
				(sheetname "")
			)
			(fill
				(thermal_gap 0.5)
				(thermal_bridge_width 0.5)
				(island_removal_mode 0)
			)
			(polygon
				(pts
					(arc
						(start 128.881124 -74.500232)
						(mid 128.119124 -74.500232)
						(end 128.881124 -74.500232)
					)
				)
			)
		)
		(zone
			(layer "F.Cu")
			(hatch none 0.5)
			(connect_pads
				(clearance 0)
			)
			(min_thickness 0.25)
			(keepout
				(tracks allowed)
				(vias not_allowed)
				(pads allowed)
				(copperpour not_allowed)
				(footprints allowed)
			)
			(placement
				(enabled no)
				(sheetname "")
			)
			(fill
				(thermal_gap 0.5)
				(thermal_bridge_width 0.5)
				(island_removal_mode 0)
			)
			(polygon
				(pts
					(arc
						(start 128.881124 -73.500234)
						(mid 128.119124 -73.500234)
						(end 128.881124 -73.500234)
					)
				)
			)
		)
		(zone
			(layer "F.Cu")
			(hatch none 0.5)
			(connect_pads
				(clearance 0)
			)
			(min_thickness 0.25)
			(keepout
				(tracks allowed)
				(vias not_allowed)
				(pads allowed)
				(copperpour not_allowed)
				(footprints allowed)
			)
			(placement
				(enabled no)
				(sheetname "")
			)
			(fill
				(thermal_gap 0.5)
				(thermal_bridge_width 0.5)
				(island_removal_mode 0)
			)
			(polygon
				(pts
					(arc
						(start 128.881124 -72.500236)
						(mid 128.119124 -72.500236)
						(end 128.881124 -72.500236)
					)
				)
			)
		)
		(zone
			(layer "F.Cu")
			(hatch none 0.5)
			(connect_pads
				(clearance 0)
			)
			(min_thickness 0.25)
			(keepout
				(tracks allowed)
				(vias not_allowed)
				(pads allowed)
				(copperpour not_allowed)
				(footprints allowed)
			)
			(placement
				(enabled no)
				(sheetname "")
			)
			(fill
				(thermal_gap 0.5)
				(thermal_bridge_width 0.5)
				(island_removal_mode 0)
			)
			(polygon
				(pts
					(arc
						(start 128.881124 -71.500238)
						(mid 128.119124 -71.500238)
						(end 128.881124 -71.500238)
					)
				)
			)
		)
		(zone
			(layer "F.Cu")
			(hatch none 0.5)
			(connect_pads
				(clearance 0)
			)
			(min_thickness 0.25)
			(keepout
				(tracks allowed)
				(vias not_allowed)
				(pads allowed)
				(copperpour not_allowed)
				(footprints allowed)
			)
			(placement
				(enabled no)
				(sheetname "")
			)
			(fill
				(thermal_gap 0.5)
				(thermal_bridge_width 0.5)
				(island_removal_mode 0)
			)
			(polygon
				(pts
					(arc
						(start 128.881124 -70.50024)
						(mid 128.119124 -70.50024)
						(end 128.881124 -70.50024)
					)
				)
			)
		)
		(zone
			(layer "F.Cu")
			(hatch none 0.5)
			(connect_pads
				(clearance 0)
			)
			(min_thickness 0.25)
			(keepout
				(tracks allowed)
				(vias not_allowed)
				(pads allowed)
				(copperpour not_allowed)
				(footprints allowed)
			)
			(placement
				(enabled no)
				(sheetname "")
			)
			(fill
				(thermal_gap 0.5)
				(thermal_bridge_width 0.5)
				(island_removal_mode 0)
			)
			(polygon
				(pts
					(arc
						(start 128.881124 -69.500242)
						(mid 128.119124 -69.500242)
						(end 128.881124 -69.500242)
					)
				)
			)
		)
		(zone
			(layer "F.Cu")
			(hatch none 0.5)
			(connect_pads
				(clearance 0)
			)
			(min_thickness 0.25)
			(keepout
				(tracks allowed)
				(vias not_allowed)
				(pads allowed)
				(copperpour not_allowed)
				(footprints allowed)
			)
			(placement
				(enabled no)
				(sheetname "")
			)
			(fill
				(thermal_gap 0.5)
				(thermal_bridge_width 0.5)
				(island_removal_mode 0)
			)
			(polygon
				(pts
					(arc
						(start 128.881124 -68.500244)
						(mid 128.119124 -68.500244)
						(end 128.881124 -68.500244)
					)
				)
			)
		)
		(zone
			(layer "F.Cu")
			(hatch none 0.5)
			(connect_pads
				(clearance 0)
			)
			(min_thickness 0.25)
			(keepout
				(tracks allowed)
				(vias not_allowed)
				(pads allowed)
				(copperpour not_allowed)
				(footprints allowed)
			)
			(placement
				(enabled no)
				(sheetname "")
			)
			(fill
				(thermal_gap 0.5)
				(thermal_bridge_width 0.5)
				(island_removal_mode 0)
			)
			(polygon
				(pts
					(arc
						(start 128.881124 -67.500246)
						(mid 128.119124 -67.500246)
						(end 128.881124 -67.500246)
					)
				)
			)
		)
		(zone
			(layer "F.Cu")
			(hatch none 0.5)
			(connect_pads
				(clearance 0)
			)
			(min_thickness 0.25)
			(keepout
				(tracks allowed)
				(vias not_allowed)
				(pads allowed)
				(copperpour not_allowed)
				(footprints allowed)
			)
			(placement
				(enabled no)
				(sheetname "")
			)
			(fill
				(thermal_gap 0.5)
				(thermal_bridge_width 0.5)
				(island_removal_mode 0)
			)
			(polygon
				(pts
					(arc
						(start 128.881124 -66.499994)
						(mid 128.119124 -66.499994)
						(end 128.881124 -66.499994)
					)
				)
			)
		)
		(zone
			(layer "F.Cu")
			(hatch none 0.5)
			(connect_pads
				(clearance 0)
			)
			(min_thickness 0.25)
			(keepout
				(tracks allowed)
				(vias not_allowed)
				(pads allowed)
				(copperpour not_allowed)
				(footprints allowed)
			)
			(placement
				(enabled no)
				(sheetname "")
			)
			(fill
				(thermal_gap 0.5)
				(thermal_bridge_width 0.5)
				(island_removal_mode 0)
			)
			(polygon
				(pts
					(arc
						(start 128.881124 -65.499996)
						(mid 128.119124 -65.499996)
						(end 128.881124 -65.499996)
					)
				)
			)
		)
		(zone
			(layer "F.Cu")
			(hatch none 0.5)
			(connect_pads
				(clearance 0)
			)
			(min_thickness 0.25)
			(keepout
				(tracks allowed)
				(vias not_allowed)
				(pads allowed)
				(copperpour not_allowed)
				(footprints allowed)
			)
			(placement
				(enabled no)
				(sheetname "")
			)
			(fill
				(thermal_gap 0.5)
				(thermal_bridge_width 0.5)
				(island_removal_mode 0)
			)
			(polygon
				(pts
					(arc
						(start 128.881124 -64.499998)
						(mid 128.119124 -64.499998)
						(end 128.881124 -64.499998)
					)
				)
			)
		)
		(zone
			(layer "F.Cu")
			(hatch none 0.5)
			(connect_pads
				(clearance 0)
			)
			(min_thickness 0.25)
			(keepout
				(tracks allowed)
				(vias not_allowed)
				(pads allowed)
				(copperpour not_allowed)
				(footprints allowed)
			)
			(placement
				(enabled no)
				(sheetname "")
			)
			(fill
				(thermal_gap 0.5)
				(thermal_bridge_width 0.5)
				(island_removal_mode 0)
			)
			(polygon
				(pts
					(arc
						(start 128.881124 -63.5)
						(mid 128.119124 -63.5)
						(end 128.881124 -63.5)
					)
				)
			)
		)
		(zone
			(layer "F.Cu")
			(hatch none 0.5)
			(connect_pads
				(clearance 0)
			)
			(min_thickness 0.25)
			(keepout
				(tracks allowed)
				(vias not_allowed)
				(pads allowed)
				(copperpour not_allowed)
				(footprints allowed)
			)
			(placement
				(enabled no)
				(sheetname "")
			)
			(fill
				(thermal_gap 0.5)
				(thermal_bridge_width 0.5)
				(island_removal_mode 0)
			)
			(polygon
				(pts
					(arc
						(start 128.881124 -62.500002)
						(mid 128.119124 -62.500002)
						(end 128.881124 -62.500002)
					)
				)
			)
		)
		(zone
			(layer "F.Cu")
			(hatch none 0.5)
			(connect_pads
				(clearance 0)
			)
			(min_thickness 0.25)
			(keepout
				(tracks allowed)
				(vias not_allowed)
				(pads allowed)
				(copperpour not_allowed)
				(footprints allowed)
			)
			(placement
				(enabled no)
				(sheetname "")
			)
			(fill
				(thermal_gap 0.5)
				(thermal_bridge_width 0.5)
				(island_removal_mode 0)
			)
			(polygon
				(pts
					(arc
						(start 128.881124 -61.500004)
						(mid 128.119124 -61.500004)
						(end 128.881124 -61.500004)
					)
				)
			)
		)
		(zone
			(layer "F.Cu")
			(hatch none 0.5)
			(connect_pads
				(clearance 0)
			)
			(min_thickness 0.25)
			(keepout
				(tracks allowed)
				(vias not_allowed)
				(pads allowed)
				(copperpour not_allowed)
				(footprints allowed)
			)
			(placement
				(enabled no)
				(sheetname "")
			)
			(fill
				(thermal_gap 0.5)
				(thermal_bridge_width 0.5)
				(island_removal_mode 0)
			)
			(polygon
				(pts
					(arc
						(start 128.881124 -60.500006)
						(mid 128.119124 -60.500006)
						(end 128.881124 -60.500006)
					)
				)
			)
		)
		(zone
			(layer "F.Cu")
			(hatch none 0.5)
			(connect_pads
				(clearance 0)
			)
			(min_thickness 0.25)
			(keepout
				(tracks allowed)
				(vias not_allowed)
				(pads allowed)
				(copperpour not_allowed)
				(footprints allowed)
			)
			(placement
				(enabled no)
				(sheetname "")
			)
			(fill
				(thermal_gap 0.5)
				(thermal_bridge_width 0.5)
				(island_removal_mode 0)
			)
			(polygon
				(pts
					(arc
						(start 128.881124 -59.500008)
						(mid 128.119124 -59.500008)
						(end 128.881124 -59.500008)
					)
				)
			)
		)
		(zone
			(layer "F.Cu")
			(hatch none 0.5)
			(connect_pads
				(clearance 0)
			)
			(min_thickness 0.25)
			(keepout
				(tracks allowed)
				(vias not_allowed)
				(pads allowed)
				(copperpour not_allowed)
				(footprints allowed)
			)
			(placement
				(enabled no)
				(sheetname "")
			)
			(fill
				(thermal_gap 0.5)
				(thermal_bridge_width 0.5)
				(island_removal_mode 0)
			)
			(polygon
				(pts
					(arc
						(start 128.881124 -58.50001)
						(mid 128.119124 -58.50001)
						(end 128.881124 -58.50001)
					)
				)
			)
		)
		(zone
			(layer "F.Cu")
			(hatch none 0.5)
			(connect_pads
				(clearance 0)
			)
			(min_thickness 0.25)
			(keepout
				(tracks allowed)
				(vias not_allowed)
				(pads allowed)
				(copperpour not_allowed)
				(footprints allowed)
			)
			(placement
				(enabled no)
				(sheetname "")
			)
			(fill
				(thermal_gap 0.5)
				(thermal_bridge_width 0.5)
				(island_removal_mode 0)
			)
			(polygon
				(pts
					(arc
						(start 128.881124 -57.500012)
						(mid 128.119124 -57.500012)
						(end 128.881124 -57.500012)
					)
				)
			)
		)
		(zone
			(layer "F.Cu")
			(hatch none 0.5)
			(connect_pads
				(clearance 0)
			)
			(min_thickness 0.25)
			(keepout
				(tracks allowed)
				(vias not_allowed)
				(pads allowed)
				(copperpour not_allowed)
				(footprints allowed)
			)
			(placement
				(enabled no)
				(sheetname "")
			)
			(fill
				(thermal_gap 0.5)
				(thermal_bridge_width 0.5)
				(island_removal_mode 0)
			)
			(polygon
				(pts
					(arc
						(start 128.881124 -56.500014)
						(mid 128.119124 -56.500014)
						(end 128.881124 -56.500014)
					)
				)
			)
		)
		(zone
			(layer "F.Cu")
			(hatch none 0.5)
			(connect_pads
				(clearance 0)
			)
			(min_thickness 0.25)
			(keepout
				(tracks allowed)
				(vias not_allowed)
				(pads allowed)
				(copperpour not_allowed)
				(footprints allowed)
			)
			(placement
				(enabled no)
				(sheetname "")
			)
			(fill
				(thermal_gap 0.5)
				(thermal_bridge_width 0.5)
				(island_removal_mode 0)
			)
			(polygon
				(pts
					(arc
						(start 128.881124 -55.500016)
						(mid 128.119124 -55.500016)
						(end 128.881124 -55.500016)
					)
				)
			)
		)
		(zone
			(layer "F.Cu")
			(hatch none 0.5)
			(connect_pads
				(clearance 0)
			)
			(min_thickness 0.25)
			(keepout
				(tracks allowed)
				(vias not_allowed)
				(pads allowed)
				(copperpour not_allowed)
				(footprints allowed)
			)
			(placement
				(enabled no)
				(sheetname "")
			)
			(fill
				(thermal_gap 0.5)
				(thermal_bridge_width 0.5)
				(island_removal_mode 0)
			)
			(polygon
				(pts
					(arc
						(start 128.881124 -54.500018)
						(mid 128.119124 -54.500018)
						(end 128.881124 -54.500018)
					)
				)
			)
		)
		(zone
			(layer "F.Cu")
			(hatch none 0.5)
			(connect_pads
				(clearance 0)
			)
			(min_thickness 0.25)
			(keepout
				(tracks allowed)
				(vias not_allowed)
				(pads allowed)
				(copperpour not_allowed)
				(footprints allowed)
			)
			(placement
				(enabled no)
				(sheetname "")
			)
			(fill
				(thermal_gap 0.5)
				(thermal_bridge_width 0.5)
				(island_removal_mode 0)
			)
			(polygon
				(pts
					(arc
						(start 129.881122 -79.500222)
						(mid 129.119122 -79.500222)
						(end 129.881122 -79.500222)
					)
				)
			)
		)
		(zone
			(layer "F.Cu")
			(hatch none 0.5)
			(connect_pads
				(clearance 0)
			)
			(min_thickness 0.25)
			(keepout
				(tracks allowed)
				(vias not_allowed)
				(pads allowed)
				(copperpour not_allowed)
				(footprints allowed)
			)
			(placement
				(enabled no)
				(sheetname "")
			)
			(fill
				(thermal_gap 0.5)
				(thermal_bridge_width 0.5)
				(island_removal_mode 0)
			)
			(polygon
				(pts
					(arc
						(start 129.881122 -78.500224)
						(mid 129.119122 -78.500224)
						(end 129.881122 -78.500224)
					)
				)
			)
		)
		(zone
			(layer "F.Cu")
			(hatch none 0.5)
			(connect_pads
				(clearance 0)
			)
			(min_thickness 0.25)
			(keepout
				(tracks allowed)
				(vias not_allowed)
				(pads allowed)
				(copperpour not_allowed)
				(footprints allowed)
			)
			(placement
				(enabled no)
				(sheetname "")
			)
			(fill
				(thermal_gap 0.5)
				(thermal_bridge_width 0.5)
				(island_removal_mode 0)
			)
			(polygon
				(pts
					(arc
						(start 129.881122 -77.500226)
						(mid 129.119122 -77.500226)
						(end 129.881122 -77.500226)
					)
				)
			)
		)
		(zone
			(layer "F.Cu")
			(hatch none 0.5)
			(connect_pads
				(clearance 0)
			)
			(min_thickness 0.25)
			(keepout
				(tracks allowed)
				(vias not_allowed)
				(pads allowed)
				(copperpour not_allowed)
				(footprints allowed)
			)
			(placement
				(enabled no)
				(sheetname "")
			)
			(fill
				(thermal_gap 0.5)
				(thermal_bridge_width 0.5)
				(island_removal_mode 0)
			)
			(polygon
				(pts
					(arc
						(start 129.881122 -76.500228)
						(mid 129.119122 -76.500228)
						(end 129.881122 -76.500228)
					)
				)
			)
		)
		(zone
			(layer "F.Cu")
			(hatch none 0.5)
			(connect_pads
				(clearance 0)
			)
			(min_thickness 0.25)
			(keepout
				(tracks allowed)
				(vias not_allowed)
				(pads allowed)
				(copperpour not_allowed)
				(footprints allowed)
			)
			(placement
				(enabled no)
				(sheetname "")
			)
			(fill
				(thermal_gap 0.5)
				(thermal_bridge_width 0.5)
				(island_removal_mode 0)
			)
			(polygon
				(pts
					(arc
						(start 129.881122 -75.50023)
						(mid 129.119122 -75.50023)
						(end 129.881122 -75.50023)
					)
				)
			)
		)
		(zone
			(layer "F.Cu")
			(hatch none 0.5)
			(connect_pads
				(clearance 0)
			)
			(min_thickness 0.25)
			(keepout
				(tracks allowed)
				(vias not_allowed)
				(pads allowed)
				(copperpour not_allowed)
				(footprints allowed)
			)
			(placement
				(enabled no)
				(sheetname "")
			)
			(fill
				(thermal_gap 0.5)
				(thermal_bridge_width 0.5)
				(island_removal_mode 0)
			)
			(polygon
				(pts
					(arc
						(start 129.881122 -74.500232)
						(mid 129.119122 -74.500232)
						(end 129.881122 -74.500232)
					)
				)
			)
		)
		(zone
			(layer "F.Cu")
			(hatch none 0.5)
			(connect_pads
				(clearance 0)
			)
			(min_thickness 0.25)
			(keepout
				(tracks allowed)
				(vias not_allowed)
				(pads allowed)
				(copperpour not_allowed)
				(footprints allowed)
			)
			(placement
				(enabled no)
				(sheetname "")
			)
			(fill
				(thermal_gap 0.5)
				(thermal_bridge_width 0.5)
				(island_removal_mode 0)
			)
			(polygon
				(pts
					(arc
						(start 129.881122 -73.500234)
						(mid 129.119122 -73.500234)
						(end 129.881122 -73.500234)
					)
				)
			)
		)
		(zone
			(layer "F.Cu")
			(hatch none 0.5)
			(connect_pads
				(clearance 0)
			)
			(min_thickness 0.25)
			(keepout
				(tracks allowed)
				(vias not_allowed)
				(pads allowed)
				(copperpour not_allowed)
				(footprints allowed)
			)
			(placement
				(enabled no)
				(sheetname "")
			)
			(fill
				(thermal_gap 0.5)
				(thermal_bridge_width 0.5)
				(island_removal_mode 0)
			)
			(polygon
				(pts
					(arc
						(start 129.881122 -72.500236)
						(mid 129.119122 -72.500236)
						(end 129.881122 -72.500236)
					)
				)
			)
		)
		(zone
			(layer "F.Cu")
			(hatch none 0.5)
			(connect_pads
				(clearance 0)
			)
			(min_thickness 0.25)
			(keepout
				(tracks allowed)
				(vias not_allowed)
				(pads allowed)
				(copperpour not_allowed)
				(footprints allowed)
			)
			(placement
				(enabled no)
				(sheetname "")
			)
			(fill
				(thermal_gap 0.5)
				(thermal_bridge_width 0.5)
				(island_removal_mode 0)
			)
			(polygon
				(pts
					(arc
						(start 129.881122 -71.500238)
						(mid 129.119122 -71.500238)
						(end 129.881122 -71.500238)
					)
				)
			)
		)
		(zone
			(layer "F.Cu")
			(hatch none 0.5)
			(connect_pads
				(clearance 0)
			)
			(min_thickness 0.25)
			(keepout
				(tracks allowed)
				(vias not_allowed)
				(pads allowed)
				(copperpour not_allowed)
				(footprints allowed)
			)
			(placement
				(enabled no)
				(sheetname "")
			)
			(fill
				(thermal_gap 0.5)
				(thermal_bridge_width 0.5)
				(island_removal_mode 0)
			)
			(polygon
				(pts
					(arc
						(start 129.881122 -70.50024)
						(mid 129.119122 -70.50024)
						(end 129.881122 -70.50024)
					)
				)
			)
		)
		(zone
			(layer "F.Cu")
			(hatch none 0.5)
			(connect_pads
				(clearance 0)
			)
			(min_thickness 0.25)
			(keepout
				(tracks allowed)
				(vias not_allowed)
				(pads allowed)
				(copperpour not_allowed)
				(footprints allowed)
			)
			(placement
				(enabled no)
				(sheetname "")
			)
			(fill
				(thermal_gap 0.5)
				(thermal_bridge_width 0.5)
				(island_removal_mode 0)
			)
			(polygon
				(pts
					(arc
						(start 129.881122 -69.500242)
						(mid 129.119122 -69.500242)
						(end 129.881122 -69.500242)
					)
				)
			)
		)
		(zone
			(layer "F.Cu")
			(hatch none 0.5)
			(connect_pads
				(clearance 0)
			)
			(min_thickness 0.25)
			(keepout
				(tracks allowed)
				(vias not_allowed)
				(pads allowed)
				(copperpour not_allowed)
				(footprints allowed)
			)
			(placement
				(enabled no)
				(sheetname "")
			)
			(fill
				(thermal_gap 0.5)
				(thermal_bridge_width 0.5)
				(island_removal_mode 0)
			)
			(polygon
				(pts
					(arc
						(start 129.881122 -68.500244)
						(mid 129.119122 -68.500244)
						(end 129.881122 -68.500244)
					)
				)
			)
		)
		(zone
			(layer "F.Cu")
			(hatch none 0.5)
			(connect_pads
				(clearance 0)
			)
			(min_thickness 0.25)
			(keepout
				(tracks allowed)
				(vias not_allowed)
				(pads allowed)
				(copperpour not_allowed)
				(footprints allowed)
			)
			(placement
				(enabled no)
				(sheetname "")
			)
			(fill
				(thermal_gap 0.5)
				(thermal_bridge_width 0.5)
				(island_removal_mode 0)
			)
			(polygon
				(pts
					(arc
						(start 129.881122 -67.500246)
						(mid 129.119122 -67.500246)
						(end 129.881122 -67.500246)
					)
				)
			)
		)
		(zone
			(layer "F.Cu")
			(hatch none 0.5)
			(connect_pads
				(clearance 0)
			)
			(min_thickness 0.25)
			(keepout
				(tracks allowed)
				(vias not_allowed)
				(pads allowed)
				(copperpour not_allowed)
				(footprints allowed)
			)
			(placement
				(enabled no)
				(sheetname "")
			)
			(fill
				(thermal_gap 0.5)
				(thermal_bridge_width 0.5)
				(island_removal_mode 0)
			)
			(polygon
				(pts
					(arc
						(start 129.881122 -66.499994)
						(mid 129.119122 -66.499994)
						(end 129.881122 -66.499994)
					)
				)
			)
		)
		(zone
			(layer "F.Cu")
			(hatch none 0.5)
			(connect_pads
				(clearance 0)
			)
			(min_thickness 0.25)
			(keepout
				(tracks allowed)
				(vias not_allowed)
				(pads allowed)
				(copperpour not_allowed)
				(footprints allowed)
			)
			(placement
				(enabled no)
				(sheetname "")
			)
			(fill
				(thermal_gap 0.5)
				(thermal_bridge_width 0.5)
				(island_removal_mode 0)
			)
			(polygon
				(pts
					(arc
						(start 129.881122 -65.499996)
						(mid 129.119122 -65.499996)
						(end 129.881122 -65.499996)
					)
				)
			)
		)
		(zone
			(layer "F.Cu")
			(hatch none 0.5)
			(connect_pads
				(clearance 0)
			)
			(min_thickness 0.25)
			(keepout
				(tracks allowed)
				(vias not_allowed)
				(pads allowed)
				(copperpour not_allowed)
				(footprints allowed)
			)
			(placement
				(enabled no)
				(sheetname "")
			)
			(fill
				(thermal_gap 0.5)
				(thermal_bridge_width 0.5)
				(island_removal_mode 0)
			)
			(polygon
				(pts
					(arc
						(start 129.881122 -64.499998)
						(mid 129.119122 -64.499998)
						(end 129.881122 -64.499998)
					)
				)
			)
		)
		(zone
			(layer "F.Cu")
			(hatch none 0.5)
			(connect_pads
				(clearance 0)
			)
			(min_thickness 0.25)
			(keepout
				(tracks allowed)
				(vias not_allowed)
				(pads allowed)
				(copperpour not_allowed)
				(footprints allowed)
			)
			(placement
				(enabled no)
				(sheetname "")
			)
			(fill
				(thermal_gap 0.5)
				(thermal_bridge_width 0.5)
				(island_removal_mode 0)
			)
			(polygon
				(pts
					(arc
						(start 129.881122 -63.5)
						(mid 129.119122 -63.5)
						(end 129.881122 -63.5)
					)
				)
			)
		)
		(zone
			(layer "F.Cu")
			(hatch none 0.5)
			(connect_pads
				(clearance 0)
			)
			(min_thickness 0.25)
			(keepout
				(tracks allowed)
				(vias not_allowed)
				(pads allowed)
				(copperpour not_allowed)
				(footprints allowed)
			)
			(placement
				(enabled no)
				(sheetname "")
			)
			(fill
				(thermal_gap 0.5)
				(thermal_bridge_width 0.5)
				(island_removal_mode 0)
			)
			(polygon
				(pts
					(arc
						(start 129.881122 -62.500002)
						(mid 129.119122 -62.500002)
						(end 129.881122 -62.500002)
					)
				)
			)
		)
		(zone
			(layer "F.Cu")
			(hatch none 0.5)
			(connect_pads
				(clearance 0)
			)
			(min_thickness 0.25)
			(keepout
				(tracks allowed)
				(vias not_allowed)
				(pads allowed)
				(copperpour not_allowed)
				(footprints allowed)
			)
			(placement
				(enabled no)
				(sheetname "")
			)
			(fill
				(thermal_gap 0.5)
				(thermal_bridge_width 0.5)
				(island_removal_mode 0)
			)
			(polygon
				(pts
					(arc
						(start 129.881122 -61.500004)
						(mid 129.119122 -61.500004)
						(end 129.881122 -61.500004)
					)
				)
			)
		)
		(zone
			(layer "F.Cu")
			(hatch none 0.5)
			(connect_pads
				(clearance 0)
			)
			(min_thickness 0.25)
			(keepout
				(tracks allowed)
				(vias not_allowed)
				(pads allowed)
				(copperpour not_allowed)
				(footprints allowed)
			)
			(placement
				(enabled no)
				(sheetname "")
			)
			(fill
				(thermal_gap 0.5)
				(thermal_bridge_width 0.5)
				(island_removal_mode 0)
			)
			(polygon
				(pts
					(arc
						(start 129.881122 -60.500006)
						(mid 129.119122 -60.500006)
						(end 129.881122 -60.500006)
					)
				)
			)
		)
		(zone
			(layer "F.Cu")
			(hatch none 0.5)
			(connect_pads
				(clearance 0)
			)
			(min_thickness 0.25)
			(keepout
				(tracks allowed)
				(vias not_allowed)
				(pads allowed)
				(copperpour not_allowed)
				(footprints allowed)
			)
			(placement
				(enabled no)
				(sheetname "")
			)
			(fill
				(thermal_gap 0.5)
				(thermal_bridge_width 0.5)
				(island_removal_mode 0)
			)
			(polygon
				(pts
					(arc
						(start 129.881122 -59.500008)
						(mid 129.119122 -59.500008)
						(end 129.881122 -59.500008)
					)
				)
			)
		)
		(zone
			(layer "F.Cu")
			(hatch none 0.5)
			(connect_pads
				(clearance 0)
			)
			(min_thickness 0.25)
			(keepout
				(tracks allowed)
				(vias not_allowed)
				(pads allowed)
				(copperpour not_allowed)
				(footprints allowed)
			)
			(placement
				(enabled no)
				(sheetname "")
			)
			(fill
				(thermal_gap 0.5)
				(thermal_bridge_width 0.5)
				(island_removal_mode 0)
			)
			(polygon
				(pts
					(arc
						(start 129.881122 -58.50001)
						(mid 129.119122 -58.50001)
						(end 129.881122 -58.50001)
					)
				)
			)
		)
		(zone
			(layer "F.Cu")
			(hatch none 0.5)
			(connect_pads
				(clearance 0)
			)
			(min_thickness 0.25)
			(keepout
				(tracks allowed)
				(vias not_allowed)
				(pads allowed)
				(copperpour not_allowed)
				(footprints allowed)
			)
			(placement
				(enabled no)
				(sheetname "")
			)
			(fill
				(thermal_gap 0.5)
				(thermal_bridge_width 0.5)
				(island_removal_mode 0)
			)
			(polygon
				(pts
					(arc
						(start 129.881122 -57.500012)
						(mid 129.119122 -57.500012)
						(end 129.881122 -57.500012)
					)
				)
			)
		)
		(zone
			(layer "F.Cu")
			(hatch none 0.5)
			(connect_pads
				(clearance 0)
			)
			(min_thickness 0.25)
			(keepout
				(tracks allowed)
				(vias not_allowed)
				(pads allowed)
				(copperpour not_allowed)
				(footprints allowed)
			)
			(placement
				(enabled no)
				(sheetname "")
			)
			(fill
				(thermal_gap 0.5)
				(thermal_bridge_width 0.5)
				(island_removal_mode 0)
			)
			(polygon
				(pts
					(arc
						(start 129.881122 -56.500014)
						(mid 129.119122 -56.500014)
						(end 129.881122 -56.500014)
					)
				)
			)
		)
		(zone
			(layer "F.Cu")
			(hatch none 0.5)
			(connect_pads
				(clearance 0)
			)
			(min_thickness 0.25)
			(keepout
				(tracks allowed)
				(vias not_allowed)
				(pads allowed)
				(copperpour not_allowed)
				(footprints allowed)
			)
			(placement
				(enabled no)
				(sheetname "")
			)
			(fill
				(thermal_gap 0.5)
				(thermal_bridge_width 0.5)
				(island_removal_mode 0)
			)
			(polygon
				(pts
					(arc
						(start 129.881122 -55.500016)
						(mid 129.119122 -55.500016)
						(end 129.881122 -55.500016)
					)
				)
			)
		)
		(zone
			(layer "F.Cu")
			(hatch none 0.5)
			(connect_pads
				(clearance 0)
			)
			(min_thickness 0.25)
			(keepout
				(tracks allowed)
				(vias not_allowed)
				(pads allowed)
				(copperpour not_allowed)
				(footprints allowed)
			)
			(placement
				(enabled no)
				(sheetname "")
			)
			(fill
				(thermal_gap 0.5)
				(thermal_bridge_width 0.5)
				(island_removal_mode 0)
			)
			(polygon
				(pts
					(arc
						(start 129.881122 -54.500018)
						(mid 129.119122 -54.500018)
						(end 129.881122 -54.500018)
					)
				)
			)
		)
		(zone
			(layer "F.Cu")
			(hatch none 0.5)
			(connect_pads
				(clearance 0)
			)
			(min_thickness 0.25)
			(keepout
				(tracks allowed)
				(vias not_allowed)
				(pads allowed)
				(copperpour not_allowed)
				(footprints allowed)
			)
			(placement
				(enabled no)
				(sheetname "")
			)
			(fill
				(thermal_gap 0.5)
				(thermal_bridge_width 0.5)
				(island_removal_mode 0)
			)
			(polygon
				(pts
					(arc
						(start 130.88112 -79.500222)
						(mid 130.11912 -79.500222)
						(end 130.88112 -79.500222)
					)
				)
			)
		)
		(zone
			(layer "F.Cu")
			(hatch none 0.5)
			(connect_pads
				(clearance 0)
			)
			(min_thickness 0.25)
			(keepout
				(tracks allowed)
				(vias not_allowed)
				(pads allowed)
				(copperpour not_allowed)
				(footprints allowed)
			)
			(placement
				(enabled no)
				(sheetname "")
			)
			(fill
				(thermal_gap 0.5)
				(thermal_bridge_width 0.5)
				(island_removal_mode 0)
			)
			(polygon
				(pts
					(arc
						(start 130.88112 -78.500224)
						(mid 130.11912 -78.500224)
						(end 130.88112 -78.500224)
					)
				)
			)
		)
		(zone
			(layer "F.Cu")
			(hatch none 0.5)
			(connect_pads
				(clearance 0)
			)
			(min_thickness 0.25)
			(keepout
				(tracks allowed)
				(vias not_allowed)
				(pads allowed)
				(copperpour not_allowed)
				(footprints allowed)
			)
			(placement
				(enabled no)
				(sheetname "")
			)
			(fill
				(thermal_gap 0.5)
				(thermal_bridge_width 0.5)
				(island_removal_mode 0)
			)
			(polygon
				(pts
					(arc
						(start 130.88112 -77.500226)
						(mid 130.11912 -77.500226)
						(end 130.88112 -77.500226)
					)
				)
			)
		)
		(zone
			(layer "F.Cu")
			(hatch none 0.5)
			(connect_pads
				(clearance 0)
			)
			(min_thickness 0.25)
			(keepout
				(tracks allowed)
				(vias not_allowed)
				(pads allowed)
				(copperpour not_allowed)
				(footprints allowed)
			)
			(placement
				(enabled no)
				(sheetname "")
			)
			(fill
				(thermal_gap 0.5)
				(thermal_bridge_width 0.5)
				(island_removal_mode 0)
			)
			(polygon
				(pts
					(arc
						(start 130.88112 -76.500228)
						(mid 130.11912 -76.500228)
						(end 130.88112 -76.500228)
					)
				)
			)
		)
		(zone
			(layer "F.Cu")
			(hatch none 0.5)
			(connect_pads
				(clearance 0)
			)
			(min_thickness 0.25)
			(keepout
				(tracks allowed)
				(vias not_allowed)
				(pads allowed)
				(copperpour not_allowed)
				(footprints allowed)
			)
			(placement
				(enabled no)
				(sheetname "")
			)
			(fill
				(thermal_gap 0.5)
				(thermal_bridge_width 0.5)
				(island_removal_mode 0)
			)
			(polygon
				(pts
					(arc
						(start 130.88112 -75.50023)
						(mid 130.11912 -75.50023)
						(end 130.88112 -75.50023)
					)
				)
			)
		)
		(zone
			(layer "F.Cu")
			(hatch none 0.5)
			(connect_pads
				(clearance 0)
			)
			(min_thickness 0.25)
			(keepout
				(tracks allowed)
				(vias not_allowed)
				(pads allowed)
				(copperpour not_allowed)
				(footprints allowed)
			)
			(placement
				(enabled no)
				(sheetname "")
			)
			(fill
				(thermal_gap 0.5)
				(thermal_bridge_width 0.5)
				(island_removal_mode 0)
			)
			(polygon
				(pts
					(arc
						(start 130.88112 -74.500232)
						(mid 130.11912 -74.500232)
						(end 130.88112 -74.500232)
					)
				)
			)
		)
		(zone
			(layer "F.Cu")
			(hatch none 0.5)
			(connect_pads
				(clearance 0)
			)
			(min_thickness 0.25)
			(keepout
				(tracks allowed)
				(vias not_allowed)
				(pads allowed)
				(copperpour not_allowed)
				(footprints allowed)
			)
			(placement
				(enabled no)
				(sheetname "")
			)
			(fill
				(thermal_gap 0.5)
				(thermal_bridge_width 0.5)
				(island_removal_mode 0)
			)
			(polygon
				(pts
					(arc
						(start 130.88112 -73.500234)
						(mid 130.11912 -73.500234)
						(end 130.88112 -73.500234)
					)
				)
			)
		)
		(zone
			(layer "F.Cu")
			(hatch none 0.5)
			(connect_pads
				(clearance 0)
			)
			(min_thickness 0.25)
			(keepout
				(tracks allowed)
				(vias not_allowed)
				(pads allowed)
				(copperpour not_allowed)
				(footprints allowed)
			)
			(placement
				(enabled no)
				(sheetname "")
			)
			(fill
				(thermal_gap 0.5)
				(thermal_bridge_width 0.5)
				(island_removal_mode 0)
			)
			(polygon
				(pts
					(arc
						(start 130.88112 -72.500236)
						(mid 130.11912 -72.500236)
						(end 130.88112 -72.500236)
					)
				)
			)
		)
		(zone
			(layer "F.Cu")
			(hatch none 0.5)
			(connect_pads
				(clearance 0)
			)
			(min_thickness 0.25)
			(keepout
				(tracks allowed)
				(vias not_allowed)
				(pads allowed)
				(copperpour not_allowed)
				(footprints allowed)
			)
			(placement
				(enabled no)
				(sheetname "")
			)
			(fill
				(thermal_gap 0.5)
				(thermal_bridge_width 0.5)
				(island_removal_mode 0)
			)
			(polygon
				(pts
					(arc
						(start 130.88112 -71.500238)
						(mid 130.11912 -71.500238)
						(end 130.88112 -71.500238)
					)
				)
			)
		)
		(zone
			(layer "F.Cu")
			(hatch none 0.5)
			(connect_pads
				(clearance 0)
			)
			(min_thickness 0.25)
			(keepout
				(tracks allowed)
				(vias not_allowed)
				(pads allowed)
				(copperpour not_allowed)
				(footprints allowed)
			)
			(placement
				(enabled no)
				(sheetname "")
			)
			(fill
				(thermal_gap 0.5)
				(thermal_bridge_width 0.5)
				(island_removal_mode 0)
			)
			(polygon
				(pts
					(arc
						(start 130.88112 -70.50024)
						(mid 130.11912 -70.50024)
						(end 130.88112 -70.50024)
					)
				)
			)
		)
		(zone
			(layer "F.Cu")
			(hatch none 0.5)
			(connect_pads
				(clearance 0)
			)
			(min_thickness 0.25)
			(keepout
				(tracks allowed)
				(vias not_allowed)
				(pads allowed)
				(copperpour not_allowed)
				(footprints allowed)
			)
			(placement
				(enabled no)
				(sheetname "")
			)
			(fill
				(thermal_gap 0.5)
				(thermal_bridge_width 0.5)
				(island_removal_mode 0)
			)
			(polygon
				(pts
					(arc
						(start 130.88112 -69.500242)
						(mid 130.11912 -69.500242)
						(end 130.88112 -69.500242)
					)
				)
			)
		)
		(zone
			(layer "F.Cu")
			(hatch none 0.5)
			(connect_pads
				(clearance 0)
			)
			(min_thickness 0.25)
			(keepout
				(tracks allowed)
				(vias not_allowed)
				(pads allowed)
				(copperpour not_allowed)
				(footprints allowed)
			)
			(placement
				(enabled no)
				(sheetname "")
			)
			(fill
				(thermal_gap 0.5)
				(thermal_bridge_width 0.5)
				(island_removal_mode 0)
			)
			(polygon
				(pts
					(arc
						(start 130.88112 -68.500244)
						(mid 130.11912 -68.500244)
						(end 130.88112 -68.500244)
					)
				)
			)
		)
		(zone
			(layer "F.Cu")
			(hatch none 0.5)
			(connect_pads
				(clearance 0)
			)
			(min_thickness 0.25)
			(keepout
				(tracks allowed)
				(vias not_allowed)
				(pads allowed)
				(copperpour not_allowed)
				(footprints allowed)
			)
			(placement
				(enabled no)
				(sheetname "")
			)
			(fill
				(thermal_gap 0.5)
				(thermal_bridge_width 0.5)
				(island_removal_mode 0)
			)
			(polygon
				(pts
					(arc
						(start 130.88112 -67.500246)
						(mid 130.11912 -67.500246)
						(end 130.88112 -67.500246)
					)
				)
			)
		)
		(zone
			(layer "F.Cu")
			(hatch none 0.5)
			(connect_pads
				(clearance 0)
			)
			(min_thickness 0.25)
			(keepout
				(tracks allowed)
				(vias not_allowed)
				(pads allowed)
				(copperpour not_allowed)
				(footprints allowed)
			)
			(placement
				(enabled no)
				(sheetname "")
			)
			(fill
				(thermal_gap 0.5)
				(thermal_bridge_width 0.5)
				(island_removal_mode 0)
			)
			(polygon
				(pts
					(arc
						(start 130.88112 -66.499994)
						(mid 130.11912 -66.499994)
						(end 130.88112 -66.499994)
					)
				)
			)
		)
		(zone
			(layer "F.Cu")
			(hatch none 0.5)
			(connect_pads
				(clearance 0)
			)
			(min_thickness 0.25)
			(keepout
				(tracks allowed)
				(vias not_allowed)
				(pads allowed)
				(copperpour not_allowed)
				(footprints allowed)
			)
			(placement
				(enabled no)
				(sheetname "")
			)
			(fill
				(thermal_gap 0.5)
				(thermal_bridge_width 0.5)
				(island_removal_mode 0)
			)
			(polygon
				(pts
					(arc
						(start 130.88112 -65.499996)
						(mid 130.11912 -65.499996)
						(end 130.88112 -65.499996)
					)
				)
			)
		)
		(zone
			(layer "F.Cu")
			(hatch none 0.5)
			(connect_pads
				(clearance 0)
			)
			(min_thickness 0.25)
			(keepout
				(tracks allowed)
				(vias not_allowed)
				(pads allowed)
				(copperpour not_allowed)
				(footprints allowed)
			)
			(placement
				(enabled no)
				(sheetname "")
			)
			(fill
				(thermal_gap 0.5)
				(thermal_bridge_width 0.5)
				(island_removal_mode 0)
			)
			(polygon
				(pts
					(arc
						(start 130.88112 -64.499998)
						(mid 130.11912 -64.499998)
						(end 130.88112 -64.499998)
					)
				)
			)
		)
		(zone
			(layer "F.Cu")
			(hatch none 0.5)
			(connect_pads
				(clearance 0)
			)
			(min_thickness 0.25)
			(keepout
				(tracks allowed)
				(vias not_allowed)
				(pads allowed)
				(copperpour not_allowed)
				(footprints allowed)
			)
			(placement
				(enabled no)
				(sheetname "")
			)
			(fill
				(thermal_gap 0.5)
				(thermal_bridge_width 0.5)
				(island_removal_mode 0)
			)
			(polygon
				(pts
					(arc
						(start 130.88112 -63.5)
						(mid 130.11912 -63.5)
						(end 130.88112 -63.5)
					)
				)
			)
		)
		(zone
			(layer "F.Cu")
			(hatch none 0.5)
			(connect_pads
				(clearance 0)
			)
			(min_thickness 0.25)
			(keepout
				(tracks allowed)
				(vias not_allowed)
				(pads allowed)
				(copperpour not_allowed)
				(footprints allowed)
			)
			(placement
				(enabled no)
				(sheetname "")
			)
			(fill
				(thermal_gap 0.5)
				(thermal_bridge_width 0.5)
				(island_removal_mode 0)
			)
			(polygon
				(pts
					(arc
						(start 130.88112 -62.500002)
						(mid 130.11912 -62.500002)
						(end 130.88112 -62.500002)
					)
				)
			)
		)
		(zone
			(layer "F.Cu")
			(hatch none 0.5)
			(connect_pads
				(clearance 0)
			)
			(min_thickness 0.25)
			(keepout
				(tracks allowed)
				(vias not_allowed)
				(pads allowed)
				(copperpour not_allowed)
				(footprints allowed)
			)
			(placement
				(enabled no)
				(sheetname "")
			)
			(fill
				(thermal_gap 0.5)
				(thermal_bridge_width 0.5)
				(island_removal_mode 0)
			)
			(polygon
				(pts
					(arc
						(start 130.88112 -61.500004)
						(mid 130.11912 -61.500004)
						(end 130.88112 -61.500004)
					)
				)
			)
		)
		(zone
			(layer "F.Cu")
			(hatch none 0.5)
			(connect_pads
				(clearance 0)
			)
			(min_thickness 0.25)
			(keepout
				(tracks allowed)
				(vias not_allowed)
				(pads allowed)
				(copperpour not_allowed)
				(footprints allowed)
			)
			(placement
				(enabled no)
				(sheetname "")
			)
			(fill
				(thermal_gap 0.5)
				(thermal_bridge_width 0.5)
				(island_removal_mode 0)
			)
			(polygon
				(pts
					(arc
						(start 130.88112 -60.500006)
						(mid 130.11912 -60.500006)
						(end 130.88112 -60.500006)
					)
				)
			)
		)
		(zone
			(layer "F.Cu")
			(hatch none 0.5)
			(connect_pads
				(clearance 0)
			)
			(min_thickness 0.25)
			(keepout
				(tracks allowed)
				(vias not_allowed)
				(pads allowed)
				(copperpour not_allowed)
				(footprints allowed)
			)
			(placement
				(enabled no)
				(sheetname "")
			)
			(fill
				(thermal_gap 0.5)
				(thermal_bridge_width 0.5)
				(island_removal_mode 0)
			)
			(polygon
				(pts
					(arc
						(start 130.88112 -59.500008)
						(mid 130.11912 -59.500008)
						(end 130.88112 -59.500008)
					)
				)
			)
		)
		(zone
			(layer "F.Cu")
			(hatch none 0.5)
			(connect_pads
				(clearance 0)
			)
			(min_thickness 0.25)
			(keepout
				(tracks allowed)
				(vias not_allowed)
				(pads allowed)
				(copperpour not_allowed)
				(footprints allowed)
			)
			(placement
				(enabled no)
				(sheetname "")
			)
			(fill
				(thermal_gap 0.5)
				(thermal_bridge_width 0.5)
				(island_removal_mode 0)
			)
			(polygon
				(pts
					(arc
						(start 130.88112 -58.50001)
						(mid 130.11912 -58.50001)
						(end 130.88112 -58.50001)
					)
				)
			)
		)
		(zone
			(layer "F.Cu")
			(hatch none 0.5)
			(connect_pads
				(clearance 0)
			)
			(min_thickness 0.25)
			(keepout
				(tracks allowed)
				(vias not_allowed)
				(pads allowed)
				(copperpour not_allowed)
				(footprints allowed)
			)
			(placement
				(enabled no)
				(sheetname "")
			)
			(fill
				(thermal_gap 0.5)
				(thermal_bridge_width 0.5)
				(island_removal_mode 0)
			)
			(polygon
				(pts
					(arc
						(start 130.88112 -57.500012)
						(mid 130.11912 -57.500012)
						(end 130.88112 -57.500012)
					)
				)
			)
		)
		(zone
			(layer "F.Cu")
			(hatch none 0.5)
			(connect_pads
				(clearance 0)
			)
			(min_thickness 0.25)
			(keepout
				(tracks allowed)
				(vias not_allowed)
				(pads allowed)
				(copperpour not_allowed)
				(footprints allowed)
			)
			(placement
				(enabled no)
				(sheetname "")
			)
			(fill
				(thermal_gap 0.5)
				(thermal_bridge_width 0.5)
				(island_removal_mode 0)
			)
			(polygon
				(pts
					(arc
						(start 130.88112 -56.500014)
						(mid 130.11912 -56.500014)
						(end 130.88112 -56.500014)
					)
				)
			)
		)
		(zone
			(layer "F.Cu")
			(hatch none 0.5)
			(connect_pads
				(clearance 0)
			)
			(min_thickness 0.25)
			(keepout
				(tracks allowed)
				(vias not_allowed)
				(pads allowed)
				(copperpour not_allowed)
				(footprints allowed)
			)
			(placement
				(enabled no)
				(sheetname "")
			)
			(fill
				(thermal_gap 0.5)
				(thermal_bridge_width 0.5)
				(island_removal_mode 0)
			)
			(polygon
				(pts
					(arc
						(start 130.88112 -55.500016)
						(mid 130.11912 -55.500016)
						(end 130.88112 -55.500016)
					)
				)
			)
		)
		(zone
			(layer "F.Cu")
			(hatch none 0.5)
			(connect_pads
				(clearance 0)
			)
			(min_thickness 0.25)
			(keepout
				(tracks allowed)
				(vias not_allowed)
				(pads allowed)
				(copperpour not_allowed)
				(footprints allowed)
			)
			(placement
				(enabled no)
				(sheetname "")
			)
			(fill
				(thermal_gap 0.5)
				(thermal_bridge_width 0.5)
				(island_removal_mode 0)
			)
			(polygon
				(pts
					(arc
						(start 130.88112 -54.500018)
						(mid 130.11912 -54.500018)
						(end 130.88112 -54.500018)
					)
				)
			)
		)
		(zone
			(layer "F.Cu")
			(hatch none 0.5)
			(connect_pads
				(clearance 0)
			)
			(min_thickness 0.25)
			(keepout
				(tracks allowed)
				(vias not_allowed)
				(pads allowed)
				(copperpour not_allowed)
				(footprints allowed)
			)
			(placement
				(enabled no)
				(sheetname "")
			)
			(fill
				(thermal_gap 0.5)
				(thermal_bridge_width 0.5)
				(island_removal_mode 0)
			)
			(polygon
				(pts
					(arc
						(start 99.906328 -81.500218)
						(mid 99.093528 -81.500218)
						(end 99.906328 -81.500218)
					)
				)
			)
		)
		(zone
			(layer "F.Cu")
			(hatch none 0.5)
			(connect_pads
				(clearance 0)
			)
			(min_thickness 0.25)
			(keepout
				(tracks allowed)
				(vias not_allowed)
				(pads allowed)
				(copperpour not_allowed)
				(footprints allowed)
			)
			(placement
				(enabled no)
				(sheetname "")
			)
			(fill
				(thermal_gap 0.5)
				(thermal_bridge_width 0.5)
				(island_removal_mode 0)
			)
			(polygon
				(pts
					(arc
						(start 99.906328 -80.50022)
						(mid 99.093528 -80.50022)
						(end 99.906328 -80.50022)
					)
				)
			)
		)
		(zone
			(layer "F.Cu")
			(hatch none 0.5)
			(connect_pads
				(clearance 0)
			)
			(min_thickness 0.25)
			(keepout
				(tracks allowed)
				(vias not_allowed)
				(pads allowed)
				(copperpour not_allowed)
				(footprints allowed)
			)
			(placement
				(enabled no)
				(sheetname "")
			)
			(fill
				(thermal_gap 0.5)
				(thermal_bridge_width 0.5)
				(island_removal_mode 0)
			)
			(polygon
				(pts
					(arc
						(start 99.906328 -53.50002)
						(mid 99.093528 -53.50002)
						(end 99.906328 -53.50002)
					)
				)
			)
		)
		(zone
			(layer "F.Cu")
			(hatch none 0.5)
			(connect_pads
				(clearance 0)
			)
			(min_thickness 0.25)
			(keepout
				(tracks allowed)
				(vias not_allowed)
				(pads allowed)
				(copperpour not_allowed)
				(footprints allowed)
			)
			(placement
				(enabled no)
				(sheetname "")
			)
			(fill
				(thermal_gap 0.5)
				(thermal_bridge_width 0.5)
				(island_removal_mode 0)
			)
			(polygon
				(pts
					(arc
						(start 99.906328 -52.500022)
						(mid 99.093528 -52.500022)
						(end 99.906328 -52.500022)
					)
				)
			)
		)
		(zone
			(layer "F.Cu")
			(hatch none 0.5)
			(connect_pads
				(clearance 0)
			)
			(min_thickness 0.25)
			(keepout
				(tracks allowed)
				(vias not_allowed)
				(pads allowed)
				(copperpour not_allowed)
				(footprints allowed)
			)
			(placement
				(enabled no)
				(sheetname "")
			)
			(fill
				(thermal_gap 0.5)
				(thermal_bridge_width 0.5)
				(island_removal_mode 0)
			)
			(polygon
				(pts
					(arc
						(start 100.906326 -82.500216)
						(mid 100.093526 -82.500216)
						(end 100.906326 -82.500216)
					)
				)
			)
		)
		(zone
			(layer "F.Cu")
			(hatch none 0.5)
			(connect_pads
				(clearance 0)
			)
			(min_thickness 0.25)
			(keepout
				(tracks allowed)
				(vias not_allowed)
				(pads allowed)
				(copperpour not_allowed)
				(footprints allowed)
			)
			(placement
				(enabled no)
				(sheetname "")
			)
			(fill
				(thermal_gap 0.5)
				(thermal_bridge_width 0.5)
				(island_removal_mode 0)
			)
			(polygon
				(pts
					(arc
						(start 100.906326 -81.500218)
						(mid 100.093526 -81.500218)
						(end 100.906326 -81.500218)
					)
				)
			)
		)
		(zone
			(layer "F.Cu")
			(hatch none 0.5)
			(connect_pads
				(clearance 0)
			)
			(min_thickness 0.25)
			(keepout
				(tracks allowed)
				(vias not_allowed)
				(pads allowed)
				(copperpour not_allowed)
				(footprints allowed)
			)
			(placement
				(enabled no)
				(sheetname "")
			)
			(fill
				(thermal_gap 0.5)
				(thermal_bridge_width 0.5)
				(island_removal_mode 0)
			)
			(polygon
				(pts
					(arc
						(start 100.906326 -80.50022)
						(mid 100.093526 -80.50022)
						(end 100.906326 -80.50022)
					)
				)
			)
		)
		(zone
			(layer "F.Cu")
			(hatch none 0.5)
			(connect_pads
				(clearance 0)
			)
			(min_thickness 0.25)
			(keepout
				(tracks allowed)
				(vias not_allowed)
				(pads allowed)
				(copperpour not_allowed)
				(footprints allowed)
			)
			(placement
				(enabled no)
				(sheetname "")
			)
			(fill
				(thermal_gap 0.5)
				(thermal_bridge_width 0.5)
				(island_removal_mode 0)
			)
			(polygon
				(pts
					(arc
						(start 100.906326 -53.50002)
						(mid 100.093526 -53.50002)
						(end 100.906326 -53.50002)
					)
				)
			)
		)
		(zone
			(layer "F.Cu")
			(hatch none 0.5)
			(connect_pads
				(clearance 0)
			)
			(min_thickness 0.25)
			(keepout
				(tracks allowed)
				(vias not_allowed)
				(pads allowed)
				(copperpour not_allowed)
				(footprints allowed)
			)
			(placement
				(enabled no)
				(sheetname "")
			)
			(fill
				(thermal_gap 0.5)
				(thermal_bridge_width 0.5)
				(island_removal_mode 0)
			)
			(polygon
				(pts
					(arc
						(start 100.906326 -52.500022)
						(mid 100.093526 -52.500022)
						(end 100.906326 -52.500022)
					)
				)
			)
		)
		(zone
			(layer "F.Cu")
			(hatch none 0.5)
			(connect_pads
				(clearance 0)
			)
			(min_thickness 0.25)
			(keepout
				(tracks allowed)
				(vias not_allowed)
				(pads allowed)
				(copperpour not_allowed)
				(footprints allowed)
			)
			(placement
				(enabled no)
				(sheetname "")
			)
			(fill
				(thermal_gap 0.5)
				(thermal_bridge_width 0.5)
				(island_removal_mode 0)
			)
			(polygon
				(pts
					(arc
						(start 100.906326 -51.500024)
						(mid 100.093526 -51.500024)
						(end 100.906326 -51.500024)
					)
				)
			)
		)
		(zone
			(layer "F.Cu")
			(hatch none 0.5)
			(connect_pads
				(clearance 0)
			)
			(min_thickness 0.25)
			(keepout
				(tracks allowed)
				(vias not_allowed)
				(pads allowed)
				(copperpour not_allowed)
				(footprints allowed)
			)
			(placement
				(enabled no)
				(sheetname "")
			)
			(fill
				(thermal_gap 0.5)
				(thermal_bridge_width 0.5)
				(island_removal_mode 0)
			)
			(polygon
				(pts
					(arc
						(start 101.906324 -82.500216)
						(mid 101.093524 -82.500216)
						(end 101.906324 -82.500216)
					)
				)
			)
		)
		(zone
			(layer "F.Cu")
			(hatch none 0.5)
			(connect_pads
				(clearance 0)
			)
			(min_thickness 0.25)
			(keepout
				(tracks allowed)
				(vias not_allowed)
				(pads allowed)
				(copperpour not_allowed)
				(footprints allowed)
			)
			(placement
				(enabled no)
				(sheetname "")
			)
			(fill
				(thermal_gap 0.5)
				(thermal_bridge_width 0.5)
				(island_removal_mode 0)
			)
			(polygon
				(pts
					(arc
						(start 101.906324 -81.500218)
						(mid 101.093524 -81.500218)
						(end 101.906324 -81.500218)
					)
				)
			)
		)
		(zone
			(layer "F.Cu")
			(hatch none 0.5)
			(connect_pads
				(clearance 0)
			)
			(min_thickness 0.25)
			(keepout
				(tracks allowed)
				(vias not_allowed)
				(pads allowed)
				(copperpour not_allowed)
				(footprints allowed)
			)
			(placement
				(enabled no)
				(sheetname "")
			)
			(fill
				(thermal_gap 0.5)
				(thermal_bridge_width 0.5)
				(island_removal_mode 0)
			)
			(polygon
				(pts
					(arc
						(start 101.906324 -80.50022)
						(mid 101.093524 -80.50022)
						(end 101.906324 -80.50022)
					)
				)
			)
		)
		(zone
			(layer "F.Cu")
			(hatch none 0.5)
			(connect_pads
				(clearance 0)
			)
			(min_thickness 0.25)
			(keepout
				(tracks allowed)
				(vias not_allowed)
				(pads allowed)
				(copperpour not_allowed)
				(footprints allowed)
			)
			(placement
				(enabled no)
				(sheetname "")
			)
			(fill
				(thermal_gap 0.5)
				(thermal_bridge_width 0.5)
				(island_removal_mode 0)
			)
			(polygon
				(pts
					(arc
						(start 101.906324 -53.50002)
						(mid 101.093524 -53.50002)
						(end 101.906324 -53.50002)
					)
				)
			)
		)
		(zone
			(layer "F.Cu")
			(hatch none 0.5)
			(connect_pads
				(clearance 0)
			)
			(min_thickness 0.25)
			(keepout
				(tracks allowed)
				(vias not_allowed)
				(pads allowed)
				(copperpour not_allowed)
				(footprints allowed)
			)
			(placement
				(enabled no)
				(sheetname "")
			)
			(fill
				(thermal_gap 0.5)
				(thermal_bridge_width 0.5)
				(island_removal_mode 0)
			)
			(polygon
				(pts
					(arc
						(start 101.906324 -52.500022)
						(mid 101.093524 -52.500022)
						(end 101.906324 -52.500022)
					)
				)
			)
		)
		(zone
			(layer "F.Cu")
			(hatch none 0.5)
			(connect_pads
				(clearance 0)
			)
			(min_thickness 0.25)
			(keepout
				(tracks allowed)
				(vias not_allowed)
				(pads allowed)
				(copperpour not_allowed)
				(footprints allowed)
			)
			(placement
				(enabled no)
				(sheetname "")
			)
			(fill
				(thermal_gap 0.5)
				(thermal_bridge_width 0.5)
				(island_removal_mode 0)
			)
			(polygon
				(pts
					(arc
						(start 101.906324 -51.500024)
						(mid 101.093524 -51.500024)
						(end 101.906324 -51.500024)
					)
				)
			)
		)
		(zone
			(layer "F.Cu")
			(hatch none 0.5)
			(connect_pads
				(clearance 0)
			)
			(min_thickness 0.25)
			(keepout
				(tracks allowed)
				(vias not_allowed)
				(pads allowed)
				(copperpour not_allowed)
				(footprints allowed)
			)
			(placement
				(enabled no)
				(sheetname "")
			)
			(fill
				(thermal_gap 0.5)
				(thermal_bridge_width 0.5)
				(island_removal_mode 0)
			)
			(polygon
				(pts
					(arc
						(start 128.906524 -82.500216)
						(mid 128.093724 -82.500216)
						(end 128.906524 -82.500216)
					)
				)
			)
		)
		(zone
			(layer "F.Cu")
			(hatch none 0.5)
			(connect_pads
				(clearance 0)
			)
			(min_thickness 0.25)
			(keepout
				(tracks allowed)
				(vias not_allowed)
				(pads allowed)
				(copperpour not_allowed)
				(footprints allowed)
			)
			(placement
				(enabled no)
				(sheetname "")
			)
			(fill
				(thermal_gap 0.5)
				(thermal_bridge_width 0.5)
				(island_removal_mode 0)
			)
			(polygon
				(pts
					(arc
						(start 128.906524 -81.500218)
						(mid 128.093724 -81.500218)
						(end 128.906524 -81.500218)
					)
				)
			)
		)
		(zone
			(layer "F.Cu")
			(hatch none 0.5)
			(connect_pads
				(clearance 0)
			)
			(min_thickness 0.25)
			(keepout
				(tracks allowed)
				(vias not_allowed)
				(pads allowed)
				(copperpour not_allowed)
				(footprints allowed)
			)
			(placement
				(enabled no)
				(sheetname "")
			)
			(fill
				(thermal_gap 0.5)
				(thermal_bridge_width 0.5)
				(island_removal_mode 0)
			)
			(polygon
				(pts
					(arc
						(start 128.906524 -80.50022)
						(mid 128.093724 -80.50022)
						(end 128.906524 -80.50022)
					)
				)
			)
		)
		(zone
			(layer "F.Cu")
			(hatch none 0.5)
			(connect_pads
				(clearance 0)
			)
			(min_thickness 0.25)
			(keepout
				(tracks allowed)
				(vias not_allowed)
				(pads allowed)
				(copperpour not_allowed)
				(footprints allowed)
			)
			(placement
				(enabled no)
				(sheetname "")
			)
			(fill
				(thermal_gap 0.5)
				(thermal_bridge_width 0.5)
				(island_removal_mode 0)
			)
			(polygon
				(pts
					(arc
						(start 128.906524 -53.50002)
						(mid 128.093724 -53.50002)
						(end 128.906524 -53.50002)
					)
				)
			)
		)
		(zone
			(layer "F.Cu")
			(hatch none 0.5)
			(connect_pads
				(clearance 0)
			)
			(min_thickness 0.25)
			(keepout
				(tracks allowed)
				(vias not_allowed)
				(pads allowed)
				(copperpour not_allowed)
				(footprints allowed)
			)
			(placement
				(enabled no)
				(sheetname "")
			)
			(fill
				(thermal_gap 0.5)
				(thermal_bridge_width 0.5)
				(island_removal_mode 0)
			)
			(polygon
				(pts
					(arc
						(start 128.906524 -52.500022)
						(mid 128.093724 -52.500022)
						(end 128.906524 -52.500022)
					)
				)
			)
		)
		(zone
			(layer "F.Cu")
			(hatch none 0.5)
			(connect_pads
				(clearance 0)
			)
			(min_thickness 0.25)
			(keepout
				(tracks allowed)
				(vias not_allowed)
				(pads allowed)
				(copperpour not_allowed)
				(footprints allowed)
			)
			(placement
				(enabled no)
				(sheetname "")
			)
			(fill
				(thermal_gap 0.5)
				(thermal_bridge_width 0.5)
				(island_removal_mode 0)
			)
			(polygon
				(pts
					(arc
						(start 128.906524 -51.500024)
						(mid 128.093724 -51.500024)
						(end 128.906524 -51.500024)
					)
				)
			)
		)
		(zone
			(layer "F.Cu")
			(hatch none 0.5)
			(connect_pads
				(clearance 0)
			)
			(min_thickness 0.25)
			(keepout
				(tracks allowed)
				(vias not_allowed)
				(pads allowed)
				(copperpour not_allowed)
				(footprints allowed)
			)
			(placement
				(enabled no)
				(sheetname "")
			)
			(fill
				(thermal_gap 0.5)
				(thermal_bridge_width 0.5)
				(island_removal_mode 0)
			)
			(polygon
				(pts
					(arc
						(start 129.906522 -82.500216)
						(mid 129.093722 -82.500216)
						(end 129.906522 -82.500216)
					)
				)
			)
		)
		(zone
			(layer "F.Cu")
			(hatch none 0.5)
			(connect_pads
				(clearance 0)
			)
			(min_thickness 0.25)
			(keepout
				(tracks allowed)
				(vias not_allowed)
				(pads allowed)
				(copperpour not_allowed)
				(footprints allowed)
			)
			(placement
				(enabled no)
				(sheetname "")
			)
			(fill
				(thermal_gap 0.5)
				(thermal_bridge_width 0.5)
				(island_removal_mode 0)
			)
			(polygon
				(pts
					(arc
						(start 129.906522 -81.500218)
						(mid 129.093722 -81.500218)
						(end 129.906522 -81.500218)
					)
				)
			)
		)
		(zone
			(layer "F.Cu")
			(hatch none 0.5)
			(connect_pads
				(clearance 0)
			)
			(min_thickness 0.25)
			(keepout
				(tracks allowed)
				(vias not_allowed)
				(pads allowed)
				(copperpour not_allowed)
				(footprints allowed)
			)
			(placement
				(enabled no)
				(sheetname "")
			)
			(fill
				(thermal_gap 0.5)
				(thermal_bridge_width 0.5)
				(island_removal_mode 0)
			)
			(polygon
				(pts
					(arc
						(start 129.906522 -80.50022)
						(mid 129.093722 -80.50022)
						(end 129.906522 -80.50022)
					)
				)
			)
		)
		(zone
			(layer "F.Cu")
			(hatch none 0.5)
			(connect_pads
				(clearance 0)
			)
			(min_thickness 0.25)
			(keepout
				(tracks allowed)
				(vias not_allowed)
				(pads allowed)
				(copperpour not_allowed)
				(footprints allowed)
			)
			(placement
				(enabled no)
				(sheetname "")
			)
			(fill
				(thermal_gap 0.5)
				(thermal_bridge_width 0.5)
				(island_removal_mode 0)
			)
			(polygon
				(pts
					(arc
						(start 129.906522 -53.50002)
						(mid 129.093722 -53.50002)
						(end 129.906522 -53.50002)
					)
				)
			)
		)
		(zone
			(layer "F.Cu")
			(hatch none 0.5)
			(connect_pads
				(clearance 0)
			)
			(min_thickness 0.25)
			(keepout
				(tracks allowed)
				(vias not_allowed)
				(pads allowed)
				(copperpour not_allowed)
				(footprints allowed)
			)
			(placement
				(enabled no)
				(sheetname "")
			)
			(fill
				(thermal_gap 0.5)
				(thermal_bridge_width 0.5)
				(island_removal_mode 0)
			)
			(polygon
				(pts
					(arc
						(start 129.906522 -52.500022)
						(mid 129.093722 -52.500022)
						(end 129.906522 -52.500022)
					)
				)
			)
		)
		(zone
			(layer "F.Cu")
			(hatch none 0.5)
			(connect_pads
				(clearance 0)
			)
			(min_thickness 0.25)
			(keepout
				(tracks allowed)
				(vias not_allowed)
				(pads allowed)
				(copperpour not_allowed)
				(footprints allowed)
			)
			(placement
				(enabled no)
				(sheetname "")
			)
			(fill
				(thermal_gap 0.5)
				(thermal_bridge_width 0.5)
				(island_removal_mode 0)
			)
			(polygon
				(pts
					(arc
						(start 129.906522 -51.500024)
						(mid 129.093722 -51.500024)
						(end 129.906522 -51.500024)
					)
				)
			)
		)
		(zone
			(layer "F.Cu")
			(hatch none 0.5)
			(connect_pads
				(clearance 0)
			)
			(min_thickness 0.25)
			(keepout
				(tracks allowed)
				(vias not_allowed)
				(pads allowed)
				(copperpour not_allowed)
				(footprints allowed)
			)
			(placement
				(enabled no)
				(sheetname "")
			)
			(fill
				(thermal_gap 0.5)
				(thermal_bridge_width 0.5)
				(island_removal_mode 0)
			)
			(polygon
				(pts
					(arc
						(start 130.90652 -81.500218)
						(mid 130.09372 -81.500218)
						(end 130.90652 -81.500218)
					)
				)
			)
		)
		(zone
			(layer "F.Cu")
			(hatch none 0.5)
			(connect_pads
				(clearance 0)
			)
			(min_thickness 0.25)
			(keepout
				(tracks allowed)
				(vias not_allowed)
				(pads allowed)
				(copperpour not_allowed)
				(footprints allowed)
			)
			(placement
				(enabled no)
				(sheetname "")
			)
			(fill
				(thermal_gap 0.5)
				(thermal_bridge_width 0.5)
				(island_removal_mode 0)
			)
			(polygon
				(pts
					(arc
						(start 130.90652 -80.50022)
						(mid 130.09372 -80.50022)
						(end 130.90652 -80.50022)
					)
				)
			)
		)
		(zone
			(layer "F.Cu")
			(hatch none 0.5)
			(connect_pads
				(clearance 0)
			)
			(min_thickness 0.25)
			(keepout
				(tracks allowed)
				(vias not_allowed)
				(pads allowed)
				(copperpour not_allowed)
				(footprints allowed)
			)
			(placement
				(enabled no)
				(sheetname "")
			)
			(fill
				(thermal_gap 0.5)
				(thermal_bridge_width 0.5)
				(island_removal_mode 0)
			)
			(polygon
				(pts
					(arc
						(start 130.90652 -53.50002)
						(mid 130.09372 -53.50002)
						(end 130.90652 -53.50002)
					)
				)
			)
		)
		(zone
			(layer "F.Cu")
			(hatch none 0.5)
			(connect_pads
				(clearance 0)
			)
			(min_thickness 0.25)
			(keepout
				(tracks allowed)
				(vias not_allowed)
				(pads allowed)
				(copperpour not_allowed)
				(footprints allowed)
			)
			(placement
				(enabled no)
				(sheetname "")
			)
			(fill
				(thermal_gap 0.5)
				(thermal_bridge_width 0.5)
				(island_removal_mode 0)
			)
			(polygon
				(pts
					(arc
						(start 130.90652 -52.500022)
						(mid 130.09372 -52.500022)
						(end 130.90652 -52.500022)
					)
				)
			)
		)
	)
	(footprint ""
		(layer "F.Cu")
		(at 49.570894 -32.973518 180)
		(property "Reference" "R401"
			(at 0 0 180)
			(layer "F.SilkS")
			(hide yes)
			(effects
				(font
					(size 1.27 1.27)
				)
			)
		)
		(property "Value" "62KR2J-GP"
			(at 0.064008 -3.993896 180)
			(unlocked yes)
			(layer "F.Fab")
			(hide yes)
			(effects
				(font
					(size 1.016 1.016)
					(thickness 0.1524)
				)
			)
		)
		(property "Device Type" "R402H16"
			(at 0.064008 -5.517896 180)
			(unlocked yes)
			(layer "F.Fab")
			(hide yes)
			(effects
				(font
					(size 1.016 1.016)
					(thickness 0.1524)
				)
			)
		)
		(duplicate_pad_numbers_are_jumpers no)
		(fp_line
			(start 0.508 -0.9398)
			(end -0.508 -0.9398)
			(stroke
				(width 0.1524)
				(type default)
			)
			(layer "F.SilkS")
		)
		(fp_line
			(start -0.508 -0.9398)
			(end -0.508 0.9398)
			(stroke
				(width 0.1524)
				(type default)
			)
			(layer "F.SilkS")
		)
		(fp_rect
			(start -0.508 0.9398)
			(end 0.508 -0.9398)
			(stroke
				(width 0)
				(type default)
			)
			(fill no)
			(layer "F.CrtYd")
		)
		(fp_rect
			(start -0.508 0.9398)
			(end 0.508 -0.9398)
			(stroke
				(width 0)
				(type default)
			)
			(fill no)
			(layer "F.Fab")
		)
		(pad "1" smd custom
			(at 0 -0.4445 180)
			(size 0.1397 0.1397)
			(layers "F.Cu" "F.Mask" "F.Paste")
			(net "P0V9_TRIP")
			(options
				(clearance outline)
				(anchor circle)
			)
			(primitives
				(gr_poly
					(pts
						(arc
							(start -0.1778 -0.2794)
							(mid -0.249642 -0.249642)
							(end -0.2794 -0.1778)
						)
						(arc
							(start -0.2794 0.1778)
							(mid -0.249642 0.249642)
							(end -0.1778 0.2794)
						)
						(arc
							(start 0.1778 0.2794)
							(mid 0.249642 0.249642)
							(end 0.2794 0.1778)
						)
						(arc
							(start 0.2794 -0.1778)
							(mid 0.249642 -0.249642)
							(end 0.1778 -0.2794)
						)
					)
					(width 0)
					(fill yes)
				)
			)
		)
		(pad "2" smd custom
			(at 0 0.4445 180)
			(size 0.1397 0.1397)
			(layers "F.Cu" "F.Mask" "F.Paste")
			(net "AGND_P0V9")
			(options
				(clearance outline)
				(anchor circle)
			)
			(primitives
				(gr_poly
					(pts
						(arc
							(start -0.1778 -0.2794)
							(mid -0.249642 -0.249642)
							(end -0.2794 -0.1778)
						)
						(arc
							(start -0.2794 0.1778)
							(mid -0.249642 0.249642)
							(end -0.1778 0.2794)
						)
						(arc
							(start 0.1778 0.2794)
							(mid 0.249642 0.249642)
							(end 0.2794 0.1778)
						)
						(arc
							(start 0.2794 -0.1778)
							(mid 0.249642 -0.249642)
							(end 0.1778 -0.2794)
						)
					)
					(width 0)
					(fill yes)
				)
			)
		)
	)
	(footprint ""
		(layer "F.Cu")
		(at 41.7576 -49.7332 180)
		(property "Reference" "C669"
			(at 0 0 180)
			(layer "F.SilkS")
			(hide yes)
			(effects
				(font
					(size 1.27 1.27)
				)
			)
		)
		(property "Value" "SC10U16V5KX-7-GP-U"
			(at -0.0762 -6.1214 180)
			(unlocked yes)
			(layer "F.Fab")
			(hide yes)
			(effects
				(font
					(size 1.016 1.016)
					(thickness 0.1524)
				)
			)
		)
		(property "Device Type" "C805H58"
			(at -0.0762 -8.1534 180)
			(unlocked yes)
			(layer "F.Fab")
			(hide yes)
			(effects
				(font
					(size 1.016 1.016)
					(thickness 0.1524)
				)
			)
		)
		(duplicate_pad_numbers_are_jumpers no)
		(fp_line
			(start 0.635 0)
			(end -0.635 0)
			(stroke
				(width 0.508)
				(type default)
			)
			(layer "F.SilkS")
		)
		(fp_rect
			(start -0.9652 1.778)
			(end 0.9652 -1.778)
			(stroke
				(width 0)
				(type default)
			)
			(fill no)
			(layer "F.CrtYd")
		)
		(fp_poly
			(pts
				(xy -0.9652 -1.778) (xy 0.9652 -1.778) (xy 0.9652 1.778) (xy -0.9652 1.778)
			)
			(stroke
				(width 0)
				(type default)
			)
			(fill no)
			(layer "F.Fab")
		)
		(pad "1" smd rect
			(at 0 -0.9652 180)
			(size 1.397 1.143)
			(layers "F.Cu" "F.Mask" "F.Paste")
			(net "P12V_STBY_VIN_Q7")
		)
		(pad "2" smd rect
			(at 0 0.9652 180)
			(size 1.397 1.143)
			(layers "F.Cu" "F.Mask" "F.Paste")
			(net "GND")
		)
	)
	(footprint ""
		(layer "F.Cu")
		(at 159.416242 -121.369074 90)
		(property "Reference" "R324"
			(at 0 0 90)
			(layer "F.SilkS")
			(hide yes)
			(effects
				(font
					(size 1.27 1.27)
				)
			)
		)
		(property "Value" "100KR2F-L1-GP"
			(at 0.064008 -3.993896 90)
			(unlocked yes)
			(layer "F.Fab")
			(hide yes)
			(effects
				(font
					(size 1.016 1.016)
					(thickness 0.1524)
				)
			)
		)
		(property "Device Type" "R402H16"
			(at 0.064008 -5.517896 90)
			(unlocked yes)
			(layer "F.Fab")
			(hide yes)
			(effects
				(font
					(size 1.016 1.016)
					(thickness 0.1524)
				)
			)
		)
		(duplicate_pad_numbers_are_jumpers no)
		(fp_line
			(start 0.508 -0.9398)
			(end -0.508 -0.9398)
			(stroke
				(width 0.1524)
				(type default)
			)
			(layer "F.SilkS")
		)
		(fp_line
			(start -0.508 -0.9398)
			(end -0.508 0.9398)
			(stroke
				(width 0.1524)
				(type default)
			)
			(layer "F.SilkS")
		)
		(fp_rect
			(start -0.508 0.9398)
			(end 0.508 -0.9398)
			(stroke
				(width 0)
				(type default)
			)
			(fill no)
			(layer "F.CrtYd")
		)
		(fp_rect
			(start -0.508 0.9398)
			(end 0.508 -0.9398)
			(stroke
				(width 0)
				(type default)
			)
			(fill no)
			(layer "F.Fab")
		)
		(pad "1" smd custom
			(at 0 -0.4445 90)
			(size 0.1397 0.1397)
			(layers "F.Cu" "F.Mask" "F.Paste")
			(net "AGND_P1V5_E")
			(options
				(clearance outline)
				(anchor circle)
			)
			(primitives
				(gr_poly
					(pts
						(arc
							(start -0.1778 -0.2794)
							(mid -0.249642 -0.249642)
							(end -0.2794 -0.1778)
						)
						(arc
							(start -0.2794 0.1778)
							(mid -0.249642 0.249642)
							(end -0.1778 0.2794)
						)
						(arc
							(start 0.1778 0.2794)
							(mid 0.249642 0.249642)
							(end 0.2794 0.1778)
						)
						(arc
							(start 0.2794 -0.1778)
							(mid 0.249642 -0.249642)
							(end 0.1778 -0.2794)
						)
					)
					(width 0)
					(fill yes)
				)
			)
		)
		(pad "2" smd custom
			(at 0 0.4445 90)
			(size 0.1397 0.1397)
			(layers "F.Cu" "F.Mask" "F.Paste")
			(net "P1V5_E_MODE")
			(options
				(clearance outline)
				(anchor circle)
			)
			(primitives
				(gr_poly
					(pts
						(arc
							(start -0.1778 -0.2794)
							(mid -0.249642 -0.249642)
							(end -0.2794 -0.1778)
						)
						(arc
							(start -0.2794 0.1778)
							(mid -0.249642 0.249642)
							(end -0.1778 0.2794)
						)
						(arc
							(start 0.1778 0.2794)
							(mid 0.249642 0.249642)
							(end 0.2794 0.1778)
						)
						(arc
							(start 0.2794 -0.1778)
							(mid 0.249642 -0.249642)
							(end 0.1778 -0.2794)
						)
					)
					(width 0)
					(fill yes)
				)
			)
		)
	)
	(footprint ""
		(layer "F.Cu")
		(at 7.0866 -57.785 90)
		(property "Reference" "R548"
			(at 0 0 90)
			(layer "F.SilkS")
			(hide yes)
			(effects
				(font
					(size 1.27 1.27)
				)
			)
		)
		(property "Value" "45K3R2F-L-GP"
			(at 0.064008 -3.993896 90)
			(unlocked yes)
			(layer "F.Fab")
			(hide yes)
			(effects
				(font
					(size 1.016 1.016)
					(thickness 0.1524)
				)
			)
		)
		(property "Device Type" "R402H16"
			(at 0.064008 -5.517896 90)
			(unlocked yes)
			(layer "F.Fab")
			(hide yes)
			(effects
				(font
					(size 1.016 1.016)
					(thickness 0.1524)
				)
			)
		)
		(duplicate_pad_numbers_are_jumpers no)
		(fp_line
			(start 0.508 -0.9398)
			(end -0.508 -0.9398)
			(stroke
				(width 0.1524)
				(type default)
			)
			(layer "F.SilkS")
		)
		(fp_line
			(start -0.508 -0.9398)
			(end -0.508 0.9398)
			(stroke
				(width 0.1524)
				(type default)
			)
			(layer "F.SilkS")
		)
		(fp_rect
			(start -0.508 0.9398)
			(end 0.508 -0.9398)
			(stroke
				(width 0)
				(type default)
			)
			(fill no)
			(layer "F.CrtYd")
		)
		(fp_rect
			(start -0.508 0.9398)
			(end 0.508 -0.9398)
			(stroke
				(width 0)
				(type default)
			)
			(fill no)
			(layer "F.Fab")
		)
		(pad "1" smd custom
			(at 0 -0.4445 90)
			(size 0.1397 0.1397)
			(layers "F.Cu" "F.Mask" "F.Paste")
			(net "P12V_STBY_SCC")
			(options
				(clearance outline)
				(anchor circle)
			)
			(primitives
				(gr_poly
					(pts
						(arc
							(start -0.1778 -0.2794)
							(mid -0.249642 -0.249642)
							(end -0.2794 -0.1778)
						)
						(arc
							(start -0.2794 0.1778)
							(mid -0.249642 0.249642)
							(end -0.1778 0.2794)
						)
						(arc
							(start 0.1778 0.2794)
							(mid 0.249642 0.249642)
							(end 0.2794 0.1778)
						)
						(arc
							(start 0.2794 -0.1778)
							(mid 0.249642 -0.249642)
							(end 0.1778 -0.2794)
						)
					)
					(width 0)
					(fill yes)
				)
			)
		)
		(pad "2" smd custom
			(at 0 0.4445 90)
			(size 0.1397 0.1397)
			(layers "F.Cu" "F.Mask" "F.Paste")
			(net "P12V_SCC_PGOOD")
			(options
				(clearance outline)
				(anchor circle)
			)
			(primitives
				(gr_poly
					(pts
						(arc
							(start -0.1778 -0.2794)
							(mid -0.249642 -0.249642)
							(end -0.2794 -0.1778)
						)
						(arc
							(start -0.2794 0.1778)
							(mid -0.249642 0.249642)
							(end -0.1778 0.2794)
						)
						(arc
							(start 0.1778 0.2794)
							(mid 0.249642 0.249642)
							(end 0.2794 0.1778)
						)
						(arc
							(start 0.2794 -0.1778)
							(mid 0.249642 -0.249642)
							(end 0.1778 -0.2794)
						)
					)
					(width 0)
					(fill yes)
				)
			)
		)
	)
	(footprint ""
		(layer "F.Cu")
		(at 127.6858 -87.2744 180)
		(property "Reference" "R102"
			(at 0 0 180)
			(layer "F.SilkS")
			(hide yes)
			(effects
				(font
					(size 1.27 1.27)
				)
			)
		)
		(property "Value" "0R2J-2-GP"
			(at 0.064008 -3.993896 180)
			(unlocked yes)
			(layer "F.Fab")
			(hide yes)
			(effects
				(font
					(size 1.016 1.016)
					(thickness 0.1524)
				)
			)
		)
		(property "Device Type" "R402H16"
			(at 0.064008 -5.517896 180)
			(unlocked yes)
			(layer "F.Fab")
			(hide yes)
			(effects
				(font
					(size 1.016 1.016)
					(thickness 0.1524)
				)
			)
		)
		(duplicate_pad_numbers_are_jumpers no)
		(fp_line
			(start 0.508 -0.9398)
			(end -0.508 -0.9398)
			(stroke
				(width 0.1524)
				(type default)
			)
			(layer "F.SilkS")
		)
		(fp_line
			(start -0.508 -0.9398)
			(end -0.508 0.9398)
			(stroke
				(width 0.1524)
				(type default)
			)
			(layer "F.SilkS")
		)
		(fp_rect
			(start -0.508 0.9398)
			(end 0.508 -0.9398)
			(stroke
				(width 0)
				(type default)
			)
			(fill no)
			(layer "F.CrtYd")
		)
		(fp_rect
			(start -0.508 0.9398)
			(end 0.508 -0.9398)
			(stroke
				(width 0)
				(type default)
			)
			(fill no)
			(layer "F.Fab")
		)
		(pad "1" smd custom
			(at 0 -0.4445 180)
			(size 0.1397 0.1397)
			(layers "F.Cu" "F.Mask" "F.Paste")
			(net "SDB_R_TX")
			(options
				(clearance outline)
				(anchor circle)
			)
			(primitives
				(gr_poly
					(pts
						(arc
							(start -0.1778 -0.2794)
							(mid -0.249642 -0.249642)
							(end -0.2794 -0.1778)
						)
						(arc
							(start -0.2794 0.1778)
							(mid -0.249642 0.249642)
							(end -0.1778 0.2794)
						)
						(arc
							(start 0.1778 0.2794)
							(mid 0.249642 0.249642)
							(end 0.2794 0.1778)
						)
						(arc
							(start 0.2794 -0.1778)
							(mid 0.249642 -0.249642)
							(end 0.1778 -0.2794)
						)
					)
					(width 0)
					(fill yes)
				)
			)
		)
		(pad "2" smd custom
			(at 0 0.4445 180)
			(size 0.1397 0.1397)
			(layers "F.Cu" "F.Mask" "F.Paste")
			(net "SDB_TX")
			(options
				(clearance outline)
				(anchor circle)
			)
			(primitives
				(gr_poly
					(pts
						(arc
							(start -0.1778 -0.2794)
							(mid -0.249642 -0.249642)
							(end -0.2794 -0.1778)
						)
						(arc
							(start -0.2794 0.1778)
							(mid -0.249642 0.249642)
							(end -0.1778 0.2794)
						)
						(arc
							(start 0.1778 0.2794)
							(mid 0.249642 0.249642)
							(end 0.2794 0.1778)
						)
						(arc
							(start 0.2794 -0.1778)
							(mid 0.249642 -0.249642)
							(end 0.1778 -0.2794)
						)
					)
					(width 0)
					(fill yes)
				)
			)
		)
	)
	(footprint ""
		(layer "F.Cu")
		(at 89.535 -88.265 -90)
		(property "Reference" "C113"
			(at 0 0 270)
			(layer "F.SilkS")
			(hide yes)
			(effects
				(font
					(size 1.27 1.27)
				)
			)
		)
		(property "Value" "SCD01U25V2KX-3GP"
			(at 1.1811 -2.7051 270)
			(unlocked yes)
			(layer "F.Fab")
			(hide yes)
			(effects
				(font
					(size 1.016 1.016)
					(thickness 0.1524)
				)
			)
		)
		(property "Device Type" "C402H22"
			(at 1.1811 -4.2291 270)
			(unlocked yes)
			(layer "F.Fab")
			(hide yes)
			(effects
				(font
					(size 1.016 1.016)
					(thickness 0.1524)
				)
			)
		)
		(duplicate_pad_numbers_are_jumpers no)
		(fp_rect
			(start -0.4318 0.9525)
			(end 0.4318 -0.9525)
			(stroke
				(width 0)
				(type default)
			)
			(fill no)
			(layer "F.CrtYd")
		)
		(fp_rect
			(start -0.4318 0.9525)
			(end 0.4318 -0.9525)
			(stroke
				(width 0)
				(type default)
			)
			(fill no)
			(layer "F.Fab")
		)
		(pad "1" smd custom
			(at 0 -0.4445 270)
			(size 0.1524 0.1524)
			(layers "F.Cu" "F.Mask" "F.Paste")
			(net "GND")
			(options
				(clearance outline)
				(anchor circle)
			)
			(primitives
				(gr_poly
					(pts
						(arc
							(start 0.3048 -0.2032)
							(mid 0.275042 -0.275042)
							(end 0.2032 -0.3048)
						)
						(arc
							(start -0.2032 -0.3048)
							(mid -0.275042 -0.275042)
							(end -0.3048 -0.2032)
						)
						(arc
							(start -0.3048 0.2032)
							(mid -0.275042 0.275042)
							(end -0.2032 0.3048)
						)
						(arc
							(start 0.2032 0.3048)
							(mid 0.275042 0.275042)
							(end 0.3048 0.2032)
						)
					)
					(width 0)
					(fill yes)
				)
			)
		)
		(pad "2" smd custom
			(at 0 0.4445 270)
			(size 0.1524 0.1524)
			(layers "F.Cu" "F.Mask" "F.Paste")
			(net "RESET_CT")
			(options
				(clearance outline)
				(anchor circle)
			)
			(primitives
				(gr_poly
					(pts
						(arc
							(start 0.3048 -0.2032)
							(mid 0.275042 -0.275042)
							(end 0.2032 -0.3048)
						)
						(arc
							(start -0.2032 -0.3048)
							(mid -0.275042 -0.275042)
							(end -0.3048 -0.2032)
						)
						(arc
							(start -0.3048 0.2032)
							(mid -0.275042 0.275042)
							(end -0.2032 0.3048)
						)
						(arc
							(start 0.2032 0.3048)
							(mid 0.275042 0.275042)
							(end 0.3048 0.2032)
						)
					)
					(width 0)
					(fill yes)
				)
			)
		)
	)
	(footprint ""
		(layer "F.Cu")
		(at 14.361414 -59.127644)
		(property "Reference" "R692"
			(at 0 0 0)
			(layer "F.SilkS")
			(hide yes)
			(effects
				(font
					(size 1.27 1.27)
				)
			)
		)
		(property "Value" "0R2J-2-GP"
			(at 0.064008 -3.993896 0)
			(unlocked yes)
			(layer "F.Fab")
			(hide yes)
			(effects
				(font
					(size 1.016 1.016)
					(thickness 0.1524)
				)
			)
		)
		(property "Device Type" "R402H16"
			(at 0.064008 -5.517896 0)
			(unlocked yes)
			(layer "F.Fab")
			(hide yes)
			(effects
				(font
					(size 1.016 1.016)
					(thickness 0.1524)
				)
			)
		)
		(duplicate_pad_numbers_are_jumpers no)
		(fp_line
			(start -0.508 -0.9398)
			(end -0.508 0.9398)
			(stroke
				(width 0.1524)
				(type default)
			)
			(layer "F.SilkS")
		)
		(fp_line
			(start 0.508 -0.9398)
			(end -0.508 -0.9398)
			(stroke
				(width 0.1524)
				(type default)
			)
			(layer "F.SilkS")
		)
		(fp_rect
			(start -0.508 0.9398)
			(end 0.508 -0.9398)
			(stroke
				(width 0)
				(type default)
			)
			(fill no)
			(layer "F.CrtYd")
		)
		(fp_rect
			(start -0.508 0.9398)
			(end 0.508 -0.9398)
			(stroke
				(width 0)
				(type default)
			)
			(fill no)
			(layer "F.Fab")
		)
		(pad "1" smd custom
			(at 0 -0.4445)
			(size 0.1397 0.1397)
			(layers "F.Cu" "F.Mask" "F.Paste")
			(net "MB0_HS_ENABLE_R")
			(options
				(clearance outline)
				(anchor circle)
			)
			(primitives
				(gr_poly
					(pts
						(arc
							(start -0.1778 -0.2794)
							(mid -0.249642 -0.249642)
							(end -0.2794 -0.1778)
						)
						(arc
							(start -0.2794 0.1778)
							(mid -0.249642 0.249642)
							(end -0.1778 0.2794)
						)
						(arc
							(start 0.1778 0.2794)
							(mid 0.249642 0.249642)
							(end 0.2794 0.1778)
						)
						(arc
							(start 0.2794 -0.1778)
							(mid 0.249642 -0.249642)
							(end 0.1778 -0.2794)
						)
					)
					(width 0)
					(fill yes)
				)
			)
		)
		(pad "2" smd custom
			(at 0 0.4445)
			(size 0.1397 0.1397)
			(layers "F.Cu" "F.Mask" "F.Paste")
			(net "MB0_HS_ENABLE")
			(options
				(clearance outline)
				(anchor circle)
			)
			(primitives
				(gr_poly
					(pts
						(arc
							(start -0.1778 -0.2794)
							(mid -0.249642 -0.249642)
							(end -0.2794 -0.1778)
						)
						(arc
							(start -0.2794 0.1778)
							(mid -0.249642 0.249642)
							(end -0.1778 0.2794)
						)
						(arc
							(start 0.1778 0.2794)
							(mid 0.249642 0.249642)
							(end 0.2794 0.1778)
						)
						(arc
							(start 0.2794 -0.1778)
							(mid 0.249642 -0.249642)
							(end 0.1778 -0.2794)
						)
					)
					(width 0)
					(fill yes)
				)
			)
		)
	)
	(footprint ""
		(layer "F.Cu")
		(at 203.691236 -73.519284)
		(property "Reference" "R230"
			(at 0 0 0)
			(layer "F.SilkS")
			(hide yes)
			(effects
				(font
					(size 1.27 1.27)
				)
			)
		)
		(property "Value" "10KR2F-2-GP"
			(at 0.064008 -3.993896 0)
			(unlocked yes)
			(layer "F.Fab")
			(hide yes)
			(effects
				(font
					(size 1.016 1.016)
					(thickness 0.1524)
				)
			)
		)
		(property "Device Type" "R402H16"
			(at 0.064008 -5.517896 0)
			(unlocked yes)
			(layer "F.Fab")
			(hide yes)
			(effects
				(font
					(size 1.016 1.016)
					(thickness 0.1524)
				)
			)
		)
		(duplicate_pad_numbers_are_jumpers no)
		(fp_line
			(start -0.508 -0.9398)
			(end -0.508 0.9398)
			(stroke
				(width 0.1524)
				(type default)
			)
			(layer "F.SilkS")
		)
		(fp_line
			(start 0.508 -0.9398)
			(end -0.508 -0.9398)
			(stroke
				(width 0.1524)
				(type default)
			)
			(layer "F.SilkS")
		)
		(fp_rect
			(start -0.508 0.9398)
			(end 0.508 -0.9398)
			(stroke
				(width 0)
				(type default)
			)
			(fill no)
			(layer "F.CrtYd")
		)
		(fp_rect
			(start -0.508 0.9398)
			(end 0.508 -0.9398)
			(stroke
				(width 0)
				(type default)
			)
			(fill no)
			(layer "F.Fab")
		)
		(pad "1" smd custom
			(at 0 -0.4445)
			(size 0.1397 0.1397)
			(layers "F.Cu" "F.Mask" "F.Paste")
			(net "P1V8_C")
			(options
				(clearance outline)
				(anchor circle)
			)
			(primitives
				(gr_poly
					(pts
						(arc
							(start -0.1778 -0.2794)
							(mid -0.249642 -0.249642)
							(end -0.2794 -0.1778)
						)
						(arc
							(start -0.2794 0.1778)
							(mid -0.249642 0.249642)
							(end -0.1778 0.2794)
						)
						(arc
							(start 0.1778 0.2794)
							(mid 0.249642 0.249642)
							(end 0.2794 0.1778)
						)
						(arc
							(start 0.2794 -0.1778)
							(mid 0.249642 -0.249642)
							(end 0.1778 -0.2794)
						)
					)
					(width 0)
					(fill yes)
				)
			)
		)
		(pad "2" smd custom
			(at 0 0.4445)
			(size 0.1397 0.1397)
			(layers "F.Cu" "F.Mask" "F.Paste")
			(net "XM_NOR_CS_N")
			(options
				(clearance outline)
				(anchor circle)
			)
			(primitives
				(gr_poly
					(pts
						(arc
							(start -0.1778 -0.2794)
							(mid -0.249642 -0.249642)
							(end -0.2794 -0.1778)
						)
						(arc
							(start -0.2794 0.1778)
							(mid -0.249642 0.249642)
							(end -0.1778 0.2794)
						)
						(arc
							(start 0.1778 0.2794)
							(mid 0.249642 0.249642)
							(end 0.2794 0.1778)
						)
						(arc
							(start 0.2794 -0.1778)
							(mid 0.249642 -0.249642)
							(end 0.1778 -0.2794)
						)
					)
					(width 0)
					(fill yes)
				)
			)
		)
	)
	(footprint ""
		(layer "F.Cu")
		(at 191.516 -32.0675 -90)
		(property "Reference" "TP61"
			(at 0 0 270)
			(layer "F.SilkS")
			(hide yes)
			(effects
				(font
					(size 1.27 1.27)
				)
			)
		)
		(property "Value" "TPAD28-2-GP"
			(at -0.0127 -1.6637 270)
			(unlocked yes)
			(layer "F.Fab")
			(hide yes)
			(effects
				(font
					(size 1.016 1.016)
					(thickness 0.1524)
				)
			)
		)
		(property "Device Type" "TPAD28"
			(at -0.0127 -3.1877 270)
			(unlocked yes)
			(layer "F.Fab")
			(hide yes)
			(effects
				(font
					(size 1.016 1.016)
					(thickness 0.1524)
				)
			)
		)
		(duplicate_pad_numbers_are_jumpers no)
		(fp_poly
			(pts
				(arc
					(start 0 -0.3556)
					(mid 0 0.3556)
					(end 0 -0.3556)
				)
			)
			(stroke
				(width 0)
				(type default)
			)
			(fill no)
			(layer "F.CrtYd")
		)
		(fp_poly
			(pts
				(arc
					(start 0 -0.6096)
					(mid 0 0.6096)
					(end 0 -0.6096)
				)
			)
			(stroke
				(width 0)
				(type default)
			)
			(fill no)
			(layer "F.Fab")
		)
		(pad "1" smd circle
			(at 0 0 270)
			(size 0.7112 0.7112)
			(layers "F.Cu" "F.Mask" "F.Paste")
			(net "IOC_GPIO_8")
		)
	)
	(footprint ""
		(layer "F.Cu")
		(at 172.26915 -23.557484 90)
		(property "Reference" "VIA4"
			(at 0 0 90)
			(layer "F.SilkS")
			(hide yes)
			(effects
				(font
					(size 1.27 1.27)
				)
			)
		)
		(property "Value" "85OHM-8L-1D6MM-L16L18-GP"
			(at 4.064 0.6096 90)
			(unlocked yes)
			(layer "F.Fab")
			(hide yes)
			(effects
				(font
					(size 1.016 1.016)
					(thickness 0.1524)
				)
			)
		)
		(property "Device Type" "VIA-PCIE-4P-368076"
			(at 4.064 -0.9144 90)
			(unlocked yes)
			(layer "F.Fab")
			(hide yes)
			(effects
				(font
					(size 1.016 1.016)
					(thickness 0.1524)
				)
			)
		)
		(duplicate_pad_numbers_are_jumpers no)
		(fp_rect
			(start -1.8415 0.381)
			(end 1.8415 -0.381)
			(stroke
				(width 0)
				(type default)
			)
			(fill no)
			(layer "F.CrtYd")
		)
		(fp_rect
			(start -1.8415 0.381)
			(end 1.8415 -0.381)
			(stroke
				(width 0)
				(type default)
			)
			(fill no)
			(layer "F.Fab")
		)
		(pad "1" thru_hole circle
			(at -1.4605 0 90)
			(size 0.508 0.508)
			(drill 0.254)
			(layers "*.Cu" "*.Mask")
			(remove_unused_layers no)
			(net "GND")
			(clearance 0.127)
			(thermal_gap 0.127)
		)
		(pad "2" thru_hole circle
			(at -0.4445 0 90)
			(size 0.508 0.508)
			(drill 0.254)
			(layers "*.Cu" "*.Mask")
			(remove_unused_layers no)
			(net "PCIE_COMP_TO_SCC_3_DP")
			(clearance 0.127)
			(thermal_gap 0.127)
		)
		(pad "3" thru_hole circle
			(at 0.4445 0 90)
			(size 0.508 0.508)
			(drill 0.254)
			(layers "*.Cu" "*.Mask")
			(remove_unused_layers no)
			(net "PCIE_COMP_TO_SCC_3_DN")
			(clearance 0.127)
			(thermal_gap 0.127)
		)
		(pad "4" thru_hole circle
			(at 1.4605 0 90)
			(size 0.508 0.508)
			(drill 0.254)
			(layers "*.Cu" "*.Mask")
			(remove_unused_layers no)
			(net "GND")
			(clearance 0.127)
			(thermal_gap 0.127)
		)
	)
	(footprint ""
		(layer "F.Cu")
		(at 149.666452 -44.762928 -78)
		(property "Reference" "VIA21"
			(at 0 0 282)
			(layer "F.SilkS")
			(hide yes)
			(effects
				(font
					(size 1.27 1.27)
				)
			)
		)
		(property "Value" "100OHM-8L-1D6MM-L13-GP"
			(at 3.289333 0.050849 282)
			(unlocked yes)
			(layer "F.Fab")
			(hide yes)
			(effects
				(font
					(size 1.016 1.016)
					(thickness 0.1524)
				)
			)
		)
		(property "Device Type" "VIA-PCIE-4P-409091"
			(at 3.289207 -1.473208 282)
			(unlocked yes)
			(layer "F.Fab")
			(hide yes)
			(effects
				(font
					(size 1.016 1.016)
					(thickness 0.1524)
				)
			)
		)
		(duplicate_pad_numbers_are_jumpers no)
		(fp_poly
			(pts
				(xy -2.044719 -0.457296) (xy 2.04468 -0.457296) (xy 2.044681 0.457104) (xy -2.044719 0.457104)
			)
			(stroke
				(width 0)
				(type default)
			)
			(fill no)
			(layer "F.CrtYd")
		)
		(fp_poly
			(pts
				(xy -2.044719 -0.457296) (xy 2.04468 -0.457296) (xy 2.044681 0.457104) (xy -2.044719 0.457104)
			)
			(stroke
				(width 0)
				(type default)
			)
			(fill no)
			(layer "F.Fab")
		)
		(pad "1" thru_hole circle
			(at -1.5875 0 282)
			(size 0.508 0.508)
			(drill 0.254)
			(layers "*.Cu" "*.Mask")
			(remove_unused_layers no)
			(net "GND")
			(clearance 0.2032)
			(thermal_gap 0.2032)
		)
		(pad "2" thru_hole circle
			(at -0.5715 0.000001 282)
			(size 0.508 0.508)
			(drill 0.254)
			(layers "*.Cu" "*.Mask")
			(remove_unused_layers no)
			(net "PHY_SCC_TO_IOC_C_44_DP")
			(clearance 0.2032)
			(thermal_gap 0.2032)
		)
		(pad "3" thru_hole circle
			(at 0.5715 -0.000001 282)
			(size 0.508 0.508)
			(drill 0.254)
			(layers "*.Cu" "*.Mask")
			(remove_unused_layers no)
			(net "PHY_SCC_TO_IOC_C_44_DN")
			(clearance 0.2032)
			(thermal_gap 0.2032)
		)
		(pad "4" thru_hole circle
			(at 1.5875 0 282)
			(size 0.508 0.508)
			(drill 0.254)
			(layers "*.Cu" "*.Mask")
			(remove_unused_layers no)
			(net "GND")
			(clearance 0.2032)
			(thermal_gap 0.2032)
		)
	)
	(footprint ""
		(layer "F.Cu")
		(at 86.037166 -55.248048)
		(property "Reference" "X1"
			(at 0 0 0)
			(layer "F.SilkS")
			(hide yes)
			(effects
				(font
					(size 1.27 1.27)
				)
			)
		)
		(property "Value" "XTAL-25MHZ-295-GP"
			(at -4.4958 -3.3782 0)
			(unlocked yes)
			(layer "F.Fab")
			(hide yes)
			(effects
				(font
					(size 1.016 1.016)
					(thickness 0.1524)
				)
			)
		)
		(property "Device Type" "SMD-OSC38H20"
			(at -4.4958 -4.9022 0)
			(unlocked yes)
			(layer "F.Fab")
			(hide yes)
			(effects
				(font
					(size 1.016 1.016)
					(thickness 0.1524)
				)
			)
		)
		(duplicate_pad_numbers_are_jumpers no)
		(fp_line
			(start -1.668272 1.2065)
			(end -1.668272 0.462788)
			(stroke
				(width 0.3302)
				(type default)
			)
			(layer "F.SilkS")
		)
		(fp_line
			(start -1.5748 -1.1176)
			(end 1.5748 -1.1176)
			(stroke
				(width 0.1524)
				(type default)
			)
			(layer "F.SilkS")
		)
		(fp_line
			(start -1.5748 1.1176)
			(end -1.5748 -1.1176)
			(stroke
				(width 0.1524)
				(type default)
			)
			(layer "F.SilkS")
		)
		(fp_line
			(start -0.659384 1.2065)
			(end -1.668272 1.2065)
			(stroke
				(width 0.3302)
				(type default)
			)
			(layer "F.SilkS")
		)
		(fp_line
			(start 1.5748 -1.1176)
			(end 1.5748 1.1176)
			(stroke
				(width 0.1524)
				(type default)
			)
			(layer "F.SilkS")
		)
		(fp_line
			(start 1.5748 1.1176)
			(end -1.5748 1.1176)
			(stroke
				(width 0.1524)
				(type default)
			)
			(layer "F.SilkS")
		)
		(fp_poly
			(pts
				(xy -2.286 1.1557) (xy -2.286 -0.1143) (xy -1.651 0.5207)
			)
			(stroke
				(width 0)
				(type default)
			)
			(fill yes)
			(layer "F.SilkS")
		)
		(fp_rect
			(start -1.0033 0.8001)
			(end 1.0033 -0.8001)
			(stroke
				(width 0)
				(type default)
			)
			(fill no)
			(layer "F.CrtYd")
		)
		(fp_poly
			(pts
				(xy -1.8288 1.3716) (xy -1.8288 -1.3716) (xy 1.8288 -1.3716) (xy 1.8288 -0.0127) (xy 1.0033 -0.0127)
				(xy 1.0033 -0.8001) (xy -1.0033 -0.8001) (xy -1.0033 0.8001) (xy 1.0033 0.8001) (xy 1.0033 0) (xy 1.8288 0)
				(xy 1.8288 1.3716)
			)
			(stroke
				(width 0)
				(type default)
			)
			(fill no)
			(layer "F.CrtYd")
		)
		(fp_rect
			(start -1.8288 1.3716)
			(end 1.8288 -1.3716)
			(stroke
				(width 0)
				(type default)
			)
			(fill no)
			(layer "F.Fab")
		)
		(pad "1" smd rect
			(at -0.769112 0.495046)
			(size 1.0922 0.7366)
			(layers "F.Cu" "F.Mask" "F.Paste")
			(net "EXP_REF_CLK_R_N")
		)
		(pad "2" smd rect
			(at 0.769112 0.495046)
			(size 1.0922 0.7366)
			(layers "F.Cu" "F.Mask" "F.Paste")
			(net "GND")
		)
		(pad "3" smd rect
			(at 0.769112 -0.495046)
			(size 1.0922 0.7366)
			(layers "F.Cu" "F.Mask" "F.Paste")
			(net "EXP_REF_CLK_P")
		)
		(pad "4" smd rect
			(at -0.769112 -0.495046)
			(size 1.0922 0.7366)
			(layers "F.Cu" "F.Mask" "F.Paste")
			(net "GND")
		)
		(zone
			(layer "F.Cu")
			(hatch none 0.5)
			(connect_pads
				(clearance 0)
			)
			(min_thickness 0.25)
			(keepout
				(tracks allowed)
				(vias not_allowed)
				(pads allowed)
				(copperpour not_allowed)
				(footprints allowed)
			)
			(placement
				(enabled no)
				(sheetname "")
			)
			(fill
				(thermal_gap 0.5)
				(thermal_bridge_width 0.5)
				(island_removal_mode 0)
			)
			(polygon
				(pts
					(xy 85.814154 -54.384702) (xy 85.814154 -55.121302) (xy 84.721954 -55.121302) (xy 84.721954 -55.374794)
					(xy 85.814154 -55.374794) (xy 85.814154 -56.111394) (xy 86.260178 -56.111394) (xy 86.260178 -55.374794)
					(xy 87.352378 -55.374794) (xy 87.352378 -55.121302) (xy 86.260178 -55.121302) (xy 86.260178 -54.384702)
				)
			)
		)
		(zone
			(layer "F.Cu")
			(hatch none 0.5)
			(connect_pads
				(clearance 0)
			)
			(min_thickness 0.25)
			(keepout
				(tracks not_allowed)
				(vias allowed)
				(pads allowed)
				(copperpour not_allowed)
				(footprints allowed)
			)
			(placement
				(enabled no)
				(sheetname "")
			)
			(fill
				(thermal_gap 0.5)
				(thermal_bridge_width 0.5)
				(island_removal_mode 0)
			)
			(polygon
				(pts
					(xy 85.814154 -54.384702) (xy 85.814154 -55.121302) (xy 84.721954 -55.121302) (xy 84.721954 -55.374794)
					(xy 85.814154 -55.374794) (xy 85.814154 -56.111394) (xy 86.260178 -56.111394) (xy 86.260178 -55.374794)
					(xy 87.352378 -55.374794) (xy 87.352378 -55.121302) (xy 86.260178 -55.121302) (xy 86.260178 -54.384702)
				)
			)
		)
	)
	(footprint ""
		(layer "F.Cu")
		(at 165.717474 -79.904082 180)
		(property "Reference" "L32"
			(at 0 0 180)
			(layer "F.SilkS")
			(hide yes)
			(effects
				(font
					(size 1.27 1.27)
				)
			)
		)
		(property "Value" "BLM41PG600-GP"
			(at -3.690874 -7.441184 180)
			(unlocked yes)
			(layer "F.Fab")
			(hide yes)
			(effects
				(font
					(size 1.016 1.016)
					(thickness 0.1524)
				)
			)
		)
		(property "Device Type" "L451616H71"
			(at -3.690874 -5.917184 180)
			(unlocked yes)
			(layer "F.Fab")
			(hide yes)
			(effects
				(font
					(size 1.016 1.016)
					(thickness 0.1524)
				)
			)
		)
		(duplicate_pad_numbers_are_jumpers no)
		(fp_line
			(start 2.8702 1.2954)
			(end 2.8702 -1.2954)
			(stroke
				(width 0.1524)
				(type default)
			)
			(layer "F.SilkS")
		)
		(fp_line
			(start 2.8702 1.2954)
			(end 2.8702 -1.2954)
			(stroke
				(width 0.1524)
				(type default)
			)
			(layer "F.SilkS")
		)
		(fp_line
			(start 2.8702 -1.2954)
			(end -2.8702 -1.2954)
			(stroke
				(width 0.1524)
				(type default)
			)
			(layer "F.SilkS")
		)
		(fp_line
			(start 2.8702 -1.2954)
			(end -2.8702 -1.2954)
			(stroke
				(width 0.1524)
				(type default)
			)
			(layer "F.SilkS")
		)
		(fp_line
			(start -2.8702 1.2954)
			(end 2.8702 1.2954)
			(stroke
				(width 0.1524)
				(type default)
			)
			(layer "F.SilkS")
		)
		(fp_line
			(start -2.8702 1.2954)
			(end 2.8702 1.2954)
			(stroke
				(width 0.1524)
				(type default)
			)
			(layer "F.SilkS")
		)
		(fp_line
			(start -2.8702 -1.2954)
			(end -2.8702 1.2954)
			(stroke
				(width 0.1524)
				(type default)
			)
			(layer "F.SilkS")
		)
		(fp_line
			(start -2.8702 -1.2954)
			(end -2.8702 1.2954)
			(stroke
				(width 0.1524)
				(type default)
			)
			(layer "F.SilkS")
		)
		(fp_poly
			(pts
				(xy -2.8702 1.2954) (xy 2.8702 1.2954) (xy 2.8702 -1.2954) (xy -2.8702 -1.2954)
			)
			(stroke
				(width 0)
				(type default)
			)
			(fill no)
			(layer "F.CrtYd")
		)
		(fp_poly
			(pts
				(xy -2.8702 1.2954) (xy 2.8702 1.2954) (xy 2.8702 -1.2954) (xy -2.8702 -1.2954)
			)
			(stroke
				(width 0)
				(type default)
			)
			(fill no)
			(layer "F.Fab")
		)
		(pad "1" smd rect
			(at -1.9685 0 180)
			(size 1.3716 1.8796)
			(layers "F.Cu" "F.Mask" "F.Paste")
			(net "P12V_STBY_SCC")
		)
		(pad "2" smd rect
			(at 1.9685 0 180)
			(size 1.3716 1.8796)
			(layers "F.Cu" "F.Mask" "F.Paste")
			(net "P12V_SYBY_VDD_U6")
		)
	)
	(footprint ""
		(layer "F.Cu")
		(at 149.521418 -54.942232 -78)
		(property "Reference" "VIA24"
			(at 0 0 282)
			(layer "F.SilkS")
			(hide yes)
			(effects
				(font
					(size 1.27 1.27)
				)
			)
		)
		(property "Value" "100OHM-8L-1D6MM-L13-GP"
			(at 3.289333 0.050849 282)
			(unlocked yes)
			(layer "F.Fab")
			(hide yes)
			(effects
				(font
					(size 1.016 1.016)
					(thickness 0.1524)
				)
			)
		)
		(property "Device Type" "VIA-PCIE-4P-409091"
			(at 3.289207 -1.473208 282)
			(unlocked yes)
			(layer "F.Fab")
			(hide yes)
			(effects
				(font
					(size 1.016 1.016)
					(thickness 0.1524)
				)
			)
		)
		(duplicate_pad_numbers_are_jumpers no)
		(fp_poly
			(pts
				(xy -2.044719 -0.457296) (xy 2.04468 -0.457296) (xy 2.044681 0.457104) (xy -2.044719 0.457104)
			)
			(stroke
				(width 0)
				(type default)
			)
			(fill no)
			(layer "F.CrtYd")
		)
		(fp_poly
			(pts
				(xy -2.044719 -0.457296) (xy 2.04468 -0.457296) (xy 2.044681 0.457104) (xy -2.044719 0.457104)
			)
			(stroke
				(width 0)
				(type default)
			)
			(fill no)
			(layer "F.Fab")
		)
		(pad "1" thru_hole circle
			(at -1.5875 0 282)
			(size 0.508 0.508)
			(drill 0.254)
			(layers "*.Cu" "*.Mask")
			(remove_unused_layers no)
			(net "GND")
			(clearance 0.2032)
			(thermal_gap 0.2032)
		)
		(pad "2" thru_hole circle
			(at -0.5715 0.000001 282)
			(size 0.508 0.508)
			(drill 0.254)
			(layers "*.Cu" "*.Mask")
			(remove_unused_layers no)
			(net "PHY_SCC_TO_IOC_C_47_DP")
			(clearance 0.2032)
			(thermal_gap 0.2032)
		)
		(pad "3" thru_hole circle
			(at 0.5715 -0.000001 282)
			(size 0.508 0.508)
			(drill 0.254)
			(layers "*.Cu" "*.Mask")
			(remove_unused_layers no)
			(net "PHY_SCC_TO_IOC_C_47_DN")
			(clearance 0.2032)
			(thermal_gap 0.2032)
		)
		(pad "4" thru_hole circle
			(at 1.5875 0 282)
			(size 0.508 0.508)
			(drill 0.254)
			(layers "*.Cu" "*.Mask")
			(remove_unused_layers no)
			(net "GND")
			(clearance 0.2032)
			(thermal_gap 0.2032)
		)
	)
	(footprint ""
		(layer "F.Cu")
		(at 65.278 -24.13 -90)
		(property "Reference" "R582"
			(at 0 0 270)
			(layer "F.SilkS")
			(hide yes)
			(effects
				(font
					(size 1.27 1.27)
				)
			)
		)
		(property "Value" "0R2J-2-GP"
			(at 0.064008 -3.993896 270)
			(unlocked yes)
			(layer "F.Fab")
			(hide yes)
			(effects
				(font
					(size 1.016 1.016)
					(thickness 0.1524)
				)
			)
		)
		(property "Device Type" "R402H16"
			(at 0.064008 -5.517896 270)
			(unlocked yes)
			(layer "F.Fab")
			(hide yes)
			(effects
				(font
					(size 1.016 1.016)
					(thickness 0.1524)
				)
			)
		)
		(duplicate_pad_numbers_are_jumpers no)
		(fp_line
			(start -0.508 -0.9398)
			(end -0.508 0.9398)
			(stroke
				(width 0.1524)
				(type default)
			)
			(layer "F.SilkS")
		)
		(fp_line
			(start 0.508 -0.9398)
			(end -0.508 -0.9398)
			(stroke
				(width 0.1524)
				(type default)
			)
			(layer "F.SilkS")
		)
		(fp_rect
			(start -0.508 0.9398)
			(end 0.508 -0.9398)
			(stroke
				(width 0)
				(type default)
			)
			(fill no)
			(layer "F.CrtYd")
		)
		(fp_rect
			(start -0.508 0.9398)
			(end 0.508 -0.9398)
			(stroke
				(width 0)
				(type default)
			)
			(fill no)
			(layer "F.Fab")
		)
		(pad "1" smd custom
			(at 0 -0.4445 270)
			(size 0.1397 0.1397)
			(layers "F.Cu" "F.Mask" "F.Paste")
			(net "SCC_FULL_PWR_EN")
			(options
				(clearance outline)
				(anchor circle)
			)
			(primitives
				(gr_poly
					(pts
						(arc
							(start -0.1778 -0.2794)
							(mid -0.249642 -0.249642)
							(end -0.2794 -0.1778)
						)
						(arc
							(start -0.2794 0.1778)
							(mid -0.249642 0.249642)
							(end -0.1778 0.2794)
						)
						(arc
							(start 0.1778 0.2794)
							(mid 0.249642 0.249642)
							(end 0.2794 0.1778)
						)
						(arc
							(start 0.2794 -0.1778)
							(mid 0.249642 -0.249642)
							(end 0.1778 -0.2794)
						)
					)
					(width 0)
					(fill yes)
				)
			)
		)
		(pad "2" smd custom
			(at 0 0.4445 270)
			(size 0.1397 0.1397)
			(layers "F.Cu" "F.Mask" "F.Paste")
			(net "SCC_FULL_PWR_EN_U49")
			(options
				(clearance outline)
				(anchor circle)
			)
			(primitives
				(gr_poly
					(pts
						(arc
							(start -0.1778 -0.2794)
							(mid -0.249642 -0.249642)
							(end -0.2794 -0.1778)
						)
						(arc
							(start -0.2794 0.1778)
							(mid -0.249642 0.249642)
							(end -0.1778 0.2794)
						)
						(arc
							(start 0.1778 0.2794)
							(mid 0.249642 0.249642)
							(end 0.2794 0.1778)
						)
						(arc
							(start 0.2794 -0.1778)
							(mid 0.249642 -0.249642)
							(end 0.1778 -0.2794)
						)
					)
					(width 0)
					(fill yes)
				)
			)
		)
	)
	(footprint ""
		(layer "F.Cu")
		(at 166.233856 -58.11901)
		(property "Reference" "R263"
			(at 0 0 0)
			(layer "F.SilkS")
			(hide yes)
			(effects
				(font
					(size 1.27 1.27)
				)
			)
		)
		(property "Value" "4K7R2F-GP"
			(at 0.064008 -3.993896 0)
			(unlocked yes)
			(layer "F.Fab")
			(hide yes)
			(effects
				(font
					(size 1.016 1.016)
					(thickness 0.1524)
				)
			)
		)
		(property "Device Type" "R402H16"
			(at 0.064008 -5.517896 0)
			(unlocked yes)
			(layer "F.Fab")
			(hide yes)
			(effects
				(font
					(size 1.016 1.016)
					(thickness 0.1524)
				)
			)
		)
		(duplicate_pad_numbers_are_jumpers no)
		(fp_line
			(start -0.508 -0.9398)
			(end -0.508 0.9398)
			(stroke
				(width 0.1524)
				(type default)
			)
			(layer "F.SilkS")
		)
		(fp_line
			(start 0.508 -0.9398)
			(end -0.508 -0.9398)
			(stroke
				(width 0.1524)
				(type default)
			)
			(layer "F.SilkS")
		)
		(fp_rect
			(start -0.508 0.9398)
			(end 0.508 -0.9398)
			(stroke
				(width 0)
				(type default)
			)
			(fill no)
			(layer "F.CrtYd")
		)
		(fp_rect
			(start -0.508 0.9398)
			(end 0.508 -0.9398)
			(stroke
				(width 0)
				(type default)
			)
			(fill no)
			(layer "F.Fab")
		)
		(pad "1" smd custom
			(at 0 -0.4445)
			(size 0.1397 0.1397)
			(layers "F.Cu" "F.Mask" "F.Paste")
			(net "P1V8_C")
			(options
				(clearance outline)
				(anchor circle)
			)
			(primitives
				(gr_poly
					(pts
						(arc
							(start -0.1778 -0.2794)
							(mid -0.249642 -0.249642)
							(end -0.2794 -0.1778)
						)
						(arc
							(start -0.2794 0.1778)
							(mid -0.249642 0.249642)
							(end -0.1778 0.2794)
						)
						(arc
							(start 0.1778 0.2794)
							(mid 0.249642 0.249642)
							(end 0.2794 0.1778)
						)
						(arc
							(start 0.2794 -0.1778)
							(mid 0.249642 -0.249642)
							(end 0.1778 -0.2794)
						)
					)
					(width 0)
					(fill yes)
				)
			)
		)
		(pad "2" smd custom
			(at 0 0.4445)
			(size 0.1397 0.1397)
			(layers "F.Cu" "F.Mask" "F.Paste")
			(net "ICE1_TCK")
			(options
				(clearance outline)
				(anchor circle)
			)
			(primitives
				(gr_poly
					(pts
						(arc
							(start -0.1778 -0.2794)
							(mid -0.249642 -0.249642)
							(end -0.2794 -0.1778)
						)
						(arc
							(start -0.2794 0.1778)
							(mid -0.249642 0.249642)
							(end -0.1778 0.2794)
						)
						(arc
							(start 0.1778 0.2794)
							(mid 0.249642 0.249642)
							(end 0.2794 0.1778)
						)
						(arc
							(start 0.2794 -0.1778)
							(mid 0.249642 -0.249642)
							(end 0.1778 -0.2794)
						)
					)
					(width 0)
					(fill yes)
				)
			)
		)
	)
	(footprint ""
		(layer "F.Cu")
		(at 139.050522 -76.52512 180)
		(property "Reference" "VIA25"
			(at 0 0 180)
			(layer "F.SilkS")
			(hide yes)
			(effects
				(font
					(size 1.27 1.27)
				)
			)
		)
		(property "Value" "100OHM-8L-1D6MM-L18L16-GP"
			(at -3.7211 -4.5085 180)
			(unlocked yes)
			(layer "F.Fab")
			(hide yes)
			(effects
				(font
					(size 1.016 1.016)
					(thickness 0.1524)
				)
			)
		)
		(property "Device Type" "VIA-PCIE-4P-394076"
			(at -3.7211 -6.0325 180)
			(unlocked yes)
			(layer "F.Fab")
			(hide yes)
			(effects
				(font
					(size 1.016 1.016)
					(thickness 0.1524)
				)
			)
		)
		(duplicate_pad_numbers_are_jumpers no)
		(fp_rect
			(start -1.9685 0.381)
			(end 1.9685 -0.381)
			(stroke
				(width 0)
				(type default)
			)
			(fill no)
			(layer "F.CrtYd")
		)
		(fp_rect
			(start -1.9685 0.381)
			(end 1.9685 -0.381)
			(stroke
				(width 0)
				(type default)
			)
			(fill no)
			(layer "F.Fab")
		)
		(pad "1" thru_hole circle
			(at -1.5875 0 180)
			(size 0.508 0.508)
			(drill 0.254)
			(layers "*.Cu" "*.Mask")
			(remove_unused_layers no)
			(net "GND")
			(clearance 0.127)
			(thermal_gap 0.127)
		)
		(pad "2" thru_hole circle
			(at -0.5715 0 180)
			(size 0.508 0.508)
			(drill 0.254)
			(layers "*.Cu" "*.Mask")
			(remove_unused_layers no)
			(net "PHY_EXP_TO_CONN_8_DP")
			(clearance 0.127)
			(thermal_gap 0.127)
		)
		(pad "3" thru_hole circle
			(at 0.5715 0 180)
			(size 0.508 0.508)
			(drill 0.254)
			(layers "*.Cu" "*.Mask")
			(remove_unused_layers no)
			(net "PHY_EXP_TO_CONN_8_DN")
			(clearance 0.127)
			(thermal_gap 0.127)
		)
		(pad "4" thru_hole circle
			(at 1.5875 0 180)
			(size 0.508 0.508)
			(drill 0.254)
			(layers "*.Cu" "*.Mask")
			(remove_unused_layers no)
			(net "GND")
			(clearance 0.127)
			(thermal_gap 0.127)
		)
	)
	(footprint ""
		(layer "F.Cu")
		(at 173.99 -110.0582 90)
		(property "Reference" "R92"
			(at 0 0 90)
			(layer "F.SilkS")
			(hide yes)
			(effects
				(font
					(size 1.27 1.27)
				)
			)
		)
		(property "Value" "0R2J-2-GP"
			(at 0.064008 -3.993896 90)
			(unlocked yes)
			(layer "F.Fab")
			(hide yes)
			(effects
				(font
					(size 1.016 1.016)
					(thickness 0.1524)
				)
			)
		)
		(property "Device Type" "R402H16"
			(at 0.064008 -5.517896 90)
			(unlocked yes)
			(layer "F.Fab")
			(hide yes)
			(effects
				(font
					(size 1.016 1.016)
					(thickness 0.1524)
				)
			)
		)
		(duplicate_pad_numbers_are_jumpers no)
		(fp_line
			(start 0.508 -0.9398)
			(end -0.508 -0.9398)
			(stroke
				(width 0.1524)
				(type default)
			)
			(layer "F.SilkS")
		)
		(fp_line
			(start -0.508 -0.9398)
			(end -0.508 0.9398)
			(stroke
				(width 0.1524)
				(type default)
			)
			(layer "F.SilkS")
		)
		(fp_rect
			(start -0.508 0.9398)
			(end 0.508 -0.9398)
			(stroke
				(width 0)
				(type default)
			)
			(fill no)
			(layer "F.CrtYd")
		)
		(fp_rect
			(start -0.508 0.9398)
			(end 0.508 -0.9398)
			(stroke
				(width 0)
				(type default)
			)
			(fill no)
			(layer "F.Fab")
		)
		(pad "1" smd custom
			(at 0 -0.4445 90)
			(size 0.1397 0.1397)
			(layers "F.Cu" "F.Mask" "F.Paste")
			(net "SCC_FULL_PWR_BUF_EN")
			(options
				(clearance outline)
				(anchor circle)
			)
			(primitives
				(gr_poly
					(pts
						(arc
							(start -0.1778 -0.2794)
							(mid -0.249642 -0.249642)
							(end -0.2794 -0.1778)
						)
						(arc
							(start -0.2794 0.1778)
							(mid -0.249642 0.249642)
							(end -0.1778 0.2794)
						)
						(arc
							(start 0.1778 0.2794)
							(mid 0.249642 0.249642)
							(end 0.2794 0.1778)
						)
						(arc
							(start 0.2794 -0.1778)
							(mid 0.249642 -0.249642)
							(end 0.1778 -0.2794)
						)
					)
					(width 0)
					(fill yes)
				)
			)
		)
		(pad "2" smd custom
			(at 0 0.4445 90)
			(size 0.1397 0.1397)
			(layers "F.Cu" "F.Mask" "F.Paste")
			(net "P1V8_E_EN")
			(options
				(clearance outline)
				(anchor circle)
			)
			(primitives
				(gr_poly
					(pts
						(arc
							(start -0.1778 -0.2794)
							(mid -0.249642 -0.249642)
							(end -0.2794 -0.1778)
						)
						(arc
							(start -0.2794 0.1778)
							(mid -0.249642 0.249642)
							(end -0.1778 0.2794)
						)
						(arc
							(start 0.1778 0.2794)
							(mid 0.249642 0.249642)
							(end 0.2794 0.1778)
						)
						(arc
							(start 0.2794 -0.1778)
							(mid 0.249642 -0.249642)
							(end 0.1778 -0.2794)
						)
					)
					(width 0)
					(fill yes)
				)
			)
		)
	)
	(footprint ""
		(layer "F.Cu")
		(at 145.249138 -32.979614 102)
		(property "Reference" "C327"
			(at 0 0 102)
			(layer "F.SilkS")
			(hide yes)
			(effects
				(font
					(size 1.27 1.27)
				)
			)
		)
		(property "Value" "SCD01U16V1KX-GP"
			(at -2.831995 -1.740026 102)
			(unlocked yes)
			(layer "F.Fab")
			(hide yes)
			(effects
				(font
					(size 1.016 1.016)
					(thickness 0.1524)
				)
			)
		)
		(property "Device Type" "C0201H13"
			(at -2.832121 -3.264082 102)
			(unlocked yes)
			(layer "F.Fab")
			(hide yes)
			(effects
				(font
					(size 1.016 1.016)
					(thickness 0.1524)
				)
			)
		)
		(duplicate_pad_numbers_are_jumpers no)
		(fp_poly
			(pts
				(xy -0.279454 -0.647706) (xy 0.279346 -0.647706) (xy 0.279346 0.647694) (xy -0.279454 0.647694)
			)
			(stroke
				(width 0)
				(type default)
			)
			(fill no)
			(layer "F.CrtYd")
		)
		(fp_poly
			(pts
				(xy -0.279454 -0.647706) (xy 0.279346 -0.647706) (xy 0.279346 0.647694) (xy -0.279454 0.647694)
			)
			(stroke
				(width 0)
				(type default)
			)
			(fill no)
			(layer "F.Fab")
		)
		(pad "1" smd custom
			(at -0.000001 -0.2794 102)
			(size 0.0762 0.0762)
			(layers "F.Cu" "F.Mask" "F.Paste")
			(net "PHY_SCC_TO_IOC_40_DP")
			(options
				(clearance outline)
				(anchor circle)
			)
			(primitives
				(gr_poly
					(pts
						(arc
							(start 0.1524 -0.127)
							(mid 0.137521 -0.162921)
							(end 0.1016 -0.1778)
						)
						(arc
							(start -0.1016 -0.1778)
							(mid -0.137521 -0.162921)
							(end -0.1524 -0.127)
						)
						(arc
							(start -0.1524 0.127)
							(mid -0.137521 0.162921)
							(end -0.1016 0.1778)
						)
						(arc
							(start 0.1016 0.1778)
							(mid 0.137521 0.162921)
							(end 0.1524 0.127)
						)
					)
					(width 0)
					(fill yes)
				)
			)
		)
		(pad "2" smd custom
			(at 0.000001 0.2794 102)
			(size 0.0762 0.0762)
			(layers "F.Cu" "F.Mask" "F.Paste")
			(net "PHY_SCC_TO_IOC_C_40_DP")
			(options
				(clearance outline)
				(anchor circle)
			)
			(primitives
				(gr_poly
					(pts
						(arc
							(start 0.1524 -0.127)
							(mid 0.137521 -0.162921)
							(end 0.1016 -0.1778)
						)
						(arc
							(start -0.1016 -0.1778)
							(mid -0.137521 -0.162921)
							(end -0.1524 -0.127)
						)
						(arc
							(start -0.1524 0.127)
							(mid -0.137521 0.162921)
							(end -0.1016 0.1778)
						)
						(arc
							(start 0.1016 0.1778)
							(mid 0.137521 0.162921)
							(end 0.1524 0.127)
						)
					)
					(width 0)
					(fill yes)
				)
			)
		)
	)
	(footprint ""
		(layer "F.Cu")
		(at 65.7098 -76.8604 180)
		(property "Reference" "R438"
			(at 0 0 180)
			(layer "F.SilkS")
			(hide yes)
			(effects
				(font
					(size 1.27 1.27)
				)
			)
		)
		(property "Value" "200KR2F-L-GP"
			(at 0.064008 -3.993896 180)
			(unlocked yes)
			(layer "F.Fab")
			(hide yes)
			(effects
				(font
					(size 1.016 1.016)
					(thickness 0.1524)
				)
			)
		)
		(property "Device Type" "R402H16"
			(at 0.064008 -5.517896 180)
			(unlocked yes)
			(layer "F.Fab")
			(hide yes)
			(effects
				(font
					(size 1.016 1.016)
					(thickness 0.1524)
				)
			)
		)
		(duplicate_pad_numbers_are_jumpers no)
		(fp_line
			(start 0.508 -0.9398)
			(end -0.508 -0.9398)
			(stroke
				(width 0.1524)
				(type default)
			)
			(layer "F.SilkS")
		)
		(fp_line
			(start -0.508 -0.9398)
			(end -0.508 0.9398)
			(stroke
				(width 0.1524)
				(type default)
			)
			(layer "F.SilkS")
		)
		(fp_rect
			(start -0.508 0.9398)
			(end 0.508 -0.9398)
			(stroke
				(width 0)
				(type default)
			)
			(fill no)
			(layer "F.CrtYd")
		)
		(fp_rect
			(start -0.508 0.9398)
			(end 0.508 -0.9398)
			(stroke
				(width 0)
				(type default)
			)
			(fill no)
			(layer "F.Fab")
		)
		(pad "1" smd custom
			(at 0 -0.4445 180)
			(size 0.1397 0.1397)
			(layers "F.Cu" "F.Mask" "F.Paste")
			(net "LS_EN_U38")
			(options
				(clearance outline)
				(anchor circle)
			)
			(primitives
				(gr_poly
					(pts
						(arc
							(start -0.1778 -0.2794)
							(mid -0.249642 -0.249642)
							(end -0.2794 -0.1778)
						)
						(arc
							(start -0.2794 0.1778)
							(mid -0.249642 0.249642)
							(end -0.1778 0.2794)
						)
						(arc
							(start 0.1778 0.2794)
							(mid 0.249642 0.249642)
							(end 0.2794 0.1778)
						)
						(arc
							(start 0.2794 -0.1778)
							(mid 0.249642 -0.249642)
							(end 0.1778 -0.2794)
						)
					)
					(width 0)
					(fill yes)
				)
			)
		)
		(pad "2" smd custom
			(at 0 0.4445 180)
			(size 0.1397 0.1397)
			(layers "F.Cu" "F.Mask" "F.Paste")
			(net "P0V9_PG")
			(options
				(clearance outline)
				(anchor circle)
			)
			(primitives
				(gr_poly
					(pts
						(arc
							(start -0.1778 -0.2794)
							(mid -0.249642 -0.249642)
							(end -0.2794 -0.1778)
						)
						(arc
							(start -0.2794 0.1778)
							(mid -0.249642 0.249642)
							(end -0.1778 0.2794)
						)
						(arc
							(start 0.1778 0.2794)
							(mid 0.249642 0.249642)
							(end 0.2794 0.1778)
						)
						(arc
							(start 0.2794 -0.1778)
							(mid 0.249642 -0.249642)
							(end 0.1778 -0.2794)
						)
					)
					(width 0)
					(fill yes)
				)
			)
		)
	)
	(footprint ""
		(layer "F.Cu")
		(at 83.80095 -108.181394)
		(property "Reference" "U48"
			(at 0 0 0)
			(layer "F.SilkS")
			(hide yes)
			(effects
				(font
					(size 1.27 1.27)
				)
			)
		)
		(property "Value" "SNLVC1G126DCKR-GP"
			(at -2.3368 -8.6868 0)
			(unlocked yes)
			(layer "F.Fab")
			(hide yes)
			(effects
				(font
					(size 1.016 1.016)
					(thickness 0.1524)
				)
			)
		)
		(property "Device Type" "SC70-5H44"
			(at -2.3114 -10.414 0)
			(unlocked yes)
			(layer "F.Fab")
			(hide yes)
			(effects
				(font
					(size 1.016 1.016)
					(thickness 0.1524)
				)
			)
		)
		(duplicate_pad_numbers_are_jumpers no)
		(fp_line
			(start -1.27 -1.7018)
			(end 1.27 -1.7018)
			(stroke
				(width 0.1524)
				(type default)
			)
			(layer "F.SilkS")
		)
		(fp_line
			(start -1.27 1.7018)
			(end -1.27 -1.7018)
			(stroke
				(width 0.1524)
				(type default)
			)
			(layer "F.SilkS")
		)
		(fp_line
			(start 0.6604 -1.8034)
			(end 1.3843 -1.8034)
			(stroke
				(width 0.3302)
				(type default)
			)
			(layer "F.SilkS")
		)
		(fp_line
			(start 1.27 -1.7018)
			(end 1.27 1.7018)
			(stroke
				(width 0.1524)
				(type default)
			)
			(layer "F.SilkS")
		)
		(fp_line
			(start 1.27 1.7018)
			(end -1.27 1.7018)
			(stroke
				(width 0.1524)
				(type default)
			)
			(layer "F.SilkS")
		)
		(fp_line
			(start 1.3843 -1.8034)
			(end 1.3843 -1.1176)
			(stroke
				(width 0.3302)
				(type default)
			)
			(layer "F.SilkS")
		)
		(fp_rect
			(start -1.524 1.9558)
			(end 1.524 -1.9558)
			(stroke
				(width 0)
				(type default)
			)
			(fill no)
			(layer "F.CrtYd")
		)
		(fp_poly
			(pts
				(xy -1.524 -1.9558) (xy 1.524 -1.9558) (xy 1.524 1.9558) (xy -1.524 1.9558)
			)
			(stroke
				(width 0)
				(type default)
			)
			(fill no)
			(layer "F.Fab")
		)
		(pad "1" smd rect
			(at 0.65024 -0.8255)
			(size 0.4064 1.2192)
			(layers "F.Cu" "F.Mask" "F.Paste")
			(net "U48_OE")
		)
		(pad "2" smd rect
			(at 0 -0.8255)
			(size 0.4064 1.2192)
			(layers "F.Cu" "F.Mask" "F.Paste")
			(net "SCC_FULL_PWR_EN_U48")
		)
		(pad "3" smd rect
			(at -0.65024 -0.8255)
			(size 0.4064 1.2192)
			(layers "F.Cu" "F.Mask" "F.Paste")
			(net "GND")
		)
		(pad "4" smd rect
			(at -0.65024 0.8255)
			(size 0.4064 1.2192)
			(layers "F.Cu" "F.Mask" "F.Paste")
			(net "SCC_FULL_PWR_BUF_EN_U48")
		)
		(pad "5" smd rect
			(at 0.65024 0.8255)
			(size 0.4064 1.2192)
			(layers "F.Cu" "F.Mask" "F.Paste")
			(net "P3V3")
		)
	)
	(footprint ""
		(layer "F.Cu")
		(at 58.547 -100.318316 90)
		(property "Reference" "R516"
			(at 0 0 90)
			(layer "F.SilkS")
			(hide yes)
			(effects
				(font
					(size 1.27 1.27)
				)
			)
		)
		(property "Value" "3D01R5F-GP"
			(at 0 -8.9535 90)
			(unlocked yes)
			(layer "F.Fab")
			(hide yes)
			(effects
				(font
					(size 1.27 1.016)
					(thickness 0.1524)
				)
			)
		)
		(property "Device Type" "R805H24"
			(at 0 -10.6299 90)
			(unlocked yes)
			(layer "F.Fab")
			(hide yes)
			(effects
				(font
					(size 1.27 1.016)
					(thickness 0.1524)
				)
			)
		)
		(duplicate_pad_numbers_are_jumpers no)
		(fp_line
			(start 0.889 -1.7018)
			(end -0.889 -1.7018)
			(stroke
				(width 0.1524)
				(type default)
			)
			(layer "F.SilkS")
		)
		(fp_line
			(start 0.889 -1.7018)
			(end 0.889 -0.381)
			(stroke
				(width 0.1524)
				(type default)
			)
			(layer "F.SilkS")
		)
		(fp_line
			(start -0.889 -1.7018)
			(end -0.889 0.2794)
			(stroke
				(width 0.1524)
				(type default)
			)
			(layer "F.SilkS")
		)
		(fp_line
			(start -0.889 0.0762)
			(end -0.889 1.7018)
			(stroke
				(width 0.1524)
				(type default)
			)
			(layer "F.SilkS")
		)
		(fp_line
			(start 0.889 1.7018)
			(end 0.889 -0.508)
			(stroke
				(width 0.1524)
				(type default)
			)
			(layer "F.SilkS")
		)
		(fp_line
			(start -0.889 1.7018)
			(end 0.889 1.7018)
			(stroke
				(width 0.1524)
				(type default)
			)
			(layer "F.SilkS")
		)
		(fp_poly
			(pts
				(xy 0.9652 -1.778) (xy 0.9652 1.778) (xy -0.9652 1.778) (xy -0.9652 -1.778)
			)
			(stroke
				(width 0)
				(type default)
			)
			(fill no)
			(layer "F.CrtYd")
		)
		(fp_rect
			(start -0.9652 1.778)
			(end 0.9652 -1.778)
			(stroke
				(width 0)
				(type default)
			)
			(fill no)
			(layer "F.Fab")
		)
		(pad "1" smd rect
			(at 0 -0.9652 90)
			(size 1.397 1.143)
			(layers "F.Cu" "F.Mask" "F.Paste")
			(net "P3V3_SNB")
		)
		(pad "2" smd rect
			(at 0 0.9652 90)
			(size 1.397 1.143)
			(layers "F.Cu" "F.Mask" "F.Paste")
			(net "GND")
		)
	)
	(footprint ""
		(layer "F.Cu")
		(at 152.164542 -96.25457 -90)
		(property "Reference" "R294"
			(at 0 0 270)
			(layer "F.SilkS")
			(hide yes)
			(effects
				(font
					(size 1.27 1.27)
				)
			)
		)
		(property "Value" "0R2J-2-GP"
			(at 0.064008 -3.993896 270)
			(unlocked yes)
			(layer "F.Fab")
			(hide yes)
			(effects
				(font
					(size 1.016 1.016)
					(thickness 0.1524)
				)
			)
		)
		(property "Device Type" "R402H16"
			(at 0.064008 -5.517896 270)
			(unlocked yes)
			(layer "F.Fab")
			(hide yes)
			(effects
				(font
					(size 1.016 1.016)
					(thickness 0.1524)
				)
			)
		)
		(duplicate_pad_numbers_are_jumpers no)
		(fp_line
			(start -0.508 -0.9398)
			(end -0.508 0.9398)
			(stroke
				(width 0.1524)
				(type default)
			)
			(layer "F.SilkS")
		)
		(fp_line
			(start 0.508 -0.9398)
			(end -0.508 -0.9398)
			(stroke
				(width 0.1524)
				(type default)
			)
			(layer "F.SilkS")
		)
		(fp_rect
			(start -0.508 0.9398)
			(end 0.508 -0.9398)
			(stroke
				(width 0)
				(type default)
			)
			(fill no)
			(layer "F.CrtYd")
		)
		(fp_rect
			(start -0.508 0.9398)
			(end 0.508 -0.9398)
			(stroke
				(width 0)
				(type default)
			)
			(fill no)
			(layer "F.Fab")
		)
		(pad "1" smd custom
			(at 0 -0.4445 270)
			(size 0.1397 0.1397)
			(layers "F.Cu" "F.Mask" "F.Paste")
			(net "SDB_RX_R")
			(options
				(clearance outline)
				(anchor circle)
			)
			(primitives
				(gr_poly
					(pts
						(arc
							(start -0.1778 -0.2794)
							(mid -0.249642 -0.249642)
							(end -0.2794 -0.1778)
						)
						(arc
							(start -0.2794 0.1778)
							(mid -0.249642 0.249642)
							(end -0.1778 0.2794)
						)
						(arc
							(start 0.1778 0.2794)
							(mid 0.249642 0.249642)
							(end 0.2794 0.1778)
						)
						(arc
							(start 0.2794 -0.1778)
							(mid 0.249642 -0.249642)
							(end 0.1778 -0.2794)
						)
					)
					(width 0)
					(fill yes)
				)
			)
		)
		(pad "2" smd custom
			(at 0 0.4445 270)
			(size 0.1397 0.1397)
			(layers "F.Cu" "F.Mask" "F.Paste")
			(net "SDB_RX")
			(options
				(clearance outline)
				(anchor circle)
			)
			(primitives
				(gr_poly
					(pts
						(arc
							(start -0.1778 -0.2794)
							(mid -0.249642 -0.249642)
							(end -0.2794 -0.1778)
						)
						(arc
							(start -0.2794 0.1778)
							(mid -0.249642 0.249642)
							(end -0.1778 0.2794)
						)
						(arc
							(start 0.1778 0.2794)
							(mid 0.249642 0.249642)
							(end 0.2794 0.1778)
						)
						(arc
							(start 0.2794 -0.1778)
							(mid 0.249642 -0.249642)
							(end 0.1778 -0.2794)
						)
					)
					(width 0)
					(fill yes)
				)
			)
		)
	)
	(footprint ""
		(layer "F.Cu")
		(at 104.7496 -86.889336 180)
		(property "Reference" "R403"
			(at 0 0 180)
			(layer "F.SilkS")
			(hide yes)
			(effects
				(font
					(size 1.27 1.27)
				)
			)
		)
		(property "Value" "10KR2F-2-GP"
			(at 0.064008 -3.993896 180)
			(unlocked yes)
			(layer "F.Fab")
			(hide yes)
			(effects
				(font
					(size 1.016 1.016)
					(thickness 0.1524)
				)
			)
		)
		(property "Device Type" "R402H16"
			(at 0.064008 -5.517896 180)
			(unlocked yes)
			(layer "F.Fab")
			(hide yes)
			(effects
				(font
					(size 1.016 1.016)
					(thickness 0.1524)
				)
			)
		)
		(duplicate_pad_numbers_are_jumpers no)
		(fp_line
			(start 0.508 -0.9398)
			(end -0.508 -0.9398)
			(stroke
				(width 0.1524)
				(type default)
			)
			(layer "F.SilkS")
		)
		(fp_line
			(start -0.508 -0.9398)
			(end -0.508 0.9398)
			(stroke
				(width 0.1524)
				(type default)
			)
			(layer "F.SilkS")
		)
		(fp_rect
			(start -0.508 0.9398)
			(end 0.508 -0.9398)
			(stroke
				(width 0)
				(type default)
			)
			(fill no)
			(layer "F.CrtYd")
		)
		(fp_rect
			(start -0.508 0.9398)
			(end 0.508 -0.9398)
			(stroke
				(width 0)
				(type default)
			)
			(fill no)
			(layer "F.Fab")
		)
		(pad "1" smd custom
			(at 0 -0.4445 180)
			(size 0.1397 0.1397)
			(layers "F.Cu" "F.Mask" "F.Paste")
			(net "SLOT_ID_0")
			(options
				(clearance outline)
				(anchor circle)
			)
			(primitives
				(gr_poly
					(pts
						(arc
							(start -0.1778 -0.2794)
							(mid -0.249642 -0.249642)
							(end -0.2794 -0.1778)
						)
						(arc
							(start -0.2794 0.1778)
							(mid -0.249642 0.249642)
							(end -0.1778 0.2794)
						)
						(arc
							(start 0.1778 0.2794)
							(mid 0.249642 0.249642)
							(end 0.2794 0.1778)
						)
						(arc
							(start 0.2794 -0.1778)
							(mid 0.249642 -0.249642)
							(end 0.1778 -0.2794)
						)
					)
					(width 0)
					(fill yes)
				)
			)
		)
		(pad "2" smd custom
			(at 0 0.4445 180)
			(size 0.1397 0.1397)
			(layers "F.Cu" "F.Mask" "F.Paste")
			(net "P1V8_E")
			(options
				(clearance outline)
				(anchor circle)
			)
			(primitives
				(gr_poly
					(pts
						(arc
							(start -0.1778 -0.2794)
							(mid -0.249642 -0.249642)
							(end -0.2794 -0.1778)
						)
						(arc
							(start -0.2794 0.1778)
							(mid -0.249642 0.249642)
							(end -0.1778 0.2794)
						)
						(arc
							(start 0.1778 0.2794)
							(mid 0.249642 0.249642)
							(end 0.2794 0.1778)
						)
						(arc
							(start 0.2794 -0.1778)
							(mid 0.249642 -0.249642)
							(end 0.1778 -0.2794)
						)
					)
					(width 0)
					(fill yes)
				)
			)
		)
	)
	(footprint ""
		(layer "F.Cu")
		(at 20.6502 -93.6752)
		(property "Reference" "R408"
			(at 0 0 0)
			(layer "F.SilkS")
			(hide yes)
			(effects
				(font
					(size 1.27 1.27)
				)
			)
		)
		(property "Value" "1KR2F-3-GP"
			(at 0.064008 -3.993896 0)
			(unlocked yes)
			(layer "F.Fab")
			(hide yes)
			(effects
				(font
					(size 1.016 1.016)
					(thickness 0.1524)
				)
			)
		)
		(property "Device Type" "R402H16"
			(at 0.064008 -5.517896 0)
			(unlocked yes)
			(layer "F.Fab")
			(hide yes)
			(effects
				(font
					(size 1.016 1.016)
					(thickness 0.1524)
				)
			)
		)
		(duplicate_pad_numbers_are_jumpers no)
		(fp_line
			(start -0.508 -0.9398)
			(end -0.508 0.9398)
			(stroke
				(width 0.1524)
				(type default)
			)
			(layer "F.SilkS")
		)
		(fp_line
			(start 0.508 -0.9398)
			(end -0.508 -0.9398)
			(stroke
				(width 0.1524)
				(type default)
			)
			(layer "F.SilkS")
		)
		(fp_rect
			(start -0.508 0.9398)
			(end 0.508 -0.9398)
			(stroke
				(width 0)
				(type default)
			)
			(fill no)
			(layer "F.CrtYd")
		)
		(fp_rect
			(start -0.508 0.9398)
			(end 0.508 -0.9398)
			(stroke
				(width 0)
				(type default)
			)
			(fill no)
			(layer "F.Fab")
		)
		(pad "1" smd custom
			(at 0 -0.4445)
			(size 0.1397 0.1397)
			(layers "F.Cu" "F.Mask" "F.Paste")
			(net "P3V3")
			(options
				(clearance outline)
				(anchor circle)
			)
			(primitives
				(gr_poly
					(pts
						(arc
							(start -0.1778 -0.2794)
							(mid -0.249642 -0.249642)
							(end -0.2794 -0.1778)
						)
						(arc
							(start -0.2794 0.1778)
							(mid -0.249642 0.249642)
							(end -0.1778 0.2794)
						)
						(arc
							(start 0.1778 0.2794)
							(mid 0.249642 0.249642)
							(end 0.2794 0.1778)
						)
						(arc
							(start 0.2794 -0.1778)
							(mid 0.249642 -0.249642)
							(end 0.1778 -0.2794)
						)
					)
					(width 0)
					(fill yes)
				)
			)
		)
		(pad "2" smd custom
			(at 0 0.4445)
			(size 0.1397 0.1397)
			(layers "F.Cu" "F.Mask" "F.Paste")
			(net "I2C_BMC_LOC_SDA0")
			(options
				(clearance outline)
				(anchor circle)
			)
			(primitives
				(gr_poly
					(pts
						(arc
							(start -0.1778 -0.2794)
							(mid -0.249642 -0.249642)
							(end -0.2794 -0.1778)
						)
						(arc
							(start -0.2794 0.1778)
							(mid -0.249642 0.249642)
							(end -0.1778 0.2794)
						)
						(arc
							(start 0.1778 0.2794)
							(mid 0.249642 0.249642)
							(end 0.2794 0.1778)
						)
						(arc
							(start 0.2794 -0.1778)
							(mid 0.249642 -0.249642)
							(end 0.1778 -0.2794)
						)
					)
					(width 0)
					(fill yes)
				)
			)
		)
	)
	(footprint ""
		(layer "F.Cu")
		(at 139.01801 -84.705952)
		(property "Reference" "R50"
			(at 0 0 0)
			(layer "F.SilkS")
			(hide yes)
			(effects
				(font
					(size 1.27 1.27)
				)
			)
		)
		(property "Value" "4K7R2F-GP"
			(at 0.064008 -3.993896 0)
			(unlocked yes)
			(layer "F.Fab")
			(hide yes)
			(effects
				(font
					(size 1.016 1.016)
					(thickness 0.1524)
				)
			)
		)
		(property "Device Type" "R402H16"
			(at 0.064008 -5.517896 0)
			(unlocked yes)
			(layer "F.Fab")
			(hide yes)
			(effects
				(font
					(size 1.016 1.016)
					(thickness 0.1524)
				)
			)
		)
		(duplicate_pad_numbers_are_jumpers no)
		(fp_line
			(start -0.508 -0.9398)
			(end -0.508 0.9398)
			(stroke
				(width 0.1524)
				(type default)
			)
			(layer "F.SilkS")
		)
		(fp_line
			(start 0.508 -0.9398)
			(end -0.508 -0.9398)
			(stroke
				(width 0.1524)
				(type default)
			)
			(layer "F.SilkS")
		)
		(fp_rect
			(start -0.508 0.9398)
			(end 0.508 -0.9398)
			(stroke
				(width 0)
				(type default)
			)
			(fill no)
			(layer "F.CrtYd")
		)
		(fp_rect
			(start -0.508 0.9398)
			(end 0.508 -0.9398)
			(stroke
				(width 0)
				(type default)
			)
			(fill no)
			(layer "F.Fab")
		)
		(pad "1" smd custom
			(at 0 -0.4445)
			(size 0.1397 0.1397)
			(layers "F.Cu" "F.Mask" "F.Paste")
			(net "P1V8_E")
			(options
				(clearance outline)
				(anchor circle)
			)
			(primitives
				(gr_poly
					(pts
						(arc
							(start -0.1778 -0.2794)
							(mid -0.249642 -0.249642)
							(end -0.2794 -0.1778)
						)
						(arc
							(start -0.2794 0.1778)
							(mid -0.249642 0.249642)
							(end -0.1778 0.2794)
						)
						(arc
							(start 0.1778 0.2794)
							(mid 0.249642 0.249642)
							(end 0.2794 0.1778)
						)
						(arc
							(start 0.2794 -0.1778)
							(mid 0.249642 -0.249642)
							(end 0.1778 -0.2794)
						)
					)
					(width 0)
					(fill yes)
				)
			)
		)
		(pad "2" smd custom
			(at 0 0.4445)
			(size 0.1397 0.1397)
			(layers "F.Cu" "F.Mask" "F.Paste")
			(net "I2C_BMC_RMT_SCL1_LS")
			(options
				(clearance outline)
				(anchor circle)
			)
			(primitives
				(gr_poly
					(pts
						(arc
							(start -0.1778 -0.2794)
							(mid -0.249642 -0.249642)
							(end -0.2794 -0.1778)
						)
						(arc
							(start -0.2794 0.1778)
							(mid -0.249642 0.249642)
							(end -0.1778 0.2794)
						)
						(arc
							(start 0.1778 0.2794)
							(mid 0.249642 0.249642)
							(end 0.2794 0.1778)
						)
						(arc
							(start 0.2794 -0.1778)
							(mid 0.249642 -0.249642)
							(end 0.1778 -0.2794)
						)
					)
					(width 0)
					(fill yes)
				)
			)
		)
	)
	(footprint ""
		(layer "F.Cu")
		(at 164.164772 -55.315612)
		(property "Reference" "TP128"
			(at 0 0 0)
			(layer "F.SilkS")
			(hide yes)
			(effects
				(font
					(size 1.27 1.27)
				)
			)
		)
		(property "Value" "TPAD28-2-GP"
			(at -0.0127 -1.6637 0)
			(unlocked yes)
			(layer "F.Fab")
			(hide yes)
			(effects
				(font
					(size 1.016 1.016)
					(thickness 0.1524)
				)
			)
		)
		(property "Device Type" "TPAD28"
			(at -0.0127 -3.1877 0)
			(unlocked yes)
			(layer "F.Fab")
			(hide yes)
			(effects
				(font
					(size 1.016 1.016)
					(thickness 0.1524)
				)
			)
		)
		(duplicate_pad_numbers_are_jumpers no)
		(fp_poly
			(pts
				(arc
					(start 0.3556 0)
					(mid -0.3556 0)
					(end 0.3556 0)
				)
			)
			(stroke
				(width 0)
				(type default)
			)
			(fill no)
			(layer "F.CrtYd")
		)
		(fp_poly
			(pts
				(arc
					(start 0.6096 0)
					(mid -0.6096 0)
					(end 0.6096 0)
				)
			)
			(stroke
				(width 0)
				(type default)
			)
			(fill no)
			(layer "F.Fab")
		)
		(pad "1" smd circle
			(at 0 0)
			(size 0.7112 0.7112)
			(layers "F.Cu" "F.Mask" "F.Paste")
			(net "ICE1_TRST#")
		)
	)
	(footprint ""
		(layer "F.Cu")
		(at 73.533 -51.689 180)
		(property "Reference" "C270"
			(at 0 0 180)
			(layer "F.SilkS")
			(hide yes)
			(effects
				(font
					(size 1.27 1.27)
				)
			)
		)
		(property "Value" "SC100U6D3V6MX-GP"
			(at -0.0762 -5.1308 180)
			(unlocked yes)
			(layer "F.Fab")
			(hide yes)
			(effects
				(font
					(size 1.016 1.016)
					(thickness 0.1524)
				)
			)
		)
		(property "Device Type" "C1206H71"
			(at -0.127 -6.6548 180)
			(unlocked yes)
			(layer "F.Fab")
			(hide yes)
			(effects
				(font
					(size 1.016 1.016)
					(thickness 0.1524)
				)
			)
		)
		(duplicate_pad_numbers_are_jumpers no)
		(fp_line
			(start 1.016 2.2352)
			(end -1.016 2.2352)
			(stroke
				(width 0.1524)
				(type default)
			)
			(layer "F.SilkS")
		)
		(fp_line
			(start 1.016 0.8382)
			(end 1.016 2.2352)
			(stroke
				(width 0.1524)
				(type default)
			)
			(layer "F.SilkS")
		)
		(fp_line
			(start 1.016 -2.2352)
			(end 1.016 -0.8382)
			(stroke
				(width 0.1524)
				(type default)
			)
			(layer "F.SilkS")
		)
		(fp_line
			(start -1.016 2.2352)
			(end -1.016 0.8382)
			(stroke
				(width 0.1524)
				(type default)
			)
			(layer "F.SilkS")
		)
		(fp_line
			(start -1.016 -0.8382)
			(end -1.016 -2.2352)
			(stroke
				(width 0.1524)
				(type default)
			)
			(layer "F.SilkS")
		)
		(fp_line
			(start -1.016 -2.2352)
			(end 1.016 -2.2352)
			(stroke
				(width 0.1524)
				(type default)
			)
			(layer "F.SilkS")
		)
		(fp_rect
			(start -1.0922 2.3114)
			(end 1.0922 -2.3114)
			(stroke
				(width 0)
				(type default)
			)
			(fill no)
			(layer "F.CrtYd")
		)
		(fp_poly
			(pts
				(xy 1.0922 -2.3114) (xy 1.0922 2.3114) (xy -1.0922 2.3114) (xy -1.0922 -2.3114)
			)
			(stroke
				(width 0)
				(type default)
			)
			(fill no)
			(layer "F.Fab")
		)
		(pad "1" smd rect
			(at 0 -1.397 180)
			(size 1.651 1.27)
			(layers "F.Cu" "F.Mask" "F.Paste")
			(net "GB_VDDA")
		)
		(pad "2" smd rect
			(at 0 1.397 180)
			(size 1.651 1.27)
			(layers "F.Cu" "F.Mask" "F.Paste")
			(net "GND")
		)
	)
	(footprint ""
		(layer "F.Cu")
		(at 174.8028 -82.677)
		(property "Reference" "L26"
			(at 0 0 0)
			(layer "F.SilkS")
			(hide yes)
			(effects
				(font
					(size 1.27 1.27)
				)
			)
		)
		(property "Value" "MPZ2012S300AT-GP"
			(at 0 -4.2418 0)
			(unlocked yes)
			(layer "F.Fab")
			(hide yes)
			(effects
				(font
					(size 1.016 1.016)
					(thickness 0.1524)
				)
			)
		)
		(property "Device Type" "L805H42"
			(at 0 -5.7912 0)
			(unlocked yes)
			(layer "F.Fab")
			(hide yes)
			(effects
				(font
					(size 1.016 1.016)
					(thickness 0.1524)
				)
			)
		)
		(duplicate_pad_numbers_are_jumpers no)
		(fp_line
			(start -0.889 -1.7018)
			(end 0.889 -1.7018)
			(stroke
				(width 0.1524)
				(type default)
			)
			(layer "F.SilkS")
		)
		(fp_line
			(start -0.889 1.7018)
			(end -0.889 -1.7018)
			(stroke
				(width 0.1524)
				(type default)
			)
			(layer "F.SilkS")
		)
		(fp_line
			(start 0.889 -1.7018)
			(end 0.889 1.7018)
			(stroke
				(width 0.1524)
				(type default)
			)
			(layer "F.SilkS")
		)
		(fp_line
			(start 0.889 1.7018)
			(end -0.889 1.7018)
			(stroke
				(width 0.1524)
				(type default)
			)
			(layer "F.SilkS")
		)
		(fp_rect
			(start -0.9652 1.778)
			(end 0.9652 -1.778)
			(stroke
				(width 0)
				(type default)
			)
			(fill no)
			(layer "F.CrtYd")
		)
		(fp_rect
			(start -0.9652 1.778)
			(end 0.9652 -1.778)
			(stroke
				(width 0)
				(type default)
			)
			(fill no)
			(layer "F.Fab")
		)
		(pad "1" smd rect
			(at 0 -0.9652)
			(size 1.397 1.143)
			(layers "F.Cu" "F.Mask" "F.Paste")
			(net "P0V975")
		)
		(pad "2" smd rect
			(at 0 0.9652)
			(size 1.397 1.143)
			(layers "F.Cu" "F.Mask" "F.Paste")
			(net "PCE_AVDD")
		)
	)
	(footprint ""
		(layer "F.Cu")
		(at 164.20084 -99.26828 90)
		(property "Reference" "C621"
			(at 0 0 90)
			(layer "F.SilkS")
			(hide yes)
			(effects
				(font
					(size 1.27 1.27)
				)
			)
		)
		(property "Value" "SC1U16V3KX-5GP"
			(at 0 -2.8194 90)
			(unlocked yes)
			(layer "F.Fab")
			(hide yes)
			(effects
				(font
					(size 1.016 1.016)
					(thickness 0.1524)
				)
			)
		)
		(property "Device Type" "C603H36"
			(at 0 -4.3434 90)
			(unlocked yes)
			(layer "F.Fab")
			(hide yes)
			(effects
				(font
					(size 1.016 1.016)
					(thickness 0.1524)
				)
			)
		)
		(duplicate_pad_numbers_are_jumpers no)
		(fp_line
			(start 0.508 0)
			(end -0.508 0)
			(stroke
				(width 0.2032)
				(type default)
			)
			(layer "F.SilkS")
		)
		(fp_rect
			(start -0.5842 1.3335)
			(end 0.5842 -1.3335)
			(stroke
				(width 0)
				(type default)
			)
			(fill no)
			(layer "F.CrtYd")
		)
		(fp_rect
			(start -0.5842 1.3335)
			(end 0.5842 -1.3335)
			(stroke
				(width 0)
				(type default)
			)
			(fill no)
			(layer "F.Fab")
		)
		(pad "1" smd custom
			(at 0 -0.762 90)
			(size 0.2159 0.2159)
			(layers "F.Cu" "F.Mask" "F.Paste")
			(net "GND")
			(options
				(clearance outline)
				(anchor circle)
			)
			(primitives
				(gr_poly
					(pts
						(arc
							(start -0.3302 -0.4318)
							(mid -0.402042 -0.402042)
							(end -0.4318 -0.3302)
						)
						(arc
							(start -0.4318 0.3302)
							(mid -0.402042 0.402042)
							(end -0.3302 0.4318)
						)
						(arc
							(start 0.3302 0.4318)
							(mid 0.402042 0.402042)
							(end 0.4318 0.3302)
						)
						(arc
							(start 0.4318 -0.3302)
							(mid 0.402042 -0.402042)
							(end 0.3302 -0.4318)
						)
					)
					(width 0)
					(fill yes)
				)
			)
		)
		(pad "2" smd custom
			(at 0 0.762 90)
			(size 0.2159 0.2159)
			(layers "F.Cu" "F.Mask" "F.Paste")
			(net "VT235_EN")
			(options
				(clearance outline)
				(anchor circle)
			)
			(primitives
				(gr_poly
					(pts
						(arc
							(start -0.3302 -0.4318)
							(mid -0.402042 -0.402042)
							(end -0.4318 -0.3302)
						)
						(arc
							(start -0.4318 0.3302)
							(mid -0.402042 0.402042)
							(end -0.3302 0.4318)
						)
						(arc
							(start 0.3302 0.4318)
							(mid 0.402042 0.402042)
							(end 0.4318 0.3302)
						)
						(arc
							(start 0.4318 -0.3302)
							(mid 0.402042 -0.402042)
							(end 0.3302 -0.4318)
						)
					)
					(width 0)
					(fill yes)
				)
			)
		)
	)
	(footprint ""
		(layer "F.Cu")
		(at 166.125398 -23.611332 90)
		(property "Reference" "VIA1"
			(at 0 0 90)
			(layer "F.SilkS")
			(hide yes)
			(effects
				(font
					(size 1.27 1.27)
				)
			)
		)
		(property "Value" "85OHM-8L-1D6MM-L16L18-GP"
			(at 4.064 0.6096 90)
			(unlocked yes)
			(layer "F.Fab")
			(hide yes)
			(effects
				(font
					(size 1.016 1.016)
					(thickness 0.1524)
				)
			)
		)
		(property "Device Type" "VIA-PCIE-4P-368076"
			(at 4.064 -0.9144 90)
			(unlocked yes)
			(layer "F.Fab")
			(hide yes)
			(effects
				(font
					(size 1.016 1.016)
					(thickness 0.1524)
				)
			)
		)
		(duplicate_pad_numbers_are_jumpers no)
		(fp_rect
			(start -1.8415 0.381)
			(end 1.8415 -0.381)
			(stroke
				(width 0)
				(type default)
			)
			(fill no)
			(layer "F.CrtYd")
		)
		(fp_rect
			(start -1.8415 0.381)
			(end 1.8415 -0.381)
			(stroke
				(width 0)
				(type default)
			)
			(fill no)
			(layer "F.Fab")
		)
		(pad "1" thru_hole circle
			(at -1.4605 0 90)
			(size 0.508 0.508)
			(drill 0.254)
			(layers "*.Cu" "*.Mask")
			(remove_unused_layers no)
			(net "GND")
			(clearance 0.127)
			(thermal_gap 0.127)
		)
		(pad "2" thru_hole circle
			(at -0.4445 0 90)
			(size 0.508 0.508)
			(drill 0.254)
			(layers "*.Cu" "*.Mask")
			(remove_unused_layers no)
			(net "PCIE_COMP_TO_SCC_0_DP")
			(clearance 0.127)
			(thermal_gap 0.127)
		)
		(pad "3" thru_hole circle
			(at 0.4445 0 90)
			(size 0.508 0.508)
			(drill 0.254)
			(layers "*.Cu" "*.Mask")
			(remove_unused_layers no)
			(net "PCIE_COMP_TO_SCC_0_DN")
			(clearance 0.127)
			(thermal_gap 0.127)
		)
		(pad "4" thru_hole circle
			(at 1.4605 0 90)
			(size 0.508 0.508)
			(drill 0.254)
			(layers "*.Cu" "*.Mask")
			(remove_unused_layers no)
			(net "GND")
			(clearance 0.127)
			(thermal_gap 0.127)
		)
	)
	(footprint ""
		(layer "F.Cu")
		(at 157.166818 -96.239076 -90)
		(property "Reference" "R315"
			(at 0 0 270)
			(layer "F.SilkS")
			(hide yes)
			(effects
				(font
					(size 1.27 1.27)
				)
			)
		)
		(property "Value" "0R2J-2-GP"
			(at 0.064008 -3.993896 270)
			(unlocked yes)
			(layer "F.Fab")
			(hide yes)
			(effects
				(font
					(size 1.016 1.016)
					(thickness 0.1524)
				)
			)
		)
		(property "Device Type" "R402H16"
			(at 0.064008 -5.517896 270)
			(unlocked yes)
			(layer "F.Fab")
			(hide yes)
			(effects
				(font
					(size 1.016 1.016)
					(thickness 0.1524)
				)
			)
		)
		(duplicate_pad_numbers_are_jumpers no)
		(fp_line
			(start -0.508 -0.9398)
			(end -0.508 0.9398)
			(stroke
				(width 0.1524)
				(type default)
			)
			(layer "F.SilkS")
		)
		(fp_line
			(start 0.508 -0.9398)
			(end -0.508 -0.9398)
			(stroke
				(width 0.1524)
				(type default)
			)
			(layer "F.SilkS")
		)
		(fp_rect
			(start -0.508 0.9398)
			(end 0.508 -0.9398)
			(stroke
				(width 0)
				(type default)
			)
			(fill no)
			(layer "F.CrtYd")
		)
		(fp_rect
			(start -0.508 0.9398)
			(end 0.508 -0.9398)
			(stroke
				(width 0)
				(type default)
			)
			(fill no)
			(layer "F.Fab")
		)
		(pad "1" smd custom
			(at 0 -0.4445 270)
			(size 0.1397 0.1397)
			(layers "F.Cu" "F.Mask" "F.Paste")
			(net "UART_EXP_RX")
			(options
				(clearance outline)
				(anchor circle)
			)
			(primitives
				(gr_poly
					(pts
						(arc
							(start -0.1778 -0.2794)
							(mid -0.249642 -0.249642)
							(end -0.2794 -0.1778)
						)
						(arc
							(start -0.2794 0.1778)
							(mid -0.249642 0.249642)
							(end -0.1778 0.2794)
						)
						(arc
							(start 0.1778 0.2794)
							(mid 0.249642 0.249642)
							(end 0.2794 0.1778)
						)
						(arc
							(start 0.2794 -0.1778)
							(mid 0.249642 -0.249642)
							(end 0.1778 -0.2794)
						)
					)
					(width 0)
					(fill yes)
				)
			)
		)
		(pad "2" smd custom
			(at 0 0.4445 270)
			(size 0.1397 0.1397)
			(layers "F.Cu" "F.Mask" "F.Paste")
			(net "EXP_SMART_RX_R")
			(options
				(clearance outline)
				(anchor circle)
			)
			(primitives
				(gr_poly
					(pts
						(arc
							(start -0.1778 -0.2794)
							(mid -0.249642 -0.249642)
							(end -0.2794 -0.1778)
						)
						(arc
							(start -0.2794 0.1778)
							(mid -0.249642 0.249642)
							(end -0.1778 0.2794)
						)
						(arc
							(start 0.1778 0.2794)
							(mid 0.249642 0.249642)
							(end 0.2794 0.1778)
						)
						(arc
							(start 0.2794 -0.1778)
							(mid 0.249642 -0.249642)
							(end 0.1778 -0.2794)
						)
					)
					(width 0)
					(fill yes)
				)
			)
		)
	)
	(footprint ""
		(layer "F.Cu")
		(at 121.92 -93.1672 90)
		(property "Reference" "R308"
			(at 0 0 90)
			(layer "F.SilkS")
			(hide yes)
			(effects
				(font
					(size 1.27 1.27)
				)
			)
		)
		(property "Value" "10KR2F-2-GP"
			(at 0.064008 -3.993896 90)
			(unlocked yes)
			(layer "F.Fab")
			(hide yes)
			(effects
				(font
					(size 1.016 1.016)
					(thickness 0.1524)
				)
			)
		)
		(property "Device Type" "R402H16"
			(at 0.064008 -5.517896 90)
			(unlocked yes)
			(layer "F.Fab")
			(hide yes)
			(effects
				(font
					(size 1.016 1.016)
					(thickness 0.1524)
				)
			)
		)
		(duplicate_pad_numbers_are_jumpers no)
		(fp_line
			(start 0.508 -0.9398)
			(end -0.508 -0.9398)
			(stroke
				(width 0.1524)
				(type default)
			)
			(layer "F.SilkS")
		)
		(fp_line
			(start -0.508 -0.9398)
			(end -0.508 0.9398)
			(stroke
				(width 0.1524)
				(type default)
			)
			(layer "F.SilkS")
		)
		(fp_rect
			(start -0.508 0.9398)
			(end 0.508 -0.9398)
			(stroke
				(width 0)
				(type default)
			)
			(fill no)
			(layer "F.CrtYd")
		)
		(fp_rect
			(start -0.508 0.9398)
			(end 0.508 -0.9398)
			(stroke
				(width 0)
				(type default)
			)
			(fill no)
			(layer "F.Fab")
		)
		(pad "1" smd custom
			(at 0 -0.4445 90)
			(size 0.1397 0.1397)
			(layers "F.Cu" "F.Mask" "F.Paste")
			(net "BMC_SPARE_1_LS")
			(options
				(clearance outline)
				(anchor circle)
			)
			(primitives
				(gr_poly
					(pts
						(arc
							(start -0.1778 -0.2794)
							(mid -0.249642 -0.249642)
							(end -0.2794 -0.1778)
						)
						(arc
							(start -0.2794 0.1778)
							(mid -0.249642 0.249642)
							(end -0.1778 0.2794)
						)
						(arc
							(start 0.1778 0.2794)
							(mid 0.249642 0.249642)
							(end 0.2794 0.1778)
						)
						(arc
							(start 0.2794 -0.1778)
							(mid 0.249642 -0.249642)
							(end 0.1778 -0.2794)
						)
					)
					(width 0)
					(fill yes)
				)
			)
		)
		(pad "2" smd custom
			(at 0 0.4445 90)
			(size 0.1397 0.1397)
			(layers "F.Cu" "F.Mask" "F.Paste")
			(net "GND")
			(options
				(clearance outline)
				(anchor circle)
			)
			(primitives
				(gr_poly
					(pts
						(arc
							(start -0.1778 -0.2794)
							(mid -0.249642 -0.249642)
							(end -0.2794 -0.1778)
						)
						(arc
							(start -0.2794 0.1778)
							(mid -0.249642 0.249642)
							(end -0.1778 0.2794)
						)
						(arc
							(start 0.1778 0.2794)
							(mid 0.249642 0.249642)
							(end 0.2794 0.1778)
						)
						(arc
							(start 0.2794 -0.1778)
							(mid 0.249642 -0.249642)
							(end 0.1778 -0.2794)
						)
					)
					(width 0)
					(fill yes)
				)
			)
		)
	)
	(footprint ""
		(layer "F.Cu")
		(at 158.81858 -99.04476 90)
		(property "Reference" "C507"
			(at 0 0 90)
			(layer "F.SilkS")
			(hide yes)
			(effects
				(font
					(size 1.27 1.27)
				)
			)
		)
		(property "Value" "SCD1U16V2KX-3GP"
			(at 1.1811 -2.7051 90)
			(unlocked yes)
			(layer "F.Fab")
			(hide yes)
			(effects
				(font
					(size 1.016 1.016)
					(thickness 0.1524)
				)
			)
		)
		(property "Device Type" "C402H22"
			(at 1.1811 -4.2291 90)
			(unlocked yes)
			(layer "F.Fab")
			(hide yes)
			(effects
				(font
					(size 1.016 1.016)
					(thickness 0.1524)
				)
			)
		)
		(duplicate_pad_numbers_are_jumpers no)
		(fp_rect
			(start -0.4318 0.9525)
			(end 0.4318 -0.9525)
			(stroke
				(width 0)
				(type default)
			)
			(fill no)
			(layer "F.CrtYd")
		)
		(fp_rect
			(start -0.4318 0.9525)
			(end 0.4318 -0.9525)
			(stroke
				(width 0)
				(type default)
			)
			(fill no)
			(layer "F.Fab")
		)
		(pad "1" smd custom
			(at 0 -0.4445 90)
			(size 0.1524 0.1524)
			(layers "F.Cu" "F.Mask" "F.Paste")
			(net "P3V3")
			(options
				(clearance outline)
				(anchor circle)
			)
			(primitives
				(gr_poly
					(pts
						(arc
							(start 0.3048 -0.2032)
							(mid 0.275042 -0.275042)
							(end 0.2032 -0.3048)
						)
						(arc
							(start -0.2032 -0.3048)
							(mid -0.275042 -0.275042)
							(end -0.3048 -0.2032)
						)
						(arc
							(start -0.3048 0.2032)
							(mid -0.275042 0.275042)
							(end -0.2032 0.3048)
						)
						(arc
							(start 0.2032 0.3048)
							(mid 0.275042 0.275042)
							(end 0.3048 0.2032)
						)
					)
					(width 0)
					(fill yes)
				)
			)
		)
		(pad "2" smd custom
			(at 0 0.4445 90)
			(size 0.1524 0.1524)
			(layers "F.Cu" "F.Mask" "F.Paste")
			(net "GND")
			(options
				(clearance outline)
				(anchor circle)
			)
			(primitives
				(gr_poly
					(pts
						(arc
							(start 0.3048 -0.2032)
							(mid 0.275042 -0.275042)
							(end 0.2032 -0.3048)
						)
						(arc
							(start -0.2032 -0.3048)
							(mid -0.275042 -0.275042)
							(end -0.3048 -0.2032)
						)
						(arc
							(start -0.3048 0.2032)
							(mid -0.275042 0.275042)
							(end -0.2032 0.3048)
						)
						(arc
							(start 0.2032 0.3048)
							(mid 0.275042 0.275042)
							(end 0.3048 0.2032)
						)
					)
					(width 0)
					(fill yes)
				)
			)
		)
	)
	(footprint ""
		(layer "F.Cu")
		(at 191.0334 -40.6527 -90)
		(property "Reference" "R256"
			(at 0 0 270)
			(layer "F.SilkS")
			(hide yes)
			(effects
				(font
					(size 1.27 1.27)
				)
			)
		)
		(property "Value" "10KR2F-2-GP"
			(at 0.064008 -3.993896 270)
			(unlocked yes)
			(layer "F.Fab")
			(hide yes)
			(effects
				(font
					(size 1.016 1.016)
					(thickness 0.1524)
				)
			)
		)
		(property "Device Type" "R402H16"
			(at 0.064008 -5.517896 270)
			(unlocked yes)
			(layer "F.Fab")
			(hide yes)
			(effects
				(font
					(size 1.016 1.016)
					(thickness 0.1524)
				)
			)
		)
		(duplicate_pad_numbers_are_jumpers no)
		(fp_line
			(start -0.508 -0.9398)
			(end -0.508 0.9398)
			(stroke
				(width 0.1524)
				(type default)
			)
			(layer "F.SilkS")
		)
		(fp_line
			(start 0.508 -0.9398)
			(end -0.508 -0.9398)
			(stroke
				(width 0.1524)
				(type default)
			)
			(layer "F.SilkS")
		)
		(fp_rect
			(start -0.508 0.9398)
			(end 0.508 -0.9398)
			(stroke
				(width 0)
				(type default)
			)
			(fill no)
			(layer "F.CrtYd")
		)
		(fp_rect
			(start -0.508 0.9398)
			(end 0.508 -0.9398)
			(stroke
				(width 0)
				(type default)
			)
			(fill no)
			(layer "F.Fab")
		)
		(pad "1" smd custom
			(at 0 -0.4445 270)
			(size 0.1397 0.1397)
			(layers "F.Cu" "F.Mask" "F.Paste")
			(net "P1V8_C")
			(options
				(clearance outline)
				(anchor circle)
			)
			(primitives
				(gr_poly
					(pts
						(arc
							(start -0.1778 -0.2794)
							(mid -0.249642 -0.249642)
							(end -0.2794 -0.1778)
						)
						(arc
							(start -0.2794 0.1778)
							(mid -0.249642 0.249642)
							(end -0.1778 0.2794)
						)
						(arc
							(start 0.1778 0.2794)
							(mid 0.249642 0.249642)
							(end 0.2794 0.1778)
						)
						(arc
							(start 0.2794 -0.1778)
							(mid 0.249642 -0.249642)
							(end 0.1778 -0.2794)
						)
					)
					(width 0)
					(fill yes)
				)
			)
		)
		(pad "2" smd custom
			(at 0 0.4445 270)
			(size 0.1397 0.1397)
			(layers "F.Cu" "F.Mask" "F.Paste")
			(net "SYS_CORE_TRI#")
			(options
				(clearance outline)
				(anchor circle)
			)
			(primitives
				(gr_poly
					(pts
						(arc
							(start -0.1778 -0.2794)
							(mid -0.249642 -0.249642)
							(end -0.2794 -0.1778)
						)
						(arc
							(start -0.2794 0.1778)
							(mid -0.249642 0.249642)
							(end -0.1778 0.2794)
						)
						(arc
							(start 0.1778 0.2794)
							(mid 0.249642 0.249642)
							(end 0.2794 0.1778)
						)
						(arc
							(start 0.2794 -0.1778)
							(mid 0.249642 -0.249642)
							(end 0.1778 -0.2794)
						)
					)
					(width 0)
					(fill yes)
				)
			)
		)
	)
	(footprint ""
		(layer "F.Cu")
		(at 173.2026 -82.4484)
		(property "Reference" "R284"
			(at 0 0 0)
			(layer "F.SilkS")
			(hide yes)
			(effects
				(font
					(size 1.27 1.27)
				)
			)
		)
		(property "Value" "D51R3F-2-GP"
			(at -0.0254 -2.5146 0)
			(unlocked yes)
			(layer "F.Fab")
			(hide yes)
			(effects
				(font
					(size 1.016 1.016)
					(thickness 0.1524)
				)
			)
		)
		(property "Device Type" "R603H22"
			(at -0.0254 -4.0386 0)
			(unlocked yes)
			(layer "F.Fab")
			(hide yes)
			(effects
				(font
					(size 1.016 1.016)
					(thickness 0.1524)
				)
			)
		)
		(duplicate_pad_numbers_are_jumpers no)
		(fp_line
			(start -0.4826 0)
			(end -0.2032 0)
			(stroke
				(width 0.2032)
				(type default)
			)
			(layer "F.SilkS")
		)
		(fp_line
			(start 0.2032 0)
			(end 0.4826 0)
			(stroke
				(width 0.2032)
				(type default)
			)
			(layer "F.SilkS")
		)
		(fp_rect
			(start -0.5842 1.3335)
			(end 0.5842 -1.3335)
			(stroke
				(width 0)
				(type default)
			)
			(fill no)
			(layer "F.CrtYd")
		)
		(fp_rect
			(start -0.5842 1.3335)
			(end 0.5842 -1.3335)
			(stroke
				(width 0)
				(type default)
			)
			(fill no)
			(layer "F.Fab")
		)
		(pad "1" smd custom
			(at 0 -0.762)
			(size 0.2159 0.2159)
			(layers "F.Cu" "F.Mask" "F.Paste")
			(net "P0V975")
			(options
				(clearance outline)
				(anchor circle)
			)
			(primitives
				(gr_poly
					(pts
						(arc
							(start -0.3302 -0.4318)
							(mid -0.402042 -0.402042)
							(end -0.4318 -0.3302)
						)
						(arc
							(start -0.4318 0.3302)
							(mid -0.402042 0.402042)
							(end -0.3302 0.4318)
						)
						(arc
							(start 0.3302 0.4318)
							(mid 0.402042 0.402042)
							(end 0.4318 0.3302)
						)
						(arc
							(start 0.4318 -0.3302)
							(mid 0.402042 -0.402042)
							(end 0.3302 -0.4318)
						)
					)
					(width 0)
					(fill yes)
				)
			)
		)
		(pad "2" smd custom
			(at 0 0.762)
			(size 0.2159 0.2159)
			(layers "F.Cu" "F.Mask" "F.Paste")
			(net "PCE_AVDD")
			(options
				(clearance outline)
				(anchor circle)
			)
			(primitives
				(gr_poly
					(pts
						(arc
							(start -0.3302 -0.4318)
							(mid -0.402042 -0.402042)
							(end -0.4318 -0.3302)
						)
						(arc
							(start -0.4318 0.3302)
							(mid -0.402042 0.402042)
							(end -0.3302 0.4318)
						)
						(arc
							(start 0.3302 0.4318)
							(mid 0.402042 0.402042)
							(end 0.4318 0.3302)
						)
						(arc
							(start 0.4318 -0.3302)
							(mid 0.402042 -0.402042)
							(end 0.3302 -0.4318)
						)
					)
					(width 0)
					(fill yes)
				)
			)
		)
	)
	(footprint ""
		(layer "F.Cu")
		(at 142.35176 -61.863986 -90)
		(property "Reference" "C35"
			(at 0 0 270)
			(layer "F.SilkS")
			(hide yes)
			(effects
				(font
					(size 1.27 1.27)
				)
			)
		)
		(property "Value" "SCD01U16V1KX-GP"
			(at -2.8321 -1.7399 270)
			(unlocked yes)
			(layer "F.Fab")
			(hide yes)
			(effects
				(font
					(size 1.016 1.016)
					(thickness 0.1524)
				)
			)
		)
		(property "Device Type" "C0201H13"
			(at -2.8321 -3.2639 270)
			(unlocked yes)
			(layer "F.Fab")
			(hide yes)
			(effects
				(font
					(size 1.016 1.016)
					(thickness 0.1524)
				)
			)
		)
		(duplicate_pad_numbers_are_jumpers no)
		(fp_rect
			(start -0.2794 0.6477)
			(end 0.2794 -0.6477)
			(stroke
				(width 0)
				(type default)
			)
			(fill no)
			(layer "F.CrtYd")
		)
		(fp_rect
			(start -0.2794 0.6477)
			(end 0.2794 -0.6477)
			(stroke
				(width 0)
				(type default)
			)
			(fill no)
			(layer "F.Fab")
		)
		(pad "1" smd custom
			(at 0 -0.2794 270)
			(size 0.0762 0.0762)
			(layers "F.Cu" "F.Mask" "F.Paste")
			(net "PHY_IOC_TO_SCC_46_DP")
			(options
				(clearance outline)
				(anchor circle)
			)
			(primitives
				(gr_poly
					(pts
						(arc
							(start 0.1524 -0.127)
							(mid 0.137521 -0.162921)
							(end 0.1016 -0.1778)
						)
						(arc
							(start -0.1016 -0.1778)
							(mid -0.137521 -0.162921)
							(end -0.1524 -0.127)
						)
						(arc
							(start -0.1524 0.127)
							(mid -0.137521 0.162921)
							(end -0.1016 0.1778)
						)
						(arc
							(start 0.1016 0.1778)
							(mid 0.137521 0.162921)
							(end 0.1524 0.127)
						)
					)
					(width 0)
					(fill yes)
				)
			)
		)
		(pad "2" smd custom
			(at 0 0.2794 270)
			(size 0.0762 0.0762)
			(layers "F.Cu" "F.Mask" "F.Paste")
			(net "PHY_IOC_TO_SCC_C_46_DP")
			(options
				(clearance outline)
				(anchor circle)
			)
			(primitives
				(gr_poly
					(pts
						(arc
							(start 0.1524 -0.127)
							(mid 0.137521 -0.162921)
							(end 0.1016 -0.1778)
						)
						(arc
							(start -0.1016 -0.1778)
							(mid -0.137521 -0.162921)
							(end -0.1524 -0.127)
						)
						(arc
							(start -0.1524 0.127)
							(mid -0.137521 0.162921)
							(end -0.1016 0.1778)
						)
						(arc
							(start 0.1016 0.1778)
							(mid 0.137521 0.162921)
							(end 0.1524 0.127)
						)
					)
					(width 0)
					(fill yes)
				)
			)
		)
	)
	(footprint ""
		(layer "F.Cu")
		(at 148.069554 -35.727386 102)
		(property "Reference" "C329"
			(at 0 0 102)
			(layer "F.SilkS")
			(hide yes)
			(effects
				(font
					(size 1.27 1.27)
				)
			)
		)
		(property "Value" "SCD01U16V1KX-GP"
			(at -2.831995 -1.740026 102)
			(unlocked yes)
			(layer "F.Fab")
			(hide yes)
			(effects
				(font
					(size 1.016 1.016)
					(thickness 0.1524)
				)
			)
		)
		(property "Device Type" "C0201H13"
			(at -2.831872 -3.264029 102)
			(unlocked yes)
			(layer "F.Fab")
			(hide yes)
			(effects
				(font
					(size 1.016 1.016)
					(thickness 0.1524)
				)
			)
		)
		(duplicate_pad_numbers_are_jumpers no)
		(fp_poly
			(pts
				(xy -0.279454 -0.647706) (xy 0.279346 -0.647706) (xy 0.279346 0.647694) (xy -0.279454 0.647694)
			)
			(stroke
				(width 0)
				(type default)
			)
			(fill no)
			(layer "F.CrtYd")
		)
		(fp_poly
			(pts
				(xy -0.279454 -0.647706) (xy 0.279346 -0.647706) (xy 0.279346 0.647694) (xy -0.279454 0.647694)
			)
			(stroke
				(width 0)
				(type default)
			)
			(fill no)
			(layer "F.Fab")
		)
		(pad "1" smd custom
			(at -0.000001 -0.2794 102)
			(size 0.0762 0.0762)
			(layers "F.Cu" "F.Mask" "F.Paste")
			(net "PHY_SCC_TO_IOC_41_DP")
			(options
				(clearance outline)
				(anchor circle)
			)
			(primitives
				(gr_poly
					(pts
						(arc
							(start 0.1524 -0.127)
							(mid 0.137521 -0.162921)
							(end 0.1016 -0.1778)
						)
						(arc
							(start -0.1016 -0.1778)
							(mid -0.137521 -0.162921)
							(end -0.1524 -0.127)
						)
						(arc
							(start -0.1524 0.127)
							(mid -0.137521 0.162921)
							(end -0.1016 0.1778)
						)
						(arc
							(start 0.1016 0.1778)
							(mid 0.137521 0.162921)
							(end 0.1524 0.127)
						)
					)
					(width 0)
					(fill yes)
				)
			)
		)
		(pad "2" smd custom
			(at 0.000001 0.2794 102)
			(size 0.0762 0.0762)
			(layers "F.Cu" "F.Mask" "F.Paste")
			(net "PHY_SCC_TO_IOC_C_41_DP")
			(options
				(clearance outline)
				(anchor circle)
			)
			(primitives
				(gr_poly
					(pts
						(arc
							(start 0.1524 -0.127)
							(mid 0.137521 -0.162921)
							(end 0.1016 -0.1778)
						)
						(arc
							(start -0.1016 -0.1778)
							(mid -0.137521 -0.162921)
							(end -0.1524 -0.127)
						)
						(arc
							(start -0.1524 0.127)
							(mid -0.137521 0.162921)
							(end -0.1016 0.1778)
						)
						(arc
							(start 0.1016 0.1778)
							(mid 0.137521 0.162921)
							(end 0.1524 0.127)
						)
					)
					(width 0)
					(fill yes)
				)
			)
		)
	)
	(footprint ""
		(layer "F.Cu")
		(at 165.461442 -84.151978 90)
		(property "Reference" "C636"
			(at 0 0 90)
			(layer "F.SilkS")
			(hide yes)
			(effects
				(font
					(size 1.27 1.27)
				)
			)
		)
		(property "Value" "SC10U16V5KX-7-GP-U"
			(at -0.0762 -6.1214 90)
			(unlocked yes)
			(layer "F.Fab")
			(hide yes)
			(effects
				(font
					(size 1.016 1.016)
					(thickness 0.1524)
				)
			)
		)
		(property "Device Type" "C805H58"
			(at -0.0762 -8.1534 90)
			(unlocked yes)
			(layer "F.Fab")
			(hide yes)
			(effects
				(font
					(size 1.016 1.016)
					(thickness 0.1524)
				)
			)
		)
		(duplicate_pad_numbers_are_jumpers no)
		(fp_line
			(start 0.635 0)
			(end -0.635 0)
			(stroke
				(width 0.508)
				(type default)
			)
			(layer "F.SilkS")
		)
		(fp_rect
			(start -0.9652 1.778)
			(end 0.9652 -1.778)
			(stroke
				(width 0)
				(type default)
			)
			(fill no)
			(layer "F.CrtYd")
		)
		(fp_poly
			(pts
				(xy -0.9652 -1.778) (xy 0.9652 -1.778) (xy 0.9652 1.778) (xy -0.9652 1.778)
			)
			(stroke
				(width 0)
				(type default)
			)
			(fill no)
			(layer "F.Fab")
		)
		(pad "1" smd rect
			(at 0 -0.9652 90)
			(size 1.397 1.143)
			(layers "F.Cu" "F.Mask" "F.Paste")
			(net "P12V_SYBY_VDD_U6")
		)
		(pad "2" smd rect
			(at 0 0.9652 90)
			(size 1.397 1.143)
			(layers "F.Cu" "F.Mask" "F.Paste")
			(net "GND")
		)
	)
	(footprint ""
		(layer "F.Cu")
		(at 196.342 -80.2132)
		(property "Reference" "TP166"
			(at 0 0 0)
			(layer "F.SilkS")
			(hide yes)
			(effects
				(font
					(size 1.27 1.27)
				)
			)
		)
		(property "Value" "TPAD28-2-GP"
			(at -0.0127 -1.6637 0)
			(unlocked yes)
			(layer "F.Fab")
			(hide yes)
			(effects
				(font
					(size 1.016 1.016)
					(thickness 0.1524)
				)
			)
		)
		(property "Device Type" "TPAD28"
			(at -0.0127 -3.1877 0)
			(unlocked yes)
			(layer "F.Fab")
			(hide yes)
			(effects
				(font
					(size 1.016 1.016)
					(thickness 0.1524)
				)
			)
		)
		(duplicate_pad_numbers_are_jumpers no)
		(fp_poly
			(pts
				(arc
					(start 0.3556 0)
					(mid -0.3556 0)
					(end 0.3556 0)
				)
			)
			(stroke
				(width 0)
				(type default)
			)
			(fill no)
			(layer "F.CrtYd")
		)
		(fp_poly
			(pts
				(arc
					(start 0.6096 0)
					(mid -0.6096 0)
					(end 0.6096 0)
				)
			)
			(stroke
				(width 0)
				(type default)
			)
			(fill no)
			(layer "F.Fab")
		)
		(pad "1" smd circle
			(at 0 0)
			(size 0.7112 0.7112)
			(layers "F.Cu" "F.Mask" "F.Paste")
			(net "TEMP2_ALERT")
		)
	)
	(footprint ""
		(layer "F.Cu")
		(at 57.431686 -21.500846 180)
		(property "Reference" "U47"
			(at 0 0 180)
			(layer "F.SilkS")
			(hide yes)
			(effects
				(font
					(size 1.27 1.27)
				)
			)
		)
		(property "Value" "SNLVC1G126DCKR-GP"
			(at -2.3368 -8.6868 180)
			(unlocked yes)
			(layer "F.Fab")
			(hide yes)
			(effects
				(font
					(size 1.016 1.016)
					(thickness 0.1524)
				)
			)
		)
		(property "Device Type" "SC70-5H44"
			(at -2.3114 -10.414 180)
			(unlocked yes)
			(layer "F.Fab")
			(hide yes)
			(effects
				(font
					(size 1.016 1.016)
					(thickness 0.1524)
				)
			)
		)
		(duplicate_pad_numbers_are_jumpers no)
		(fp_line
			(start 1.3843 -1.8034)
			(end 1.3843 -1.1176)
			(stroke
				(width 0.3302)
				(type default)
			)
			(layer "F.SilkS")
		)
		(fp_line
			(start 1.27 1.7018)
			(end -1.27 1.7018)
			(stroke
				(width 0.1524)
				(type default)
			)
			(layer "F.SilkS")
		)
		(fp_line
			(start 1.27 -1.7018)
			(end 1.27 1.7018)
			(stroke
				(width 0.1524)
				(type default)
			)
			(layer "F.SilkS")
		)
		(fp_line
			(start 0.6604 -1.8034)
			(end 1.3843 -1.8034)
			(stroke
				(width 0.3302)
				(type default)
			)
			(layer "F.SilkS")
		)
		(fp_line
			(start -1.27 1.7018)
			(end -1.27 -1.7018)
			(stroke
				(width 0.1524)
				(type default)
			)
			(layer "F.SilkS")
		)
		(fp_line
			(start -1.27 -1.7018)
			(end 1.27 -1.7018)
			(stroke
				(width 0.1524)
				(type default)
			)
			(layer "F.SilkS")
		)
		(fp_rect
			(start -1.524 1.9558)
			(end 1.524 -1.9558)
			(stroke
				(width 0)
				(type default)
			)
			(fill no)
			(layer "F.CrtYd")
		)
		(fp_poly
			(pts
				(xy -1.524 -1.9558) (xy 1.524 -1.9558) (xy 1.524 1.9558) (xy -1.524 1.9558)
			)
			(stroke
				(width 0)
				(type default)
			)
			(fill no)
			(layer "F.Fab")
		)
		(pad "1" smd rect
			(at 0.65024 -0.8255 180)
			(size 0.4064 1.2192)
			(layers "F.Cu" "F.Mask" "F.Paste")
			(net "U47_OE")
		)
		(pad "2" smd rect
			(at 0 -0.8255 180)
			(size 0.4064 1.2192)
			(layers "F.Cu" "F.Mask" "F.Paste")
			(net "SCC_STBY_PWR_EN")
		)
		(pad "3" smd rect
			(at -0.65024 -0.8255 180)
			(size 0.4064 1.2192)
			(layers "F.Cu" "F.Mask" "F.Paste")
			(net "GND")
		)
		(pad "4" smd rect
			(at -0.65024 0.8255 180)
			(size 0.4064 1.2192)
			(layers "F.Cu" "F.Mask" "F.Paste")
			(net "SCC_STBY_PWR_BUF_EN")
		)
		(pad "5" smd rect
			(at 0.65024 0.8255 180)
			(size 0.4064 1.2192)
			(layers "F.Cu" "F.Mask" "F.Paste")
			(net "P3V3_DPB")
		)
	)
	(footprint ""
		(layer "F.Cu")
		(at 7.6962 -55.245 -90)
		(property "Reference" "C108"
			(at 0 0 270)
			(layer "F.SilkS")
			(hide yes)
			(effects
				(font
					(size 1.27 1.27)
				)
			)
		)
		(property "Value" "SC2D2U25V5KX-2-GP"
			(at -0.0762 -6.1214 270)
			(unlocked yes)
			(layer "F.Fab")
			(hide yes)
			(effects
				(font
					(size 1.016 1.016)
					(thickness 0.1524)
				)
			)
		)
		(property "Device Type" "C805H54"
			(at -0.0762 -8.1534 270)
			(unlocked yes)
			(layer "F.Fab")
			(hide yes)
			(effects
				(font
					(size 1.016 1.016)
					(thickness 0.1524)
				)
			)
		)
		(duplicate_pad_numbers_are_jumpers no)
		(fp_line
			(start 0.635 0)
			(end -0.635 0)
			(stroke
				(width 0.508)
				(type default)
			)
			(layer "F.SilkS")
		)
		(fp_rect
			(start -0.9652 1.778)
			(end 0.9652 -1.778)
			(stroke
				(width 0)
				(type default)
			)
			(fill no)
			(layer "F.CrtYd")
		)
		(fp_poly
			(pts
				(xy -0.9652 -1.778) (xy 0.9652 -1.778) (xy 0.9652 1.778) (xy -0.9652 1.778)
			)
			(stroke
				(width 0)
				(type default)
			)
			(fill no)
			(layer "F.Fab")
		)
		(pad "1" smd rect
			(at 0 -0.9652 270)
			(size 1.397 1.143)
			(layers "F.Cu" "F.Mask" "F.Paste")
			(net "P12V_SCC_PGOOD")
		)
		(pad "2" smd rect
			(at 0 0.9652 270)
			(size 1.397 1.143)
			(layers "F.Cu" "F.Mask" "F.Paste")
			(net "GND")
		)
	)
	(footprint ""
		(layer "F.Cu")
		(at 99.224846 -86.503002 -90)
		(property "Reference" "R77"
			(at 0 0 270)
			(layer "F.SilkS")
			(hide yes)
			(effects
				(font
					(size 1.27 1.27)
				)
			)
		)
		(property "Value" "4K7R2F-GP"
			(at 0.064008 -3.993896 270)
			(unlocked yes)
			(layer "F.Fab")
			(hide yes)
			(effects
				(font
					(size 1.016 1.016)
					(thickness 0.1524)
				)
			)
		)
		(property "Device Type" "R402H16"
			(at 0.064008 -5.517896 270)
			(unlocked yes)
			(layer "F.Fab")
			(hide yes)
			(effects
				(font
					(size 1.016 1.016)
					(thickness 0.1524)
				)
			)
		)
		(duplicate_pad_numbers_are_jumpers no)
		(fp_line
			(start -0.508 -0.9398)
			(end -0.508 0.9398)
			(stroke
				(width 0.1524)
				(type default)
			)
			(layer "F.SilkS")
		)
		(fp_line
			(start 0.508 -0.9398)
			(end -0.508 -0.9398)
			(stroke
				(width 0.1524)
				(type default)
			)
			(layer "F.SilkS")
		)
		(fp_rect
			(start -0.508 0.9398)
			(end 0.508 -0.9398)
			(stroke
				(width 0)
				(type default)
			)
			(fill no)
			(layer "F.CrtYd")
		)
		(fp_rect
			(start -0.508 0.9398)
			(end 0.508 -0.9398)
			(stroke
				(width 0)
				(type default)
			)
			(fill no)
			(layer "F.Fab")
		)
		(pad "1" smd custom
			(at 0 -0.4445 270)
			(size 0.1397 0.1397)
			(layers "F.Cu" "F.Mask" "F.Paste")
			(net "SCC_TYPE_1_LS")
			(options
				(clearance outline)
				(anchor circle)
			)
			(primitives
				(gr_poly
					(pts
						(arc
							(start -0.1778 -0.2794)
							(mid -0.249642 -0.249642)
							(end -0.2794 -0.1778)
						)
						(arc
							(start -0.2794 0.1778)
							(mid -0.249642 0.249642)
							(end -0.1778 0.2794)
						)
						(arc
							(start 0.1778 0.2794)
							(mid 0.249642 0.249642)
							(end 0.2794 0.1778)
						)
						(arc
							(start 0.2794 -0.1778)
							(mid 0.249642 -0.249642)
							(end 0.1778 -0.2794)
						)
					)
					(width 0)
					(fill yes)
				)
			)
		)
		(pad "2" smd custom
			(at 0 0.4445 270)
			(size 0.1397 0.1397)
			(layers "F.Cu" "F.Mask" "F.Paste")
			(net "GND")
			(options
				(clearance outline)
				(anchor circle)
			)
			(primitives
				(gr_poly
					(pts
						(arc
							(start -0.1778 -0.2794)
							(mid -0.249642 -0.249642)
							(end -0.2794 -0.1778)
						)
						(arc
							(start -0.2794 0.1778)
							(mid -0.249642 0.249642)
							(end -0.1778 0.2794)
						)
						(arc
							(start 0.1778 0.2794)
							(mid 0.249642 0.249642)
							(end 0.2794 0.1778)
						)
						(arc
							(start 0.2794 -0.1778)
							(mid 0.249642 -0.249642)
							(end 0.1778 -0.2794)
						)
					)
					(width 0)
					(fill yes)
				)
			)
		)
	)
	(footprint ""
		(layer "F.Cu")
		(at 187.3758 -22.9362 -90)
		(property "Reference" "R270"
			(at 0 0 270)
			(layer "F.SilkS")
			(hide yes)
			(effects
				(font
					(size 1.27 1.27)
				)
			)
		)
		(property "Value" "10KR2F-2-GP"
			(at 0.064008 -3.993896 270)
			(unlocked yes)
			(layer "F.Fab")
			(hide yes)
			(effects
				(font
					(size 1.016 1.016)
					(thickness 0.1524)
				)
			)
		)
		(property "Device Type" "R402H16"
			(at 0.064008 -5.517896 270)
			(unlocked yes)
			(layer "F.Fab")
			(hide yes)
			(effects
				(font
					(size 1.016 1.016)
					(thickness 0.1524)
				)
			)
		)
		(duplicate_pad_numbers_are_jumpers no)
		(fp_line
			(start -0.508 -0.9398)
			(end -0.508 0.9398)
			(stroke
				(width 0.1524)
				(type default)
			)
			(layer "F.SilkS")
		)
		(fp_line
			(start 0.508 -0.9398)
			(end -0.508 -0.9398)
			(stroke
				(width 0.1524)
				(type default)
			)
			(layer "F.SilkS")
		)
		(fp_rect
			(start -0.508 0.9398)
			(end 0.508 -0.9398)
			(stroke
				(width 0)
				(type default)
			)
			(fill no)
			(layer "F.CrtYd")
		)
		(fp_rect
			(start -0.508 0.9398)
			(end 0.508 -0.9398)
			(stroke
				(width 0)
				(type default)
			)
			(fill no)
			(layer "F.Fab")
		)
		(pad "1" smd custom
			(at 0 -0.4445 270)
			(size 0.1397 0.1397)
			(layers "F.Cu" "F.Mask" "F.Paste")
			(net "SYS_DBMODE3")
			(options
				(clearance outline)
				(anchor circle)
			)
			(primitives
				(gr_poly
					(pts
						(arc
							(start -0.1778 -0.2794)
							(mid -0.249642 -0.249642)
							(end -0.2794 -0.1778)
						)
						(arc
							(start -0.2794 0.1778)
							(mid -0.249642 0.249642)
							(end -0.1778 0.2794)
						)
						(arc
							(start 0.1778 0.2794)
							(mid 0.249642 0.249642)
							(end 0.2794 0.1778)
						)
						(arc
							(start 0.2794 -0.1778)
							(mid 0.249642 -0.249642)
							(end 0.1778 -0.2794)
						)
					)
					(width 0)
					(fill yes)
				)
			)
		)
		(pad "2" smd custom
			(at 0 0.4445 270)
			(size 0.1397 0.1397)
			(layers "F.Cu" "F.Mask" "F.Paste")
			(net "GND")
			(options
				(clearance outline)
				(anchor circle)
			)
			(primitives
				(gr_poly
					(pts
						(arc
							(start -0.1778 -0.2794)
							(mid -0.249642 -0.249642)
							(end -0.2794 -0.1778)
						)
						(arc
							(start -0.2794 0.1778)
							(mid -0.249642 0.249642)
							(end -0.1778 0.2794)
						)
						(arc
							(start 0.1778 0.2794)
							(mid 0.249642 0.249642)
							(end 0.2794 0.1778)
						)
						(arc
							(start 0.2794 -0.1778)
							(mid 0.249642 -0.249642)
							(end 0.1778 -0.2794)
						)
					)
					(width 0)
					(fill yes)
				)
			)
		)
	)
	(footprint ""
		(layer "F.Cu")
		(at 92.583 -77.0128 90)
		(property "Reference" "R122"
			(at 0 0 90)
			(layer "F.SilkS")
			(hide yes)
			(effects
				(font
					(size 1.27 1.27)
				)
			)
		)
		(property "Value" "4K75R2F-1-GP"
			(at 0.064008 -3.993896 90)
			(unlocked yes)
			(layer "F.Fab")
			(hide yes)
			(effects
				(font
					(size 1.016 1.016)
					(thickness 0.1524)
				)
			)
		)
		(property "Device Type" "R402H16"
			(at 0.064008 -5.517896 90)
			(unlocked yes)
			(layer "F.Fab")
			(hide yes)
			(effects
				(font
					(size 1.016 1.016)
					(thickness 0.1524)
				)
			)
		)
		(duplicate_pad_numbers_are_jumpers no)
		(fp_line
			(start 0.508 -0.9398)
			(end -0.508 -0.9398)
			(stroke
				(width 0.1524)
				(type default)
			)
			(layer "F.SilkS")
		)
		(fp_line
			(start -0.508 -0.9398)
			(end -0.508 0.9398)
			(stroke
				(width 0.1524)
				(type default)
			)
			(layer "F.SilkS")
		)
		(fp_rect
			(start -0.508 0.9398)
			(end 0.508 -0.9398)
			(stroke
				(width 0)
				(type default)
			)
			(fill no)
			(layer "F.CrtYd")
		)
		(fp_rect
			(start -0.508 0.9398)
			(end 0.508 -0.9398)
			(stroke
				(width 0)
				(type default)
			)
			(fill no)
			(layer "F.Fab")
		)
		(pad "1" smd custom
			(at 0 -0.4445 90)
			(size 0.1397 0.1397)
			(layers "F.Cu" "F.Mask" "F.Paste")
			(net "P1V8_E")
			(options
				(clearance outline)
				(anchor circle)
			)
			(primitives
				(gr_poly
					(pts
						(arc
							(start -0.1778 -0.2794)
							(mid -0.249642 -0.249642)
							(end -0.2794 -0.1778)
						)
						(arc
							(start -0.2794 0.1778)
							(mid -0.249642 0.249642)
							(end -0.1778 0.2794)
						)
						(arc
							(start 0.1778 0.2794)
							(mid 0.249642 0.249642)
							(end 0.2794 0.1778)
						)
						(arc
							(start 0.2794 -0.1778)
							(mid 0.249642 -0.249642)
							(end 0.1778 -0.2794)
						)
					)
					(width 0)
					(fill yes)
				)
			)
		)
		(pad "2" smd custom
			(at 0 0.4445 90)
			(size 0.1397 0.1397)
			(layers "F.Cu" "F.Mask" "F.Paste")
			(net "EXP_CLK_SEL1")
			(options
				(clearance outline)
				(anchor circle)
			)
			(primitives
				(gr_poly
					(pts
						(arc
							(start -0.1778 -0.2794)
							(mid -0.249642 -0.249642)
							(end -0.2794 -0.1778)
						)
						(arc
							(start -0.2794 0.1778)
							(mid -0.249642 0.249642)
							(end -0.1778 0.2794)
						)
						(arc
							(start 0.1778 0.2794)
							(mid 0.249642 0.249642)
							(end 0.2794 0.1778)
						)
						(arc
							(start 0.2794 -0.1778)
							(mid 0.249642 -0.249642)
							(end 0.1778 -0.2794)
						)
					)
					(width 0)
					(fill yes)
				)
			)
		)
	)
	(footprint ""
		(layer "F.Cu")
		(at 191.1858 -24.8412 90)
		(property "Reference" "R271"
			(at 0 0 90)
			(layer "F.SilkS")
			(hide yes)
			(effects
				(font
					(size 1.27 1.27)
				)
			)
		)
		(property "Value" "10KR2F-2-GP"
			(at 0.064008 -3.993896 90)
			(unlocked yes)
			(layer "F.Fab")
			(hide yes)
			(effects
				(font
					(size 1.016 1.016)
					(thickness 0.1524)
				)
			)
		)
		(property "Device Type" "R402H16"
			(at 0.064008 -5.517896 90)
			(unlocked yes)
			(layer "F.Fab")
			(hide yes)
			(effects
				(font
					(size 1.016 1.016)
					(thickness 0.1524)
				)
			)
		)
		(duplicate_pad_numbers_are_jumpers no)
		(fp_line
			(start 0.508 -0.9398)
			(end -0.508 -0.9398)
			(stroke
				(width 0.1524)
				(type default)
			)
			(layer "F.SilkS")
		)
		(fp_line
			(start -0.508 -0.9398)
			(end -0.508 0.9398)
			(stroke
				(width 0.1524)
				(type default)
			)
			(layer "F.SilkS")
		)
		(fp_rect
			(start -0.508 0.9398)
			(end 0.508 -0.9398)
			(stroke
				(width 0)
				(type default)
			)
			(fill no)
			(layer "F.CrtYd")
		)
		(fp_rect
			(start -0.508 0.9398)
			(end 0.508 -0.9398)
			(stroke
				(width 0)
				(type default)
			)
			(fill no)
			(layer "F.Fab")
		)
		(pad "1" smd custom
			(at 0 -0.4445 90)
			(size 0.1397 0.1397)
			(layers "F.Cu" "F.Mask" "F.Paste")
			(net "SYS_DBMODE2")
			(options
				(clearance outline)
				(anchor circle)
			)
			(primitives
				(gr_poly
					(pts
						(arc
							(start -0.1778 -0.2794)
							(mid -0.249642 -0.249642)
							(end -0.2794 -0.1778)
						)
						(arc
							(start -0.2794 0.1778)
							(mid -0.249642 0.249642)
							(end -0.1778 0.2794)
						)
						(arc
							(start 0.1778 0.2794)
							(mid 0.249642 0.249642)
							(end 0.2794 0.1778)
						)
						(arc
							(start 0.2794 -0.1778)
							(mid 0.249642 -0.249642)
							(end 0.1778 -0.2794)
						)
					)
					(width 0)
					(fill yes)
				)
			)
		)
		(pad "2" smd custom
			(at 0 0.4445 90)
			(size 0.1397 0.1397)
			(layers "F.Cu" "F.Mask" "F.Paste")
			(net "GND")
			(options
				(clearance outline)
				(anchor circle)
			)
			(primitives
				(gr_poly
					(pts
						(arc
							(start -0.1778 -0.2794)
							(mid -0.249642 -0.249642)
							(end -0.2794 -0.1778)
						)
						(arc
							(start -0.2794 0.1778)
							(mid -0.249642 0.249642)
							(end -0.1778 0.2794)
						)
						(arc
							(start 0.1778 0.2794)
							(mid 0.249642 0.249642)
							(end 0.2794 0.1778)
						)
						(arc
							(start 0.2794 -0.1778)
							(mid 0.249642 -0.249642)
							(end 0.1778 -0.2794)
						)
					)
					(width 0)
					(fill yes)
				)
			)
		)
	)
	(footprint ""
		(layer "F.Cu")
		(at 169.460164 -55.167276)
		(property "Reference" "TP119"
			(at 0 0 0)
			(layer "F.SilkS")
			(hide yes)
			(effects
				(font
					(size 1.27 1.27)
				)
			)
		)
		(property "Value" "TPAD28-2-GP"
			(at -0.0127 -1.6637 0)
			(unlocked yes)
			(layer "F.Fab")
			(hide yes)
			(effects
				(font
					(size 1.016 1.016)
					(thickness 0.1524)
				)
			)
		)
		(property "Device Type" "TPAD28"
			(at -0.0127 -3.1877 0)
			(unlocked yes)
			(layer "F.Fab")
			(hide yes)
			(effects
				(font
					(size 1.016 1.016)
					(thickness 0.1524)
				)
			)
		)
		(duplicate_pad_numbers_are_jumpers no)
		(fp_poly
			(pts
				(arc
					(start 0.3556 0)
					(mid -0.3556 0)
					(end 0.3556 0)
				)
			)
			(stroke
				(width 0)
				(type default)
			)
			(fill no)
			(layer "F.CrtYd")
		)
		(fp_poly
			(pts
				(arc
					(start 0.6096 0)
					(mid -0.6096 0)
					(end 0.6096 0)
				)
			)
			(stroke
				(width 0)
				(type default)
			)
			(fill no)
			(layer "F.Fab")
		)
		(pad "1" smd circle
			(at 0 0)
			(size 0.7112 0.7112)
			(layers "F.Cu" "F.Mask" "F.Paste")
			(net "ICE0_TCK")
		)
	)
	(footprint ""
		(layer "F.Cu")
		(at 92.808298 -65.966086)
		(property "Reference" "R581"
			(at 0 0 0)
			(layer "F.SilkS")
			(hide yes)
			(effects
				(font
					(size 1.27 1.27)
				)
			)
		)
		(property "Value" "0R2J-2-GP"
			(at 0.064008 -3.993896 0)
			(unlocked yes)
			(layer "F.Fab")
			(hide yes)
			(effects
				(font
					(size 1.016 1.016)
					(thickness 0.1524)
				)
			)
		)
		(property "Device Type" "R402H16"
			(at 0.064008 -5.517896 0)
			(unlocked yes)
			(layer "F.Fab")
			(hide yes)
			(effects
				(font
					(size 1.016 1.016)
					(thickness 0.1524)
				)
			)
		)
		(duplicate_pad_numbers_are_jumpers no)
		(fp_line
			(start -0.508 -0.9398)
			(end -0.508 0.9398)
			(stroke
				(width 0.1524)
				(type default)
			)
			(layer "F.SilkS")
		)
		(fp_line
			(start 0.508 -0.9398)
			(end -0.508 -0.9398)
			(stroke
				(width 0.1524)
				(type default)
			)
			(layer "F.SilkS")
		)
		(fp_rect
			(start -0.508 0.9398)
			(end 0.508 -0.9398)
			(stroke
				(width 0)
				(type default)
			)
			(fill no)
			(layer "F.CrtYd")
		)
		(fp_rect
			(start -0.508 0.9398)
			(end 0.508 -0.9398)
			(stroke
				(width 0)
				(type default)
			)
			(fill no)
			(layer "F.Fab")
		)
		(pad "1" smd custom
			(at 0 -0.4445)
			(size 0.1397 0.1397)
			(layers "F.Cu" "F.Mask" "F.Paste")
			(net "GND")
			(options
				(clearance outline)
				(anchor circle)
			)
			(primitives
				(gr_poly
					(pts
						(arc
							(start -0.1778 -0.2794)
							(mid -0.249642 -0.249642)
							(end -0.2794 -0.1778)
						)
						(arc
							(start -0.2794 0.1778)
							(mid -0.249642 0.249642)
							(end -0.1778 0.2794)
						)
						(arc
							(start 0.1778 0.2794)
							(mid 0.249642 0.249642)
							(end 0.2794 0.1778)
						)
						(arc
							(start 0.2794 -0.1778)
							(mid 0.249642 -0.249642)
							(end 0.1778 -0.2794)
						)
					)
					(width 0)
					(fill yes)
				)
			)
		)
		(pad "2" smd custom
			(at 0 0.4445)
			(size 0.1397 0.1397)
			(layers "F.Cu" "F.Mask" "F.Paste")
			(net "LED46")
			(options
				(clearance outline)
				(anchor circle)
			)
			(primitives
				(gr_poly
					(pts
						(arc
							(start -0.1778 -0.2794)
							(mid -0.249642 -0.249642)
							(end -0.2794 -0.1778)
						)
						(arc
							(start -0.2794 0.1778)
							(mid -0.249642 0.249642)
							(end -0.1778 0.2794)
						)
						(arc
							(start 0.1778 0.2794)
							(mid 0.249642 0.249642)
							(end 0.2794 0.1778)
						)
						(arc
							(start 0.2794 -0.1778)
							(mid 0.249642 -0.249642)
							(end 0.1778 -0.2794)
						)
					)
					(width 0)
					(fill yes)
				)
			)
		)
	)
	(footprint ""
		(layer "F.Cu")
		(at 173.680374 -100.109782 180)
		(property "Reference" "C624"
			(at 0 0 180)
			(layer "F.SilkS")
			(hide yes)
			(effects
				(font
					(size 1.27 1.27)
				)
			)
		)
		(property "Value" "SC220P50V2KX-3GP"
			(at 1.1811 -2.7051 180)
			(unlocked yes)
			(layer "F.Fab")
			(hide yes)
			(effects
				(font
					(size 1.016 1.016)
					(thickness 0.1524)
				)
			)
		)
		(property "Device Type" "C402H22"
			(at 1.1811 -4.2291 180)
			(unlocked yes)
			(layer "F.Fab")
			(hide yes)
			(effects
				(font
					(size 1.016 1.016)
					(thickness 0.1524)
				)
			)
		)
		(duplicate_pad_numbers_are_jumpers no)
		(fp_rect
			(start -0.4318 0.9525)
			(end 0.4318 -0.9525)
			(stroke
				(width 0)
				(type default)
			)
			(fill no)
			(layer "F.CrtYd")
		)
		(fp_rect
			(start -0.4318 0.9525)
			(end 0.4318 -0.9525)
			(stroke
				(width 0)
				(type default)
			)
			(fill no)
			(layer "F.Fab")
		)
		(pad "1" smd custom
			(at 0 -0.4445 180)
			(size 0.1524 0.1524)
			(layers "F.Cu" "F.Mask" "F.Paste")
			(net "VT235_PGIN")
			(options
				(clearance outline)
				(anchor circle)
			)
			(primitives
				(gr_poly
					(pts
						(arc
							(start 0.3048 -0.2032)
							(mid 0.275042 -0.275042)
							(end 0.2032 -0.3048)
						)
						(arc
							(start -0.2032 -0.3048)
							(mid -0.275042 -0.275042)
							(end -0.3048 -0.2032)
						)
						(arc
							(start -0.3048 0.2032)
							(mid -0.275042 0.275042)
							(end -0.2032 0.3048)
						)
						(arc
							(start 0.2032 0.3048)
							(mid 0.275042 0.275042)
							(end 0.3048 0.2032)
						)
					)
					(width 0)
					(fill yes)
				)
			)
		)
		(pad "2" smd custom
			(at 0 0.4445 180)
			(size 0.1524 0.1524)
			(layers "F.Cu" "F.Mask" "F.Paste")
			(net "VT235_VREF")
			(options
				(clearance outline)
				(anchor circle)
			)
			(primitives
				(gr_poly
					(pts
						(arc
							(start 0.3048 -0.2032)
							(mid 0.275042 -0.275042)
							(end 0.2032 -0.3048)
						)
						(arc
							(start -0.2032 -0.3048)
							(mid -0.275042 -0.275042)
							(end -0.3048 -0.2032)
						)
						(arc
							(start -0.3048 0.2032)
							(mid -0.275042 0.275042)
							(end -0.2032 0.3048)
						)
						(arc
							(start 0.2032 0.3048)
							(mid 0.275042 0.275042)
							(end 0.3048 0.2032)
						)
					)
					(width 0)
					(fill yes)
				)
			)
		)
	)
	(footprint ""
		(layer "F.Cu")
		(at 87.2236 -82.2706 90)
		(property "Reference" "R549"
			(at 0 0 90)
			(layer "F.SilkS")
			(hide yes)
			(effects
				(font
					(size 1.27 1.27)
				)
			)
		)
		(property "Value" "4K7R2F-GP"
			(at 0.064008 -3.993896 90)
			(unlocked yes)
			(layer "F.Fab")
			(hide yes)
			(effects
				(font
					(size 1.016 1.016)
					(thickness 0.1524)
				)
			)
		)
		(property "Device Type" "R402H16"
			(at 0.064008 -5.517896 90)
			(unlocked yes)
			(layer "F.Fab")
			(hide yes)
			(effects
				(font
					(size 1.016 1.016)
					(thickness 0.1524)
				)
			)
		)
		(duplicate_pad_numbers_are_jumpers no)
		(fp_line
			(start 0.508 -0.9398)
			(end -0.508 -0.9398)
			(stroke
				(width 0.1524)
				(type default)
			)
			(layer "F.SilkS")
		)
		(fp_line
			(start -0.508 -0.9398)
			(end -0.508 0.9398)
			(stroke
				(width 0.1524)
				(type default)
			)
			(layer "F.SilkS")
		)
		(fp_rect
			(start -0.508 0.9398)
			(end 0.508 -0.9398)
			(stroke
				(width 0)
				(type default)
			)
			(fill no)
			(layer "F.CrtYd")
		)
		(fp_rect
			(start -0.508 0.9398)
			(end 0.508 -0.9398)
			(stroke
				(width 0)
				(type default)
			)
			(fill no)
			(layer "F.Fab")
		)
		(pad "1" smd custom
			(at 0 -0.4445 90)
			(size 0.1397 0.1397)
			(layers "F.Cu" "F.Mask" "F.Paste")
			(net "P0V9_PG")
			(options
				(clearance outline)
				(anchor circle)
			)
			(primitives
				(gr_poly
					(pts
						(arc
							(start -0.1778 -0.2794)
							(mid -0.249642 -0.249642)
							(end -0.2794 -0.1778)
						)
						(arc
							(start -0.2794 0.1778)
							(mid -0.249642 0.249642)
							(end -0.1778 0.2794)
						)
						(arc
							(start 0.1778 0.2794)
							(mid 0.249642 0.249642)
							(end 0.2794 0.1778)
						)
						(arc
							(start 0.2794 -0.1778)
							(mid 0.249642 -0.249642)
							(end 0.1778 -0.2794)
						)
					)
					(width 0)
					(fill yes)
				)
			)
		)
		(pad "2" smd custom
			(at 0 0.4445 90)
			(size 0.1397 0.1397)
			(layers "F.Cu" "F.Mask" "F.Paste")
			(net "GND")
			(options
				(clearance outline)
				(anchor circle)
			)
			(primitives
				(gr_poly
					(pts
						(arc
							(start -0.1778 -0.2794)
							(mid -0.249642 -0.249642)
							(end -0.2794 -0.1778)
						)
						(arc
							(start -0.2794 0.1778)
							(mid -0.249642 0.249642)
							(end -0.1778 0.2794)
						)
						(arc
							(start 0.1778 0.2794)
							(mid 0.249642 0.249642)
							(end 0.2794 0.1778)
						)
						(arc
							(start 0.2794 -0.1778)
							(mid 0.249642 -0.249642)
							(end 0.1778 -0.2794)
						)
					)
					(width 0)
					(fill yes)
				)
			)
		)
	)
	(footprint ""
		(layer "F.Cu")
		(at 163.290504 -9.237472 180)
		(property "Reference" "U12"
			(at 0 0 180)
			(layer "F.SilkS")
			(hide yes)
			(effects
				(font
					(size 1.27 1.27)
				)
			)
		)
		(property "Value" "SNLVC8T245DGVR-GP"
			(at 0 -11.1252 180)
			(unlocked yes)
			(layer "F.Fab")
			(hide yes)
			(effects
				(font
					(size 1.016 1.016)
					(thickness 0.1524)
				)
			)
		)
		(property "Device Type" "TVSOP24H48"
			(at 0 -12.6492 180)
			(unlocked yes)
			(layer "F.Fab")
			(hide yes)
			(effects
				(font
					(size 1.016 1.016)
					(thickness 0.1524)
				)
			)
		)
		(duplicate_pad_numbers_are_jumpers no)
		(fp_line
			(start 2.2987 1.397)
			(end 2.2987 -1.397)
			(stroke
				(width 0.1524)
				(type default)
			)
			(layer "F.SilkS")
		)
		(fp_line
			(start 2.2987 -1.397)
			(end -2.9337 -1.397)
			(stroke
				(width 0.1524)
				(type default)
			)
			(layer "F.SilkS")
		)
		(fp_line
			(start -2.5654 0)
			(end -2.9337 0.3683)
			(stroke
				(width 0.1524)
				(type default)
			)
			(layer "F.SilkS")
		)
		(fp_line
			(start -2.7559 1.397)
			(end -2.7559 3.8354)
			(stroke
				(width 0.508)
				(type default)
			)
			(layer "F.SilkS")
		)
		(fp_line
			(start -2.9337 1.397)
			(end 2.2987 1.397)
			(stroke
				(width 0.1524)
				(type default)
			)
			(layer "F.SilkS")
		)
		(fp_line
			(start -2.9337 -0.3683)
			(end -2.5654 0)
			(stroke
				(width 0.1524)
				(type default)
			)
			(layer "F.SilkS")
		)
		(fp_line
			(start -2.9337 -1.397)
			(end -2.9337 1.397)
			(stroke
				(width 0.1524)
				(type default)
			)
			(layer "F.SilkS")
		)
		(fp_rect
			(start -3.0099 4.0894)
			(end 3.0099 -4.0894)
			(stroke
				(width 0)
				(type default)
			)
			(fill no)
			(layer "F.CrtYd")
		)
		(fp_poly
			(pts
				(xy -3.0099 -4.0894) (xy 3.0099 -4.0894) (xy 3.0099 4.0894) (xy -3.0099 4.0894)
			)
			(stroke
				(width 0)
				(type default)
			)
			(fill no)
			(layer "F.Fab")
		)
		(pad "1" smd rect
			(at -2.19964 2.8194 180)
			(size 0.2032 1.524)
			(layers "F.Cu" "F.Mask" "F.Paste")
			(net "P3V3")
		)
		(pad "2" smd rect
			(at -1.79959 2.8194 180)
			(size 0.2032 1.524)
			(layers "F.Cu" "F.Mask" "F.Paste")
			(net "P3V3")
		)
		(pad "3" smd rect
			(at -1.39954 2.8194 180)
			(size 0.2032 1.524)
			(layers "F.Cu" "F.Mask" "F.Paste")
			(net "BMC_LOC_HEARTBEAT")
		)
		(pad "4" smd rect
			(at -0.99949 2.8194 180)
			(size 0.2032 1.524)
			(layers "F.Cu" "F.Mask" "F.Paste")
			(net "BMC_RMT_HEARTBEAT")
		)
		(pad "5" smd rect
			(at -0.59944 2.8194 180)
			(size 0.2032 1.524)
			(layers "F.Cu" "F.Mask" "F.Paste")
			(net "SCC_RESET_BUF_N")
		)
		(pad "6" smd rect
			(at -0.19939 2.8194 180)
			(size 0.2032 1.524)
			(layers "F.Cu" "F.Mask" "F.Paste")
			(net "SCC_RMT_HEARTBEAT")
		)
		(pad "7" smd rect
			(at 0.19939 2.8194 180)
			(size 0.2032 1.524)
			(layers "F.Cu" "F.Mask" "F.Paste")
			(net "DRIVE_INSERT_ALERT_N")
		)
		(pad "8" smd rect
			(at 0.59944 2.8194 180)
			(size 0.2032 1.524)
			(layers "F.Cu" "F.Mask" "F.Paste")
			(net "COMP_SPARE_0")
		)
		(pad "9" smd rect
			(at 0.99949 2.8194 180)
			(size 0.2032 1.524)
			(layers "F.Cu" "F.Mask" "F.Paste")
			(net "Net_20")
		)
		(pad "10" smd rect
			(at 1.39954 2.8194 180)
			(size 0.2032 1.524)
			(layers "F.Cu" "F.Mask" "F.Paste")
			(net "BMC_SPARE_0")
		)
		(pad "11" smd rect
			(at 1.79959 2.8194 180)
			(size 0.2032 1.524)
			(layers "F.Cu" "F.Mask" "F.Paste")
			(net "GND")
		)
		(pad "12" smd rect
			(at 2.19964 2.8194 180)
			(size 0.2032 1.524)
			(layers "F.Cu" "F.Mask" "F.Paste")
			(net "GND")
		)
		(pad "13" smd rect
			(at 2.19964 -2.8194 180)
			(size 0.2032 1.524)
			(layers "F.Cu" "F.Mask" "F.Paste")
			(net "GND")
		)
		(pad "14" smd rect
			(at 1.79959 -2.8194 180)
			(size 0.2032 1.524)
			(layers "F.Cu" "F.Mask" "F.Paste")
			(net "BMC_SPARE_0_LS")
		)
		(pad "15" smd rect
			(at 1.39954 -2.8194 180)
			(size 0.2032 1.524)
			(layers "F.Cu" "F.Mask" "F.Paste")
			(net "Net_21")
		)
		(pad "16" smd rect
			(at 0.99949 -2.8194 180)
			(size 0.2032 1.524)
			(layers "F.Cu" "F.Mask" "F.Paste")
			(net "COMP_SPARE_0_LS")
		)
		(pad "17" smd rect
			(at 0.59944 -2.8194 180)
			(size 0.2032 1.524)
			(layers "F.Cu" "F.Mask" "F.Paste")
			(net "DRIVE_INSERT_ALERT_LS_N")
		)
		(pad "18" smd rect
			(at 0.19939 -2.8194 180)
			(size 0.2032 1.524)
			(layers "F.Cu" "F.Mask" "F.Paste")
			(net "SCC_RMT_HEARTBEAT_LS")
		)
		(pad "19" smd rect
			(at -0.19939 -2.8194 180)
			(size 0.2032 1.524)
			(layers "F.Cu" "F.Mask" "F.Paste")
			(net "SCC_RESET_LS_N")
		)
		(pad "20" smd rect
			(at -0.59944 -2.8194 180)
			(size 0.2032 1.524)
			(layers "F.Cu" "F.Mask" "F.Paste")
			(net "BMC_RMT_HEARTBEAT_LS")
		)
		(pad "21" smd rect
			(at -0.99949 -2.8194 180)
			(size 0.2032 1.524)
			(layers "F.Cu" "F.Mask" "F.Paste")
			(net "BMC_LOC_HEARTBEAT_LS")
		)
		(pad "22" smd rect
			(at -1.39954 -2.8194 180)
			(size 0.2032 1.524)
			(layers "F.Cu" "F.Mask" "F.Paste")
			(net "LS_EN_U12")
		)
		(pad "23" smd rect
			(at -1.79959 -2.8194 180)
			(size 0.2032 1.524)
			(layers "F.Cu" "F.Mask" "F.Paste")
			(net "P1V8_E")
		)
		(pad "24" smd rect
			(at -2.19964 -2.8194 180)
			(size 0.2032 1.524)
			(layers "F.Cu" "F.Mask" "F.Paste")
			(net "P1V8_E")
		)
	)
	(footprint ""
		(layer "F.Cu")
		(at 179.578 -55.245 90)
		(property "Reference" "TP114"
			(at 0 0 90)
			(layer "F.SilkS")
			(hide yes)
			(effects
				(font
					(size 1.27 1.27)
				)
			)
		)
		(property "Value" "TPAD28-2-GP"
			(at -0.0127 -1.6637 90)
			(unlocked yes)
			(layer "F.Fab")
			(hide yes)
			(effects
				(font
					(size 1.016 1.016)
					(thickness 0.1524)
				)
			)
		)
		(property "Device Type" "TPAD28"
			(at -0.0127 -3.1877 90)
			(unlocked yes)
			(layer "F.Fab")
			(hide yes)
			(effects
				(font
					(size 1.016 1.016)
					(thickness 0.1524)
				)
			)
		)
		(duplicate_pad_numbers_are_jumpers no)
		(fp_poly
			(pts
				(arc
					(start 0 0.3556)
					(mid 0 -0.3556)
					(end 0 0.3556)
				)
			)
			(stroke
				(width 0)
				(type default)
			)
			(fill no)
			(layer "F.CrtYd")
		)
		(fp_poly
			(pts
				(arc
					(start 0 0.6096)
					(mid 0 -0.6096)
					(end 0 0.6096)
				)
			)
			(stroke
				(width 0)
				(type default)
			)
			(fill no)
			(layer "F.Fab")
		)
		(pad "1" smd circle
			(at 0 0 90)
			(size 0.7112 0.7112)
			(layers "F.Cu" "F.Mask" "F.Paste")
			(net "XM_RB")
		)
	)
	(footprint ""
		(layer "F.Cu")
		(at 70.612 -51.943 90)
		(property "Reference" "R163"
			(at 0 0 90)
			(layer "F.SilkS")
			(hide yes)
			(effects
				(font
					(size 1.27 1.27)
				)
			)
		)
		(property "Value" "D51R3F-2-GP"
			(at -0.0254 -2.5146 90)
			(unlocked yes)
			(layer "F.Fab")
			(hide yes)
			(effects
				(font
					(size 1.016 1.016)
					(thickness 0.1524)
				)
			)
		)
		(property "Device Type" "R603H22"
			(at -0.0254 -4.0386 90)
			(unlocked yes)
			(layer "F.Fab")
			(hide yes)
			(effects
				(font
					(size 1.016 1.016)
					(thickness 0.1524)
				)
			)
		)
		(duplicate_pad_numbers_are_jumpers no)
		(fp_line
			(start 0.2032 0)
			(end 0.4826 0)
			(stroke
				(width 0.2032)
				(type default)
			)
			(layer "F.SilkS")
		)
		(fp_line
			(start -0.4826 0)
			(end -0.2032 0)
			(stroke
				(width 0.2032)
				(type default)
			)
			(layer "F.SilkS")
		)
		(fp_rect
			(start -0.5842 1.3335)
			(end 0.5842 -1.3335)
			(stroke
				(width 0)
				(type default)
			)
			(fill no)
			(layer "F.CrtYd")
		)
		(fp_rect
			(start -0.5842 1.3335)
			(end 0.5842 -1.3335)
			(stroke
				(width 0)
				(type default)
			)
			(fill no)
			(layer "F.Fab")
		)
		(pad "1" smd custom
			(at 0 -0.762 90)
			(size 0.2159 0.2159)
			(layers "F.Cu" "F.Mask" "F.Paste")
			(net "P0V9")
			(options
				(clearance outline)
				(anchor circle)
			)
			(primitives
				(gr_poly
					(pts
						(arc
							(start -0.3302 -0.4318)
							(mid -0.402042 -0.402042)
							(end -0.4318 -0.3302)
						)
						(arc
							(start -0.4318 0.3302)
							(mid -0.402042 0.402042)
							(end -0.3302 0.4318)
						)
						(arc
							(start 0.3302 0.4318)
							(mid 0.402042 0.402042)
							(end 0.4318 0.3302)
						)
						(arc
							(start 0.4318 -0.3302)
							(mid 0.402042 -0.402042)
							(end 0.3302 -0.4318)
						)
					)
					(width 0)
					(fill yes)
				)
			)
		)
		(pad "2" smd custom
			(at 0 0.762 90)
			(size 0.2159 0.2159)
			(layers "F.Cu" "F.Mask" "F.Paste")
			(net "GB_VDDA")
			(options
				(clearance outline)
				(anchor circle)
			)
			(primitives
				(gr_poly
					(pts
						(arc
							(start -0.3302 -0.4318)
							(mid -0.402042 -0.402042)
							(end -0.4318 -0.3302)
						)
						(arc
							(start -0.4318 0.3302)
							(mid -0.402042 0.402042)
							(end -0.3302 0.4318)
						)
						(arc
							(start 0.3302 0.4318)
							(mid 0.402042 0.402042)
							(end 0.4318 0.3302)
						)
						(arc
							(start 0.4318 -0.3302)
							(mid 0.402042 -0.402042)
							(end 0.3302 -0.4318)
						)
					)
					(width 0)
					(fill yes)
				)
			)
		)
	)
	(footprint ""
		(layer "F.Cu")
		(at 140.514324 -104.872028 180)
		(property "Reference" "R382"
			(at 0 0 180)
			(layer "F.SilkS")
			(hide yes)
			(effects
				(font
					(size 1.27 1.27)
				)
			)
		)
		(property "Value" "0R5J-5-GP"
			(at 0 -8.9535 180)
			(unlocked yes)
			(layer "F.Fab")
			(hide yes)
			(effects
				(font
					(size 1.27 1.016)
					(thickness 0.1524)
				)
			)
		)
		(property "Device Type" "R805H24"
			(at 0 -10.6299 180)
			(unlocked yes)
			(layer "F.Fab")
			(hide yes)
			(effects
				(font
					(size 1.27 1.016)
					(thickness 0.1524)
				)
			)
		)
		(duplicate_pad_numbers_are_jumpers no)
		(fp_line
			(start 0.889 1.7018)
			(end 0.889 -0.508)
			(stroke
				(width 0.1524)
				(type default)
			)
			(layer "F.SilkS")
		)
		(fp_line
			(start 0.889 -1.7018)
			(end 0.889 -0.381)
			(stroke
				(width 0.1524)
				(type default)
			)
			(layer "F.SilkS")
		)
		(fp_line
			(start 0.889 -1.7018)
			(end -0.889 -1.7018)
			(stroke
				(width 0.1524)
				(type default)
			)
			(layer "F.SilkS")
		)
		(fp_line
			(start -0.889 1.7018)
			(end 0.889 1.7018)
			(stroke
				(width 0.1524)
				(type default)
			)
			(layer "F.SilkS")
		)
		(fp_line
			(start -0.889 0.0762)
			(end -0.889 1.7018)
			(stroke
				(width 0.1524)
				(type default)
			)
			(layer "F.SilkS")
		)
		(fp_line
			(start -0.889 -1.7018)
			(end -0.889 0.2794)
			(stroke
				(width 0.1524)
				(type default)
			)
			(layer "F.SilkS")
		)
		(fp_poly
			(pts
				(xy 0.9652 -1.778) (xy 0.9652 1.778) (xy -0.9652 1.778) (xy -0.9652 -1.778)
			)
			(stroke
				(width 0)
				(type default)
			)
			(fill no)
			(layer "F.CrtYd")
		)
		(fp_rect
			(start -0.9652 1.778)
			(end 0.9652 -1.778)
			(stroke
				(width 0)
				(type default)
			)
			(fill no)
			(layer "F.Fab")
		)
		(pad "1" smd rect
			(at 0 -0.9652 180)
			(size 1.397 1.143)
			(layers "F.Cu" "F.Mask" "F.Paste")
			(net "P1V5_E")
		)
		(pad "2" smd rect
			(at 0 0.9652 180)
			(size 1.397 1.143)
			(layers "F.Cu" "F.Mask" "F.Paste")
			(net "P1V5_E_OUT")
		)
	)
	(footprint ""
		(layer "F.Cu")
		(at 171.517056 -55.113428)
		(property "Reference" "TP154"
			(at 0 0 0)
			(layer "F.SilkS")
			(hide yes)
			(effects
				(font
					(size 1.27 1.27)
				)
			)
		)
		(property "Value" "TPAD28-2-GP"
			(at -0.0127 -1.6637 0)
			(unlocked yes)
			(layer "F.Fab")
			(hide yes)
			(effects
				(font
					(size 1.016 1.016)
					(thickness 0.1524)
				)
			)
		)
		(property "Device Type" "TPAD28"
			(at -0.0127 -3.1877 0)
			(unlocked yes)
			(layer "F.Fab")
			(hide yes)
			(effects
				(font
					(size 1.016 1.016)
					(thickness 0.1524)
				)
			)
		)
		(duplicate_pad_numbers_are_jumpers no)
		(fp_poly
			(pts
				(arc
					(start 0.3556 0)
					(mid -0.3556 0)
					(end 0.3556 0)
				)
			)
			(stroke
				(width 0)
				(type default)
			)
			(fill no)
			(layer "F.CrtYd")
		)
		(fp_poly
			(pts
				(arc
					(start 0.6096 0)
					(mid -0.6096 0)
					(end 0.6096 0)
				)
			)
			(stroke
				(width 0)
				(type default)
			)
			(fill no)
			(layer "F.Fab")
		)
		(pad "1" smd circle
			(at 0 0)
			(size 0.7112 0.7112)
			(layers "F.Cu" "F.Mask" "F.Paste")
			(net "PG_CORE")
		)
	)
	(footprint ""
		(layer "F.Cu")
		(at 176.62652 -108.3437)
		(property "Reference" "R444"
			(at 0 0 0)
			(layer "F.SilkS")
			(hide yes)
			(effects
				(font
					(size 1.27 1.27)
				)
			)
		)
		(property "Value" "0R2J-2-GP"
			(at 0.064008 -3.993896 0)
			(unlocked yes)
			(layer "F.Fab")
			(hide yes)
			(effects
				(font
					(size 1.016 1.016)
					(thickness 0.1524)
				)
			)
		)
		(property "Device Type" "R402H16"
			(at 0.064008 -5.517896 0)
			(unlocked yes)
			(layer "F.Fab")
			(hide yes)
			(effects
				(font
					(size 1.016 1.016)
					(thickness 0.1524)
				)
			)
		)
		(duplicate_pad_numbers_are_jumpers no)
		(fp_line
			(start -0.508 -0.9398)
			(end -0.508 0.9398)
			(stroke
				(width 0.1524)
				(type default)
			)
			(layer "F.SilkS")
		)
		(fp_line
			(start 0.508 -0.9398)
			(end -0.508 -0.9398)
			(stroke
				(width 0.1524)
				(type default)
			)
			(layer "F.SilkS")
		)
		(fp_rect
			(start -0.508 0.9398)
			(end 0.508 -0.9398)
			(stroke
				(width 0)
				(type default)
			)
			(fill no)
			(layer "F.CrtYd")
		)
		(fp_rect
			(start -0.508 0.9398)
			(end 0.508 -0.9398)
			(stroke
				(width 0)
				(type default)
			)
			(fill no)
			(layer "F.Fab")
		)
		(pad "1" smd custom
			(at 0 -0.4445)
			(size 0.1397 0.1397)
			(layers "F.Cu" "F.Mask" "F.Paste")
			(net "P1V8_C_PG_LS")
			(options
				(clearance outline)
				(anchor circle)
			)
			(primitives
				(gr_poly
					(pts
						(arc
							(start -0.1778 -0.2794)
							(mid -0.249642 -0.249642)
							(end -0.2794 -0.1778)
						)
						(arc
							(start -0.2794 0.1778)
							(mid -0.249642 0.249642)
							(end -0.1778 0.2794)
						)
						(arc
							(start 0.1778 0.2794)
							(mid 0.249642 0.249642)
							(end 0.2794 0.1778)
						)
						(arc
							(start 0.2794 -0.1778)
							(mid 0.249642 -0.249642)
							(end 0.1778 -0.2794)
						)
					)
					(width 0)
					(fill yes)
				)
			)
		)
		(pad "2" smd custom
			(at 0 0.4445)
			(size 0.1397 0.1397)
			(layers "F.Cu" "F.Mask" "F.Paste")
			(net "Q22_D")
			(options
				(clearance outline)
				(anchor circle)
			)
			(primitives
				(gr_poly
					(pts
						(arc
							(start -0.1778 -0.2794)
							(mid -0.249642 -0.249642)
							(end -0.2794 -0.1778)
						)
						(arc
							(start -0.2794 0.1778)
							(mid -0.249642 0.249642)
							(end -0.1778 0.2794)
						)
						(arc
							(start 0.1778 0.2794)
							(mid 0.249642 0.249642)
							(end 0.2794 0.1778)
						)
						(arc
							(start 0.2794 -0.1778)
							(mid 0.249642 -0.249642)
							(end 0.1778 -0.2794)
						)
					)
					(width 0)
					(fill yes)
				)
			)
		)
	)
	(footprint ""
		(layer "F.Cu")
		(at 119.378984 -89.588848 180)
		(property "Reference" "R46"
			(at 0 0 180)
			(layer "F.SilkS")
			(hide yes)
			(effects
				(font
					(size 1.27 1.27)
				)
			)
		)
		(property "Value" "4K7R2F-GP"
			(at 0.064008 -3.993896 180)
			(unlocked yes)
			(layer "F.Fab")
			(hide yes)
			(effects
				(font
					(size 1.016 1.016)
					(thickness 0.1524)
				)
			)
		)
		(property "Device Type" "R402H16"
			(at 0.064008 -5.517896 180)
			(unlocked yes)
			(layer "F.Fab")
			(hide yes)
			(effects
				(font
					(size 1.016 1.016)
					(thickness 0.1524)
				)
			)
		)
		(duplicate_pad_numbers_are_jumpers no)
		(fp_line
			(start 0.508 -0.9398)
			(end -0.508 -0.9398)
			(stroke
				(width 0.1524)
				(type default)
			)
			(layer "F.SilkS")
		)
		(fp_line
			(start -0.508 -0.9398)
			(end -0.508 0.9398)
			(stroke
				(width 0.1524)
				(type default)
			)
			(layer "F.SilkS")
		)
		(fp_rect
			(start -0.508 0.9398)
			(end 0.508 -0.9398)
			(stroke
				(width 0)
				(type default)
			)
			(fill no)
			(layer "F.CrtYd")
		)
		(fp_rect
			(start -0.508 0.9398)
			(end 0.508 -0.9398)
			(stroke
				(width 0)
				(type default)
			)
			(fill no)
			(layer "F.Fab")
		)
		(pad "1" smd custom
			(at 0 -0.4445 180)
			(size 0.1397 0.1397)
			(layers "F.Cu" "F.Mask" "F.Paste")
			(net "EXP_GPIO15")
			(options
				(clearance outline)
				(anchor circle)
			)
			(primitives
				(gr_poly
					(pts
						(arc
							(start -0.1778 -0.2794)
							(mid -0.249642 -0.249642)
							(end -0.2794 -0.1778)
						)
						(arc
							(start -0.2794 0.1778)
							(mid -0.249642 0.249642)
							(end -0.1778 0.2794)
						)
						(arc
							(start 0.1778 0.2794)
							(mid 0.249642 0.249642)
							(end 0.2794 0.1778)
						)
						(arc
							(start 0.2794 -0.1778)
							(mid 0.249642 -0.249642)
							(end 0.1778 -0.2794)
						)
					)
					(width 0)
					(fill yes)
				)
			)
		)
		(pad "2" smd custom
			(at 0 0.4445 180)
			(size 0.1397 0.1397)
			(layers "F.Cu" "F.Mask" "F.Paste")
			(net "GND")
			(options
				(clearance outline)
				(anchor circle)
			)
			(primitives
				(gr_poly
					(pts
						(arc
							(start -0.1778 -0.2794)
							(mid -0.249642 -0.249642)
							(end -0.2794 -0.1778)
						)
						(arc
							(start -0.2794 0.1778)
							(mid -0.249642 0.249642)
							(end -0.1778 0.2794)
						)
						(arc
							(start 0.1778 0.2794)
							(mid 0.249642 0.249642)
							(end 0.2794 0.1778)
						)
						(arc
							(start 0.2794 -0.1778)
							(mid 0.249642 -0.249642)
							(end 0.1778 -0.2794)
						)
					)
					(width 0)
					(fill yes)
				)
			)
		)
	)
	(footprint ""
		(layer "F.Cu")
		(at 155.1051 -100.38588 90)
		(property "Reference" "R293"
			(at 0 0 90)
			(layer "F.SilkS")
			(hide yes)
			(effects
				(font
					(size 1.27 1.27)
				)
			)
		)
		(property "Value" "0R2J-2-GP"
			(at 0.064008 -3.993896 90)
			(unlocked yes)
			(layer "F.Fab")
			(hide yes)
			(effects
				(font
					(size 1.016 1.016)
					(thickness 0.1524)
				)
			)
		)
		(property "Device Type" "R402H16"
			(at 0.064008 -5.517896 90)
			(unlocked yes)
			(layer "F.Fab")
			(hide yes)
			(effects
				(font
					(size 1.016 1.016)
					(thickness 0.1524)
				)
			)
		)
		(duplicate_pad_numbers_are_jumpers no)
		(fp_line
			(start 0.508 -0.9398)
			(end -0.508 -0.9398)
			(stroke
				(width 0.1524)
				(type default)
			)
			(layer "F.SilkS")
		)
		(fp_line
			(start -0.508 -0.9398)
			(end -0.508 0.9398)
			(stroke
				(width 0.1524)
				(type default)
			)
			(layer "F.SilkS")
		)
		(fp_rect
			(start -0.508 0.9398)
			(end 0.508 -0.9398)
			(stroke
				(width 0)
				(type default)
			)
			(fill no)
			(layer "F.CrtYd")
		)
		(fp_rect
			(start -0.508 0.9398)
			(end 0.508 -0.9398)
			(stroke
				(width 0)
				(type default)
			)
			(fill no)
			(layer "F.Fab")
		)
		(pad "1" smd custom
			(at 0 -0.4445 90)
			(size 0.1397 0.1397)
			(layers "F.Cu" "F.Mask" "F.Paste")
			(net "UART_SDB_TX")
			(options
				(clearance outline)
				(anchor circle)
			)
			(primitives
				(gr_poly
					(pts
						(arc
							(start -0.1778 -0.2794)
							(mid -0.249642 -0.249642)
							(end -0.2794 -0.1778)
						)
						(arc
							(start -0.2794 0.1778)
							(mid -0.249642 0.249642)
							(end -0.1778 0.2794)
						)
						(arc
							(start 0.1778 0.2794)
							(mid 0.249642 0.249642)
							(end 0.2794 0.1778)
						)
						(arc
							(start 0.2794 -0.1778)
							(mid 0.249642 -0.249642)
							(end 0.1778 -0.2794)
						)
					)
					(width 0)
					(fill yes)
				)
			)
		)
		(pad "2" smd custom
			(at 0 0.4445 90)
			(size 0.1397 0.1397)
			(layers "F.Cu" "F.Mask" "F.Paste")
			(net "SAS_R_SDBTX")
			(options
				(clearance outline)
				(anchor circle)
			)
			(primitives
				(gr_poly
					(pts
						(arc
							(start -0.1778 -0.2794)
							(mid -0.249642 -0.249642)
							(end -0.2794 -0.1778)
						)
						(arc
							(start -0.2794 0.1778)
							(mid -0.249642 0.249642)
							(end -0.1778 0.2794)
						)
						(arc
							(start 0.1778 0.2794)
							(mid 0.249642 0.249642)
							(end 0.2794 0.1778)
						)
						(arc
							(start 0.2794 -0.1778)
							(mid 0.249642 -0.249642)
							(end 0.1778 -0.2794)
						)
					)
					(width 0)
					(fill yes)
				)
			)
		)
	)
	(footprint ""
		(layer "F.Cu")
		(at 39.8018 -34.163 180)
		(property "Reference" "R383"
			(at 0 0 180)
			(layer "F.SilkS")
			(hide yes)
			(effects
				(font
					(size 1.27 1.27)
				)
			)
		)
		(property "Value" "0R2J-2-GP"
			(at 0.064008 -3.993896 180)
			(unlocked yes)
			(layer "F.Fab")
			(hide yes)
			(effects
				(font
					(size 1.016 1.016)
					(thickness 0.1524)
				)
			)
		)
		(property "Device Type" "R402H16"
			(at 0.064008 -5.517896 180)
			(unlocked yes)
			(layer "F.Fab")
			(hide yes)
			(effects
				(font
					(size 1.016 1.016)
					(thickness 0.1524)
				)
			)
		)
		(duplicate_pad_numbers_are_jumpers no)
		(fp_line
			(start 0.508 -0.9398)
			(end -0.508 -0.9398)
			(stroke
				(width 0.1524)
				(type default)
			)
			(layer "F.SilkS")
		)
		(fp_line
			(start -0.508 -0.9398)
			(end -0.508 0.9398)
			(stroke
				(width 0.1524)
				(type default)
			)
			(layer "F.SilkS")
		)
		(fp_rect
			(start -0.508 0.9398)
			(end 0.508 -0.9398)
			(stroke
				(width 0)
				(type default)
			)
			(fill no)
			(layer "F.CrtYd")
		)
		(fp_rect
			(start -0.508 0.9398)
			(end 0.508 -0.9398)
			(stroke
				(width 0)
				(type default)
			)
			(fill no)
			(layer "F.Fab")
		)
		(pad "1" smd custom
			(at 0 -0.4445 180)
			(size 0.1397 0.1397)
			(layers "F.Cu" "F.Mask" "F.Paste")
			(net "P1V5_E_PG")
			(options
				(clearance outline)
				(anchor circle)
			)
			(primitives
				(gr_poly
					(pts
						(arc
							(start -0.1778 -0.2794)
							(mid -0.249642 -0.249642)
							(end -0.2794 -0.1778)
						)
						(arc
							(start -0.2794 0.1778)
							(mid -0.249642 0.249642)
							(end -0.1778 0.2794)
						)
						(arc
							(start 0.1778 0.2794)
							(mid 0.249642 0.249642)
							(end 0.2794 0.1778)
						)
						(arc
							(start 0.2794 -0.1778)
							(mid 0.249642 -0.249642)
							(end 0.1778 -0.2794)
						)
					)
					(width 0)
					(fill yes)
				)
			)
		)
		(pad "2" smd custom
			(at 0 0.4445 180)
			(size 0.1397 0.1397)
			(layers "F.Cu" "F.Mask" "F.Paste")
			(net "P0V9_EN")
			(options
				(clearance outline)
				(anchor circle)
			)
			(primitives
				(gr_poly
					(pts
						(arc
							(start -0.1778 -0.2794)
							(mid -0.249642 -0.249642)
							(end -0.2794 -0.1778)
						)
						(arc
							(start -0.2794 0.1778)
							(mid -0.249642 0.249642)
							(end -0.1778 0.2794)
						)
						(arc
							(start 0.1778 0.2794)
							(mid 0.249642 0.249642)
							(end 0.2794 0.1778)
						)
						(arc
							(start 0.2794 -0.1778)
							(mid 0.249642 -0.249642)
							(end 0.1778 -0.2794)
						)
					)
					(width 0)
					(fill yes)
				)
			)
		)
	)
	(footprint ""
		(layer "F.Cu")
		(at 145.6182 -124.3838 90)
		(property "Reference" "R29"
			(at 0 0 90)
			(layer "F.SilkS")
			(hide yes)
			(effects
				(font
					(size 1.27 1.27)
				)
			)
		)
		(property "Value" "10R3F-GP"
			(at -0.0254 -2.5146 90)
			(unlocked yes)
			(layer "F.Fab")
			(hide yes)
			(effects
				(font
					(size 1.016 1.016)
					(thickness 0.1524)
				)
			)
		)
		(property "Device Type" "R603H22"
			(at -0.0254 -4.0386 90)
			(unlocked yes)
			(layer "F.Fab")
			(hide yes)
			(effects
				(font
					(size 1.016 1.016)
					(thickness 0.1524)
				)
			)
		)
		(duplicate_pad_numbers_are_jumpers no)
		(fp_line
			(start 0.2032 0)
			(end 0.4826 0)
			(stroke
				(width 0.2032)
				(type default)
			)
			(layer "F.SilkS")
		)
		(fp_line
			(start -0.4826 0)
			(end -0.2032 0)
			(stroke
				(width 0.2032)
				(type default)
			)
			(layer "F.SilkS")
		)
		(fp_rect
			(start -0.5842 1.3335)
			(end 0.5842 -1.3335)
			(stroke
				(width 0)
				(type default)
			)
			(fill no)
			(layer "F.CrtYd")
		)
		(fp_rect
			(start -0.5842 1.3335)
			(end 0.5842 -1.3335)
			(stroke
				(width 0)
				(type default)
			)
			(fill no)
			(layer "F.Fab")
		)
		(pad "1" smd custom
			(at 0 -0.762 90)
			(size 0.2159 0.2159)
			(layers "F.Cu" "F.Mask" "F.Paste")
			(net "P1V5_E_OUT")
			(options
				(clearance outline)
				(anchor circle)
			)
			(primitives
				(gr_poly
					(pts
						(arc
							(start -0.3302 -0.4318)
							(mid -0.402042 -0.402042)
							(end -0.4318 -0.3302)
						)
						(arc
							(start -0.4318 0.3302)
							(mid -0.402042 0.402042)
							(end -0.3302 0.4318)
						)
						(arc
							(start 0.3302 0.4318)
							(mid 0.402042 0.402042)
							(end 0.4318 0.3302)
						)
						(arc
							(start 0.4318 -0.3302)
							(mid 0.402042 -0.402042)
							(end 0.3302 -0.4318)
						)
					)
					(width 0)
					(fill yes)
				)
			)
		)
		(pad "2" smd custom
			(at 0 0.762 90)
			(size 0.2159 0.2159)
			(layers "F.Cu" "F.Mask" "F.Paste")
			(net "P1V5_E_VFB_R")
			(options
				(clearance outline)
				(anchor circle)
			)
			(primitives
				(gr_poly
					(pts
						(arc
							(start -0.3302 -0.4318)
							(mid -0.402042 -0.402042)
							(end -0.4318 -0.3302)
						)
						(arc
							(start -0.4318 0.3302)
							(mid -0.402042 0.402042)
							(end -0.3302 0.4318)
						)
						(arc
							(start 0.3302 0.4318)
							(mid 0.402042 0.402042)
							(end 0.4318 0.3302)
						)
						(arc
							(start 0.4318 -0.3302)
							(mid 0.402042 -0.402042)
							(end 0.3302 -0.4318)
						)
					)
					(width 0)
					(fill yes)
				)
			)
		)
	)
	(footprint ""
		(layer "F.Cu")
		(at 163.446968 -22.462744 180)
		(property "Reference" "R174"
			(at 0 0 180)
			(layer "F.SilkS")
			(hide yes)
			(effects
				(font
					(size 1.27 1.27)
				)
			)
		)
		(property "Value" "0R2J-2-GP"
			(at 0.064008 -3.993896 180)
			(unlocked yes)
			(layer "F.Fab")
			(hide yes)
			(effects
				(font
					(size 1.016 1.016)
					(thickness 0.1524)
				)
			)
		)
		(property "Device Type" "R402H16"
			(at 0.064008 -5.517896 180)
			(unlocked yes)
			(layer "F.Fab")
			(hide yes)
			(effects
				(font
					(size 1.016 1.016)
					(thickness 0.1524)
				)
			)
		)
		(duplicate_pad_numbers_are_jumpers no)
		(fp_line
			(start 0.508 -0.9398)
			(end -0.508 -0.9398)
			(stroke
				(width 0.1524)
				(type default)
			)
			(layer "F.SilkS")
		)
		(fp_line
			(start -0.508 -0.9398)
			(end -0.508 0.9398)
			(stroke
				(width 0.1524)
				(type default)
			)
			(layer "F.SilkS")
		)
		(fp_rect
			(start -0.508 0.9398)
			(end 0.508 -0.9398)
			(stroke
				(width 0)
				(type default)
			)
			(fill no)
			(layer "F.CrtYd")
		)
		(fp_rect
			(start -0.508 0.9398)
			(end 0.508 -0.9398)
			(stroke
				(width 0)
				(type default)
			)
			(fill no)
			(layer "F.Fab")
		)
		(pad "1" smd custom
			(at 0 -0.4445 180)
			(size 0.1397 0.1397)
			(layers "F.Cu" "F.Mask" "F.Paste")
			(net "PCIE_COMP_TO_SCC_CLK_0_DN")
			(options
				(clearance outline)
				(anchor circle)
			)
			(primitives
				(gr_poly
					(pts
						(arc
							(start -0.1778 -0.2794)
							(mid -0.249642 -0.249642)
							(end -0.2794 -0.1778)
						)
						(arc
							(start -0.2794 0.1778)
							(mid -0.249642 0.249642)
							(end -0.1778 0.2794)
						)
						(arc
							(start 0.1778 0.2794)
							(mid 0.249642 0.249642)
							(end 0.2794 0.1778)
						)
						(arc
							(start 0.2794 -0.1778)
							(mid 0.249642 -0.249642)
							(end 0.1778 -0.2794)
						)
					)
					(width 0)
					(fill yes)
				)
			)
		)
		(pad "2" smd custom
			(at 0 0.4445 180)
			(size 0.1397 0.1397)
			(layers "F.Cu" "F.Mask" "F.Paste")
			(net "PCIE_CLK_R_N")
			(options
				(clearance outline)
				(anchor circle)
			)
			(primitives
				(gr_poly
					(pts
						(arc
							(start -0.1778 -0.2794)
							(mid -0.249642 -0.249642)
							(end -0.2794 -0.1778)
						)
						(arc
							(start -0.2794 0.1778)
							(mid -0.249642 0.249642)
							(end -0.1778 0.2794)
						)
						(arc
							(start 0.1778 0.2794)
							(mid 0.249642 0.249642)
							(end 0.2794 0.1778)
						)
						(arc
							(start 0.2794 -0.1778)
							(mid 0.249642 -0.249642)
							(end 0.1778 -0.2794)
						)
					)
					(width 0)
					(fill yes)
				)
			)
		)
	)
	(footprint ""
		(layer "F.Cu")
		(at 11.811 -47.0408 180)
		(property "Reference" "R523"
			(at 0 0 180)
			(layer "F.SilkS")
			(hide yes)
			(effects
				(font
					(size 1.27 1.27)
				)
			)
		)
		(property "Value" "10R2F-L-GP"
			(at 0.064008 -3.993896 180)
			(unlocked yes)
			(layer "F.Fab")
			(hide yes)
			(effects
				(font
					(size 1.016 1.016)
					(thickness 0.1524)
				)
			)
		)
		(property "Device Type" "R402H14"
			(at 0.064008 -5.517896 180)
			(unlocked yes)
			(layer "F.Fab")
			(hide yes)
			(effects
				(font
					(size 1.016 1.016)
					(thickness 0.1524)
				)
			)
		)
		(duplicate_pad_numbers_are_jumpers no)
		(fp_line
			(start 0.508 -0.9398)
			(end -0.508 -0.9398)
			(stroke
				(width 0.1524)
				(type default)
			)
			(layer "F.SilkS")
		)
		(fp_line
			(start -0.508 -0.9398)
			(end -0.508 0.9398)
			(stroke
				(width 0.1524)
				(type default)
			)
			(layer "F.SilkS")
		)
		(fp_rect
			(start -0.508 0.9398)
			(end 0.508 -0.9398)
			(stroke
				(width 0)
				(type default)
			)
			(fill no)
			(layer "F.CrtYd")
		)
		(fp_rect
			(start -0.508 0.9398)
			(end 0.508 -0.9398)
			(stroke
				(width 0)
				(type default)
			)
			(fill no)
			(layer "F.Fab")
		)
		(pad "1" smd custom
			(at 0 -0.4445 180)
			(size 0.1397 0.1397)
			(layers "F.Cu" "F.Mask" "F.Paste")
			(net "MB0_CM_SENSE_R1_N")
			(options
				(clearance outline)
				(anchor circle)
			)
			(primitives
				(gr_poly
					(pts
						(arc
							(start -0.1778 -0.2794)
							(mid -0.249642 -0.249642)
							(end -0.2794 -0.1778)
						)
						(arc
							(start -0.2794 0.1778)
							(mid -0.249642 0.249642)
							(end -0.1778 0.2794)
						)
						(arc
							(start 0.1778 0.2794)
							(mid 0.249642 0.249642)
							(end 0.2794 0.1778)
						)
						(arc
							(start 0.2794 -0.1778)
							(mid 0.249642 -0.249642)
							(end 0.1778 -0.2794)
						)
					)
					(width 0)
					(fill yes)
				)
			)
		)
		(pad "2" smd custom
			(at 0 0.4445 180)
			(size 0.1397 0.1397)
			(layers "F.Cu" "F.Mask" "F.Paste")
			(net "MB0_HS_SENSE_N")
			(options
				(clearance outline)
				(anchor circle)
			)
			(primitives
				(gr_poly
					(pts
						(arc
							(start -0.1778 -0.2794)
							(mid -0.249642 -0.249642)
							(end -0.2794 -0.1778)
						)
						(arc
							(start -0.2794 0.1778)
							(mid -0.249642 0.249642)
							(end -0.1778 0.2794)
						)
						(arc
							(start 0.1778 0.2794)
							(mid 0.249642 0.249642)
							(end 0.2794 0.1778)
						)
						(arc
							(start 0.2794 -0.1778)
							(mid 0.249642 -0.249642)
							(end 0.1778 -0.2794)
						)
					)
					(width 0)
					(fill yes)
				)
			)
		)
	)
	(footprint ""
		(layer "F.Cu")
		(at 160.4772 -81.534 180)
		(property "Reference" "R323"
			(at 0 0 180)
			(layer "F.SilkS")
			(hide yes)
			(effects
				(font
					(size 1.27 1.27)
				)
			)
		)
		(property "Value" "1KR2F-3-GP"
			(at 0.064008 -3.993896 180)
			(unlocked yes)
			(layer "F.Fab")
			(hide yes)
			(effects
				(font
					(size 1.016 1.016)
					(thickness 0.1524)
				)
			)
		)
		(property "Device Type" "R402H16"
			(at 0.064008 -5.517896 180)
			(unlocked yes)
			(layer "F.Fab")
			(hide yes)
			(effects
				(font
					(size 1.016 1.016)
					(thickness 0.1524)
				)
			)
		)
		(duplicate_pad_numbers_are_jumpers no)
		(fp_line
			(start 0.508 -0.9398)
			(end -0.508 -0.9398)
			(stroke
				(width 0.1524)
				(type default)
			)
			(layer "F.SilkS")
		)
		(fp_line
			(start -0.508 -0.9398)
			(end -0.508 0.9398)
			(stroke
				(width 0.1524)
				(type default)
			)
			(layer "F.SilkS")
		)
		(fp_rect
			(start -0.508 0.9398)
			(end 0.508 -0.9398)
			(stroke
				(width 0)
				(type default)
			)
			(fill no)
			(layer "F.CrtYd")
		)
		(fp_rect
			(start -0.508 0.9398)
			(end 0.508 -0.9398)
			(stroke
				(width 0)
				(type default)
			)
			(fill no)
			(layer "F.Fab")
		)
		(pad "1" smd custom
			(at 0 -0.4445 180)
			(size 0.1397 0.1397)
			(layers "F.Cu" "F.Mask" "F.Paste")
			(net "P0V9")
			(options
				(clearance outline)
				(anchor circle)
			)
			(primitives
				(gr_poly
					(pts
						(arc
							(start -0.1778 -0.2794)
							(mid -0.249642 -0.249642)
							(end -0.2794 -0.1778)
						)
						(arc
							(start -0.2794 0.1778)
							(mid -0.249642 0.249642)
							(end -0.1778 0.2794)
						)
						(arc
							(start 0.1778 0.2794)
							(mid 0.249642 0.249642)
							(end 0.2794 0.1778)
						)
						(arc
							(start 0.2794 -0.1778)
							(mid 0.249642 -0.249642)
							(end 0.1778 -0.2794)
						)
					)
					(width 0)
					(fill yes)
				)
			)
		)
		(pad "2" smd custom
			(at 0 0.4445 180)
			(size 0.1397 0.1397)
			(layers "F.Cu" "F.Mask" "F.Paste")
			(net "P0V9_SENSE")
			(options
				(clearance outline)
				(anchor circle)
			)
			(primitives
				(gr_poly
					(pts
						(arc
							(start -0.1778 -0.2794)
							(mid -0.249642 -0.249642)
							(end -0.2794 -0.1778)
						)
						(arc
							(start -0.2794 0.1778)
							(mid -0.249642 0.249642)
							(end -0.1778 0.2794)
						)
						(arc
							(start 0.1778 0.2794)
							(mid 0.249642 0.249642)
							(end 0.2794 0.1778)
						)
						(arc
							(start 0.2794 -0.1778)
							(mid 0.249642 -0.249642)
							(end 0.1778 -0.2794)
						)
					)
					(width 0)
					(fill yes)
				)
			)
		)
	)
	(footprint ""
		(layer "F.Cu")
		(at 62.7634 -54.229 -90)
		(property "Reference" "TC1"
			(at 0 0 270)
			(layer "F.SilkS")
			(hide yes)
			(effects
				(font
					(size 1.27 1.27)
				)
			)
		)
		(property "Value" "SE470UF2VDM-GP"
			(at 0 -9.6012 270)
			(unlocked yes)
			(layer "F.Fab")
			(hide yes)
			(effects
				(font
					(size 1.016 1.016)
					(thickness 0.1524)
				)
			)
		)
		(property "Device Type" "CT7343H83"
			(at 0 -11.1252 270)
			(unlocked yes)
			(layer "F.Fab")
			(hide yes)
			(effects
				(font
					(size 1.016 1.016)
					(thickness 0.1524)
				)
			)
		)
		(duplicate_pad_numbers_are_jumpers no)
		(fp_line
			(start -2.286 4.8768)
			(end -2.286 2.032)
			(stroke
				(width 0.1524)
				(type default)
			)
			(layer "F.SilkS")
		)
		(fp_line
			(start 2.286 4.8768)
			(end -2.286 4.8768)
			(stroke
				(width 0.1524)
				(type default)
			)
			(layer "F.SilkS")
		)
		(fp_line
			(start 2.286 2.032)
			(end 2.286 4.8768)
			(stroke
				(width 0.1524)
				(type default)
			)
			(layer "F.SilkS")
		)
		(fp_line
			(start 2.286 -2.032)
			(end 2.286 -4.8768)
			(stroke
				(width 0.1524)
				(type default)
			)
			(layer "F.SilkS")
		)
		(fp_line
			(start 2.1082 -4.699)
			(end -2.1082 -4.699)
			(stroke
				(width 0.508)
				(type default)
			)
			(layer "F.SilkS")
		)
		(fp_line
			(start -2.286 -4.8768)
			(end -2.286 -2.032)
			(stroke
				(width 0.1524)
				(type default)
			)
			(layer "F.SilkS")
		)
		(fp_line
			(start 2.286 -4.8768)
			(end -2.286 -4.8768)
			(stroke
				(width 0.1524)
				(type default)
			)
			(layer "F.SilkS")
		)
		(fp_rect
			(start -2.1463 3.6449)
			(end 2.1463 -3.6449)
			(stroke
				(width 0)
				(type default)
			)
			(fill no)
			(layer "F.CrtYd")
		)
		(fp_poly
			(pts
				(xy -2.54 4.953) (xy -2.54 4.2926) (xy -3.81 4.2926) (xy -3.81 -4.2926) (xy -2.54 -4.2926) (xy -2.54 -4.953)
				(xy 2.54 -4.953) (xy 2.54 -4.2926) (xy 3.81 -4.2926) (xy 3.81 -1.6256) (xy 2.1463 -1.6256) (xy 2.1463 -3.6449)
				(xy -2.1463 -3.6449) (xy -2.1463 3.6449) (xy 2.1463 3.6449) (xy 2.1463 -1.6129) (xy 3.81 -1.6129)
				(xy 3.81 4.2926) (xy 2.54 4.2926) (xy 2.54 4.953)
			)
			(stroke
				(width 0)
				(type default)
			)
			(fill no)
			(layer "F.CrtYd")
		)
		(fp_rect
			(start -2.54 4.953)
			(end 2.54 -4.953)
			(stroke
				(width 0)
				(type default)
			)
			(fill no)
			(layer "F.Fab")
		)
		(fp_rect
			(start -3.81 4.2926)
			(end -2.54 -4.2926)
			(stroke
				(width 0)
				(type default)
			)
			(fill no)
			(layer "F.Fab")
		)
		(fp_rect
			(start 2.54 4.2926)
			(end 3.81 -4.2926)
			(stroke
				(width 0)
				(type default)
			)
			(fill no)
			(layer "F.Fab")
		)
		(pad "1" smd rect
			(at 0 -3.1496 270)
			(size 2.413 2.286)
			(layers "F.Cu" "F.Mask" "F.Paste")
			(net "P0V9")
		)
		(pad "2" smd rect
			(at 0 3.1496 270)
			(size 2.413 2.286)
			(layers "F.Cu" "F.Mask" "F.Paste")
			(net "GND")
		)
		(zone
			(layer "F.Cu")
			(hatch none 0.5)
			(connect_pads
				(clearance 0)
			)
			(min_thickness 0.25)
			(keepout
				(tracks allowed)
				(vias not_allowed)
				(pads allowed)
				(copperpour not_allowed)
				(footprints allowed)
			)
			(placement
				(enabled no)
				(sheetname "")
			)
			(fill
				(thermal_gap 0.5)
				(thermal_bridge_width 0.5)
				(island_removal_mode 0)
			)
			(polygon
				(pts
					(xy 58.166 -55.7403) (xy 58.166 -52.7177) (xy 61.0616 -52.7177) (xy 61.3918 -52.7177) (xy 61.3918 -55.7403)
					(xy 61.0616 -55.7403)
				)
			)
		)
		(zone
			(layer "F.Cu")
			(hatch none 0.5)
			(connect_pads
				(clearance 0)
			)
			(min_thickness 0.25)
			(keepout
				(tracks allowed)
				(vias not_allowed)
				(pads allowed)
				(copperpour not_allowed)
				(footprints allowed)
			)
			(placement
				(enabled no)
				(sheetname "")
			)
			(fill
				(thermal_gap 0.5)
				(thermal_bridge_width 0.5)
				(island_removal_mode 0)
			)
			(polygon
				(pts
					(xy 64.4525 -52.7177) (xy 67.3608 -52.7177) (xy 67.3608 -55.7403) (xy 64.4652 -55.7403) (xy 64.135 -55.7403)
					(xy 64.135 -52.7177)
				)
			)
		)
	)
	(footprint ""
		(layer "F.Cu")
		(at 73.533 -41.148 180)
		(property "Reference" "C283"
			(at 0 0 180)
			(layer "F.SilkS")
			(hide yes)
			(effects
				(font
					(size 1.27 1.27)
				)
			)
		)
		(property "Value" "SC100U6D3V6MX-GP"
			(at -0.0762 -5.1308 180)
			(unlocked yes)
			(layer "F.Fab")
			(hide yes)
			(effects
				(font
					(size 1.016 1.016)
					(thickness 0.1524)
				)
			)
		)
		(property "Device Type" "C1206H71"
			(at -0.127 -6.6548 180)
			(unlocked yes)
			(layer "F.Fab")
			(hide yes)
			(effects
				(font
					(size 1.016 1.016)
					(thickness 0.1524)
				)
			)
		)
		(duplicate_pad_numbers_are_jumpers no)
		(fp_line
			(start 1.016 2.2352)
			(end -1.016 2.2352)
			(stroke
				(width 0.1524)
				(type default)
			)
			(layer "F.SilkS")
		)
		(fp_line
			(start 1.016 0.8382)
			(end 1.016 2.2352)
			(stroke
				(width 0.1524)
				(type default)
			)
			(layer "F.SilkS")
		)
		(fp_line
			(start 1.016 -2.2352)
			(end 1.016 -0.8382)
			(stroke
				(width 0.1524)
				(type default)
			)
			(layer "F.SilkS")
		)
		(fp_line
			(start -1.016 2.2352)
			(end -1.016 0.8382)
			(stroke
				(width 0.1524)
				(type default)
			)
			(layer "F.SilkS")
		)
		(fp_line
			(start -1.016 -0.8382)
			(end -1.016 -2.2352)
			(stroke
				(width 0.1524)
				(type default)
			)
			(layer "F.SilkS")
		)
		(fp_line
			(start -1.016 -2.2352)
			(end 1.016 -2.2352)
			(stroke
				(width 0.1524)
				(type default)
			)
			(layer "F.SilkS")
		)
		(fp_rect
			(start -1.0922 2.3114)
			(end 1.0922 -2.3114)
			(stroke
				(width 0)
				(type default)
			)
			(fill no)
			(layer "F.CrtYd")
		)
		(fp_poly
			(pts
				(xy 1.0922 -2.3114) (xy 1.0922 2.3114) (xy -1.0922 2.3114) (xy -1.0922 -2.3114)
			)
			(stroke
				(width 0)
				(type default)
			)
			(fill no)
			(layer "F.Fab")
		)
		(pad "1" smd rect
			(at 0 -1.397 180)
			(size 1.651 1.27)
			(layers "F.Cu" "F.Mask" "F.Paste")
			(net "GB_VDDA")
		)
		(pad "2" smd rect
			(at 0 1.397 180)
			(size 1.651 1.27)
			(layers "F.Cu" "F.Mask" "F.Paste")
			(net "GND")
		)
	)
	(footprint ""
		(layer "F.Cu")
		(at 5.588 -94.831408 180)
		(property "Reference" "R425"
			(at 0 0 180)
			(layer "F.SilkS")
			(hide yes)
			(effects
				(font
					(size 1.27 1.27)
				)
			)
		)
		(property "Value" "200KR2F-L-GP"
			(at 0.064008 -3.993896 180)
			(unlocked yes)
			(layer "F.Fab")
			(hide yes)
			(effects
				(font
					(size 1.016 1.016)
					(thickness 0.1524)
				)
			)
		)
		(property "Device Type" "R402H16"
			(at 0.064008 -5.517896 180)
			(unlocked yes)
			(layer "F.Fab")
			(hide yes)
			(effects
				(font
					(size 1.016 1.016)
					(thickness 0.1524)
				)
			)
		)
		(duplicate_pad_numbers_are_jumpers no)
		(fp_line
			(start 0.508 -0.9398)
			(end -0.508 -0.9398)
			(stroke
				(width 0.1524)
				(type default)
			)
			(layer "F.SilkS")
		)
		(fp_line
			(start -0.508 -0.9398)
			(end -0.508 0.9398)
			(stroke
				(width 0.1524)
				(type default)
			)
			(layer "F.SilkS")
		)
		(fp_rect
			(start -0.508 0.9398)
			(end 0.508 -0.9398)
			(stroke
				(width 0)
				(type default)
			)
			(fill no)
			(layer "F.CrtYd")
		)
		(fp_rect
			(start -0.508 0.9398)
			(end 0.508 -0.9398)
			(stroke
				(width 0)
				(type default)
			)
			(fill no)
			(layer "F.Fab")
		)
		(pad "1" smd custom
			(at 0 -0.4445 180)
			(size 0.1397 0.1397)
			(layers "F.Cu" "F.Mask" "F.Paste")
			(net "LS_EN_U36")
			(options
				(clearance outline)
				(anchor circle)
			)
			(primitives
				(gr_poly
					(pts
						(arc
							(start -0.1778 -0.2794)
							(mid -0.249642 -0.249642)
							(end -0.2794 -0.1778)
						)
						(arc
							(start -0.2794 0.1778)
							(mid -0.249642 0.249642)
							(end -0.1778 0.2794)
						)
						(arc
							(start 0.1778 0.2794)
							(mid 0.249642 0.249642)
							(end 0.2794 0.1778)
						)
						(arc
							(start 0.2794 -0.1778)
							(mid 0.249642 -0.249642)
							(end 0.1778 -0.2794)
						)
					)
					(width 0)
					(fill yes)
				)
			)
		)
		(pad "2" smd custom
			(at 0 0.4445 180)
			(size 0.1397 0.1397)
			(layers "F.Cu" "F.Mask" "F.Paste")
			(net "P0V9_PG")
			(options
				(clearance outline)
				(anchor circle)
			)
			(primitives
				(gr_poly
					(pts
						(arc
							(start -0.1778 -0.2794)
							(mid -0.249642 -0.249642)
							(end -0.2794 -0.1778)
						)
						(arc
							(start -0.2794 0.1778)
							(mid -0.249642 0.249642)
							(end -0.1778 0.2794)
						)
						(arc
							(start 0.1778 0.2794)
							(mid 0.249642 0.249642)
							(end 0.2794 0.1778)
						)
						(arc
							(start 0.2794 -0.1778)
							(mid 0.249642 -0.249642)
							(end 0.1778 -0.2794)
						)
					)
					(width 0)
					(fill yes)
				)
			)
		)
	)
	(footprint ""
		(layer "F.Cu")
		(at 45.1612 -33.401 180)
		(property "Reference" "U8"
			(at 0 0 180)
			(layer "F.SilkS")
			(hide yes)
			(effects
				(font
					(size 1.27 1.27)
				)
			)
		)
		(property "Value" "TPS51219RTER-1-GP"
			(at -4.064 -6.722618 180)
			(unlocked yes)
			(layer "F.Fab")
			(hide yes)
			(effects
				(font
					(size 1.016 1.016)
					(thickness 0.1524)
				)
			)
		)
		(property "Device Type" "QFN16-G1D8-UH32"
			(at -4.064 -8.246618 180)
			(unlocked yes)
			(layer "F.Fab")
			(hide yes)
			(effects
				(font
					(size 1.016 1.016)
					(thickness 0.1524)
				)
			)
		)
		(duplicate_pad_numbers_are_jumpers no)
		(fp_line
			(start 2.5146 2.5146)
			(end 2.5146 1.2446)
			(stroke
				(width 0.1524)
				(type default)
			)
			(layer "F.SilkS")
		)
		(fp_line
			(start 2.287524 -0.260604)
			(end 2.795524 -0.260604)
			(stroke
				(width 0.1524)
				(type default)
			)
			(layer "F.SilkS")
		)
		(fp_line
			(start 1.2446 2.5146)
			(end 2.5146 2.5146)
			(stroke
				(width 0.1524)
				(type default)
			)
			(layer "F.SilkS")
		)
		(fp_line
			(start -0.248666 2.287524)
			(end -0.248666 3.049524)
			(stroke
				(width 0.1524)
				(type default)
			)
			(layer "F.SilkS")
		)
		(fp_line
			(start -1.2446 -2.5146)
			(end -2.5146 -2.5146)
			(stroke
				(width 0.1524)
				(type default)
			)
			(layer "F.SilkS")
		)
		(fp_line
			(start -2.287524 -0.753364)
			(end -2.795524 -0.753364)
			(stroke
				(width 0.1524)
				(type default)
			)
			(layer "F.SilkS")
		)
		(fp_line
			(start -2.5146 2.5146)
			(end -1.2446 2.5146)
			(stroke
				(width 0.1524)
				(type default)
			)
			(layer "F.SilkS")
		)
		(fp_line
			(start -2.5146 1.2446)
			(end -2.5146 2.5146)
			(stroke
				(width 0.1524)
				(type default)
			)
			(layer "F.SilkS")
		)
		(fp_line
			(start -2.5146 -2.5146)
			(end -2.5146 -1.2446)
			(stroke
				(width 0.1524)
				(type default)
			)
			(layer "F.SilkS")
		)
		(fp_poly
			(pts
				(xy 1.2446 -2.5146) (xy 2.5146 -2.5146) (xy 2.5146 -1.2446)
			)
			(stroke
				(width 0)
				(type default)
			)
			(fill yes)
			(layer "F.SilkS")
		)
		(fp_rect
			(start -1.4986 1.4986)
			(end 1.4986 -1.4986)
			(stroke
				(width 0)
				(type default)
			)
			(fill no)
			(layer "F.CrtYd")
		)
		(fp_poly
			(pts
				(xy -1.4986 -1.4986) (xy -2.5146 -1.4986) (xy -2.5146 -2.5146) (xy 2.5146 -2.5146) (xy 2.5146 2.5146)
				(xy -2.5146 2.5146) (xy -2.5146 -1.4859) (xy -1.4986 -1.4859) (xy -1.4986 1.4986) (xy 1.4986 1.4986)
				(xy 1.4986 -1.4986)
			)
			(stroke
				(width 0)
				(type default)
			)
			(fill no)
			(layer "F.CrtYd")
		)
		(fp_rect
			(start -2.5146 2.5146)
			(end 2.5146 -2.5146)
			(stroke
				(width 0)
				(type default)
			)
			(fill no)
			(layer "F.Fab")
		)
		(pad "1" smd rect
			(at 0.750062 -1.550924 180)
			(size 0.3048 0.9144)
			(layers "F.Cu" "F.Mask" "F.Paste")
			(net "P0V9_VREF")
		)
		(pad "2" smd rect
			(at 0.249936 -1.550924 180)
			(size 0.3048 0.9144)
			(layers "F.Cu" "F.Mask" "F.Paste")
			(net "P0V9_REFIN")
		)
		(pad "3" smd rect
			(at -0.249936 -1.550924 180)
			(size 0.3048 0.9144)
			(layers "F.Cu" "F.Mask" "F.Paste")
			(net "P0V9_GSNS")
		)
		(pad "4" smd rect
			(at -0.750062 -1.550924 180)
			(size 0.3048 0.9144)
			(layers "F.Cu" "F.Mask" "F.Paste")
			(net "P0V9_VSNS")
		)
		(pad "5" smd rect
			(at -1.550924 -0.750062 180)
			(size 0.9144 0.3048)
			(layers "F.Cu" "F.Mask" "F.Paste")
			(net "P0V9_COMP")
		)
		(pad "6" smd rect
			(at -1.550924 -0.249936 180)
			(size 0.9144 0.3048)
			(layers "F.Cu" "F.Mask" "F.Paste")
			(net "P0V9_TRIP")
		)
		(pad "7" smd rect
			(at -1.550924 0.249936 180)
			(size 0.9144 0.3048)
			(layers "F.Cu" "F.Mask" "F.Paste")
			(net "AGND_P0V9")
		)
		(pad "8" smd rect
			(at -1.550924 0.750062 180)
			(size 0.9144 0.3048)
			(layers "F.Cu" "F.Mask" "F.Paste")
			(net "GND")
		)
		(pad "9" smd rect
			(at -0.750062 1.550924 180)
			(size 0.3048 0.9144)
			(layers "F.Cu" "F.Mask" "F.Paste")
			(net "P0V9_V5")
		)
		(pad "10" smd rect
			(at -0.249936 1.550924 180)
			(size 0.3048 0.9144)
			(layers "F.Cu" "F.Mask" "F.Paste")
			(net "P0V9_DL")
		)
		(pad "11" smd rect
			(at 0.249936 1.550924 180)
			(size 0.3048 0.9144)
			(layers "F.Cu" "F.Mask" "F.Paste")
			(net "P0V9_DH")
		)
		(pad "12" smd rect
			(at 0.750062 1.550924 180)
			(size 0.3048 0.9144)
			(layers "F.Cu" "F.Mask" "F.Paste")
			(net "P0V9_SW")
		)
		(pad "13" smd rect
			(at 1.550924 0.750062 180)
			(size 0.9144 0.3048)
			(layers "F.Cu" "F.Mask" "F.Paste")
			(net "P0V9_BST")
		)
		(pad "14" smd rect
			(at 1.550924 0.249936 180)
			(size 0.9144 0.3048)
			(layers "F.Cu" "F.Mask" "F.Paste")
			(net "P0V9_EN")
		)
		(pad "15" smd rect
			(at 1.550924 -0.249936 180)
			(size 0.9144 0.3048)
			(layers "F.Cu" "F.Mask" "F.Paste")
			(net "P0V9_MODE")
		)
		(pad "16" smd rect
			(at 1.550924 -0.750062 180)
			(size 0.9144 0.3048)
			(layers "F.Cu" "F.Mask" "F.Paste")
			(net "P0V9_U8_PG")
		)
		(pad "17" smd rect
			(at 0 0 180)
			(size 1.778 1.778)
			(layers "F.Cu" "F.Mask" "F.Paste")
			(net "GND")
		)
	)
	(footprint ""
		(layer "F.Cu")
		(at 70.866 -101.6)
		(property "Reference" "R518"
			(at 0 0 0)
			(layer "F.SilkS")
			(hide yes)
			(effects
				(font
					(size 1.27 1.27)
				)
			)
		)
		(property "Value" "10KR2F-2-GP"
			(at 0.064008 -3.993896 0)
			(unlocked yes)
			(layer "F.Fab")
			(hide yes)
			(effects
				(font
					(size 1.016 1.016)
					(thickness 0.1524)
				)
			)
		)
		(property "Device Type" "R402H16"
			(at 0.064008 -5.517896 0)
			(unlocked yes)
			(layer "F.Fab")
			(hide yes)
			(effects
				(font
					(size 1.016 1.016)
					(thickness 0.1524)
				)
			)
		)
		(duplicate_pad_numbers_are_jumpers no)
		(fp_line
			(start -0.508 -0.9398)
			(end -0.508 0.9398)
			(stroke
				(width 0.1524)
				(type default)
			)
			(layer "F.SilkS")
		)
		(fp_line
			(start 0.508 -0.9398)
			(end -0.508 -0.9398)
			(stroke
				(width 0.1524)
				(type default)
			)
			(layer "F.SilkS")
		)
		(fp_rect
			(start -0.508 0.9398)
			(end 0.508 -0.9398)
			(stroke
				(width 0)
				(type default)
			)
			(fill no)
			(layer "F.CrtYd")
		)
		(fp_rect
			(start -0.508 0.9398)
			(end 0.508 -0.9398)
			(stroke
				(width 0)
				(type default)
			)
			(fill no)
			(layer "F.Fab")
		)
		(pad "1" smd custom
			(at 0 -0.4445)
			(size 0.1397 0.1397)
			(layers "F.Cu" "F.Mask" "F.Paste")
			(net "P3V3_VFB")
			(options
				(clearance outline)
				(anchor circle)
			)
			(primitives
				(gr_poly
					(pts
						(arc
							(start -0.1778 -0.2794)
							(mid -0.249642 -0.249642)
							(end -0.2794 -0.1778)
						)
						(arc
							(start -0.2794 0.1778)
							(mid -0.249642 0.249642)
							(end -0.1778 0.2794)
						)
						(arc
							(start 0.1778 0.2794)
							(mid 0.249642 0.249642)
							(end 0.2794 0.1778)
						)
						(arc
							(start 0.2794 -0.1778)
							(mid 0.249642 -0.249642)
							(end 0.1778 -0.2794)
						)
					)
					(width 0)
					(fill yes)
				)
			)
		)
		(pad "2" smd custom
			(at 0 0.4445)
			(size 0.1397 0.1397)
			(layers "F.Cu" "F.Mask" "F.Paste")
			(net "AGND_P3V3")
			(options
				(clearance outline)
				(anchor circle)
			)
			(primitives
				(gr_poly
					(pts
						(arc
							(start -0.1778 -0.2794)
							(mid -0.249642 -0.249642)
							(end -0.2794 -0.1778)
						)
						(arc
							(start -0.2794 0.1778)
							(mid -0.249642 0.249642)
							(end -0.1778 0.2794)
						)
						(arc
							(start 0.1778 0.2794)
							(mid 0.249642 0.249642)
							(end 0.2794 0.1778)
						)
						(arc
							(start 0.2794 -0.1778)
							(mid 0.249642 -0.249642)
							(end 0.1778 -0.2794)
						)
					)
					(width 0)
					(fill yes)
				)
			)
		)
	)
	(footprint ""
		(layer "F.Cu")
		(at 61.1632 -71.0438 90)
		(property "Reference" "C552"
			(at 0 0 90)
			(layer "F.SilkS")
			(hide yes)
			(effects
				(font
					(size 1.27 1.27)
				)
			)
		)
		(property "Value" "SCD1U16V2KX-3GP"
			(at 1.1811 -2.7051 90)
			(unlocked yes)
			(layer "F.Fab")
			(hide yes)
			(effects
				(font
					(size 1.016 1.016)
					(thickness 0.1524)
				)
			)
		)
		(property "Device Type" "C402H22"
			(at 1.1811 -4.2291 90)
			(unlocked yes)
			(layer "F.Fab")
			(hide yes)
			(effects
				(font
					(size 1.016 1.016)
					(thickness 0.1524)
				)
			)
		)
		(duplicate_pad_numbers_are_jumpers no)
		(fp_rect
			(start -0.4318 0.9525)
			(end 0.4318 -0.9525)
			(stroke
				(width 0)
				(type default)
			)
			(fill no)
			(layer "F.CrtYd")
		)
		(fp_rect
			(start -0.4318 0.9525)
			(end 0.4318 -0.9525)
			(stroke
				(width 0)
				(type default)
			)
			(fill no)
			(layer "F.Fab")
		)
		(pad "1" smd custom
			(at 0 -0.4445 90)
			(size 0.1524 0.1524)
			(layers "F.Cu" "F.Mask" "F.Paste")
			(net "VREF4")
			(options
				(clearance outline)
				(anchor circle)
			)
			(primitives
				(gr_poly
					(pts
						(arc
							(start 0.3048 -0.2032)
							(mid 0.275042 -0.275042)
							(end 0.2032 -0.3048)
						)
						(arc
							(start -0.2032 -0.3048)
							(mid -0.275042 -0.275042)
							(end -0.3048 -0.2032)
						)
						(arc
							(start -0.3048 0.2032)
							(mid -0.275042 0.275042)
							(end -0.2032 0.3048)
						)
						(arc
							(start 0.2032 0.3048)
							(mid 0.275042 0.275042)
							(end 0.3048 0.2032)
						)
					)
					(width 0)
					(fill yes)
				)
			)
		)
		(pad "2" smd custom
			(at 0 0.4445 90)
			(size 0.1524 0.1524)
			(layers "F.Cu" "F.Mask" "F.Paste")
			(net "GND")
			(options
				(clearance outline)
				(anchor circle)
			)
			(primitives
				(gr_poly
					(pts
						(arc
							(start 0.3048 -0.2032)
							(mid 0.275042 -0.275042)
							(end 0.2032 -0.3048)
						)
						(arc
							(start -0.2032 -0.3048)
							(mid -0.275042 -0.275042)
							(end -0.3048 -0.2032)
						)
						(arc
							(start -0.3048 0.2032)
							(mid -0.275042 0.275042)
							(end -0.2032 0.3048)
						)
						(arc
							(start 0.2032 0.3048)
							(mid 0.275042 0.275042)
							(end 0.3048 0.2032)
						)
					)
					(width 0)
					(fill yes)
				)
			)
		)
	)
	(footprint ""
		(layer "F.Cu")
		(at 70.104 -10.795 90)
		(property "Reference" "R245"
			(at 0 0 90)
			(layer "F.SilkS")
			(hide yes)
			(effects
				(font
					(size 1.27 1.27)
				)
			)
		)
		(property "Value" "0R2J-2-GP"
			(at 0.064008 -3.993896 90)
			(unlocked yes)
			(layer "F.Fab")
			(hide yes)
			(effects
				(font
					(size 1.016 1.016)
					(thickness 0.1524)
				)
			)
		)
		(property "Device Type" "R402H16"
			(at 0.064008 -5.517896 90)
			(unlocked yes)
			(layer "F.Fab")
			(hide yes)
			(effects
				(font
					(size 1.016 1.016)
					(thickness 0.1524)
				)
			)
		)
		(duplicate_pad_numbers_are_jumpers no)
		(fp_line
			(start 0.508 -0.9398)
			(end -0.508 -0.9398)
			(stroke
				(width 0.1524)
				(type default)
			)
			(layer "F.SilkS")
		)
		(fp_line
			(start -0.508 -0.9398)
			(end -0.508 0.9398)
			(stroke
				(width 0.1524)
				(type default)
			)
			(layer "F.SilkS")
		)
		(fp_rect
			(start -0.508 0.9398)
			(end 0.508 -0.9398)
			(stroke
				(width 0)
				(type default)
			)
			(fill no)
			(layer "F.CrtYd")
		)
		(fp_rect
			(start -0.508 0.9398)
			(end 0.508 -0.9398)
			(stroke
				(width 0)
				(type default)
			)
			(fill no)
			(layer "F.Fab")
		)
		(pad "1" smd custom
			(at 0 -0.4445 90)
			(size 0.1397 0.1397)
			(layers "F.Cu" "F.Mask" "F.Paste")
			(net "GND")
			(options
				(clearance outline)
				(anchor circle)
			)
			(primitives
				(gr_poly
					(pts
						(arc
							(start -0.1778 -0.2794)
							(mid -0.249642 -0.249642)
							(end -0.2794 -0.1778)
						)
						(arc
							(start -0.2794 0.1778)
							(mid -0.249642 0.249642)
							(end -0.1778 0.2794)
						)
						(arc
							(start 0.1778 0.2794)
							(mid 0.249642 0.249642)
							(end 0.2794 0.1778)
						)
						(arc
							(start 0.2794 -0.1778)
							(mid 0.249642 -0.249642)
							(end 0.1778 -0.2794)
						)
					)
					(width 0)
					(fill yes)
				)
			)
		)
		(pad "2" smd custom
			(at 0 0.4445 90)
			(size 0.1397 0.1397)
			(layers "F.Cu" "F.Mask" "F.Paste")
			(net "SCC_TYPE_3")
			(options
				(clearance outline)
				(anchor circle)
			)
			(primitives
				(gr_poly
					(pts
						(arc
							(start -0.1778 -0.2794)
							(mid -0.249642 -0.249642)
							(end -0.2794 -0.1778)
						)
						(arc
							(start -0.2794 0.1778)
							(mid -0.249642 0.249642)
							(end -0.1778 0.2794)
						)
						(arc
							(start 0.1778 0.2794)
							(mid 0.249642 0.249642)
							(end 0.2794 0.1778)
						)
						(arc
							(start 0.2794 -0.1778)
							(mid 0.249642 -0.249642)
							(end 0.1778 -0.2794)
						)
					)
					(width 0)
					(fill yes)
				)
			)
		)
	)
	(footprint ""
		(layer "F.Cu")
		(at 152.980898 -81.903824 -90)
		(property "Reference" "R326"
			(at 0 0 270)
			(layer "F.SilkS")
			(hide yes)
			(effects
				(font
					(size 1.27 1.27)
				)
			)
		)
		(property "Value" "0R2J-2-GP"
			(at 0.064008 -3.993896 270)
			(unlocked yes)
			(layer "F.Fab")
			(hide yes)
			(effects
				(font
					(size 1.016 1.016)
					(thickness 0.1524)
				)
			)
		)
		(property "Device Type" "R402H16"
			(at 0.064008 -5.517896 270)
			(unlocked yes)
			(layer "F.Fab")
			(hide yes)
			(effects
				(font
					(size 1.016 1.016)
					(thickness 0.1524)
				)
			)
		)
		(duplicate_pad_numbers_are_jumpers no)
		(fp_line
			(start -0.508 -0.9398)
			(end -0.508 0.9398)
			(stroke
				(width 0.1524)
				(type default)
			)
			(layer "F.SilkS")
		)
		(fp_line
			(start 0.508 -0.9398)
			(end -0.508 -0.9398)
			(stroke
				(width 0.1524)
				(type default)
			)
			(layer "F.SilkS")
		)
		(fp_rect
			(start -0.508 0.9398)
			(end 0.508 -0.9398)
			(stroke
				(width 0)
				(type default)
			)
			(fill no)
			(layer "F.CrtYd")
		)
		(fp_rect
			(start -0.508 0.9398)
			(end 0.508 -0.9398)
			(stroke
				(width 0)
				(type default)
			)
			(fill no)
			(layer "F.Fab")
		)
		(pad "1" smd custom
			(at 0 -0.4445 270)
			(size 0.1397 0.1397)
			(layers "F.Cu" "F.Mask" "F.Paste")
			(net "VOL_SEN1_SDA")
			(options
				(clearance outline)
				(anchor circle)
			)
			(primitives
				(gr_poly
					(pts
						(arc
							(start -0.1778 -0.2794)
							(mid -0.249642 -0.249642)
							(end -0.2794 -0.1778)
						)
						(arc
							(start -0.2794 0.1778)
							(mid -0.249642 0.249642)
							(end -0.1778 0.2794)
						)
						(arc
							(start 0.1778 0.2794)
							(mid 0.249642 0.249642)
							(end 0.2794 0.1778)
						)
						(arc
							(start 0.2794 -0.1778)
							(mid 0.249642 -0.249642)
							(end 0.1778 -0.2794)
						)
					)
					(width 0)
					(fill yes)
				)
			)
		)
		(pad "2" smd custom
			(at 0 0.4445 270)
			(size 0.1397 0.1397)
			(layers "F.Cu" "F.Mask" "F.Paste")
			(net "I2C_SCC_SDA2")
			(options
				(clearance outline)
				(anchor circle)
			)
			(primitives
				(gr_poly
					(pts
						(arc
							(start -0.1778 -0.2794)
							(mid -0.249642 -0.249642)
							(end -0.2794 -0.1778)
						)
						(arc
							(start -0.2794 0.1778)
							(mid -0.249642 0.249642)
							(end -0.1778 0.2794)
						)
						(arc
							(start 0.1778 0.2794)
							(mid 0.249642 0.249642)
							(end 0.2794 0.1778)
						)
						(arc
							(start 0.2794 -0.1778)
							(mid 0.249642 -0.249642)
							(end 0.1778 -0.2794)
						)
					)
					(width 0)
					(fill yes)
				)
			)
		)
	)
	(footprint ""
		(layer "F.Cu")
		(at 164.075872 -58.114438)
		(property "Reference" "R260"
			(at 0 0 0)
			(layer "F.SilkS")
			(hide yes)
			(effects
				(font
					(size 1.27 1.27)
				)
			)
		)
		(property "Value" "4K7R2F-GP"
			(at 0.064008 -3.993896 0)
			(unlocked yes)
			(layer "F.Fab")
			(hide yes)
			(effects
				(font
					(size 1.016 1.016)
					(thickness 0.1524)
				)
			)
		)
		(property "Device Type" "R402H16"
			(at 0.064008 -5.517896 0)
			(unlocked yes)
			(layer "F.Fab")
			(hide yes)
			(effects
				(font
					(size 1.016 1.016)
					(thickness 0.1524)
				)
			)
		)
		(duplicate_pad_numbers_are_jumpers no)
		(fp_line
			(start -0.508 -0.9398)
			(end -0.508 0.9398)
			(stroke
				(width 0.1524)
				(type default)
			)
			(layer "F.SilkS")
		)
		(fp_line
			(start 0.508 -0.9398)
			(end -0.508 -0.9398)
			(stroke
				(width 0.1524)
				(type default)
			)
			(layer "F.SilkS")
		)
		(fp_rect
			(start -0.508 0.9398)
			(end 0.508 -0.9398)
			(stroke
				(width 0)
				(type default)
			)
			(fill no)
			(layer "F.CrtYd")
		)
		(fp_rect
			(start -0.508 0.9398)
			(end 0.508 -0.9398)
			(stroke
				(width 0)
				(type default)
			)
			(fill no)
			(layer "F.Fab")
		)
		(pad "1" smd custom
			(at 0 -0.4445)
			(size 0.1397 0.1397)
			(layers "F.Cu" "F.Mask" "F.Paste")
			(net "P1V8_C")
			(options
				(clearance outline)
				(anchor circle)
			)
			(primitives
				(gr_poly
					(pts
						(arc
							(start -0.1778 -0.2794)
							(mid -0.249642 -0.249642)
							(end -0.2794 -0.1778)
						)
						(arc
							(start -0.2794 0.1778)
							(mid -0.249642 0.249642)
							(end -0.1778 0.2794)
						)
						(arc
							(start 0.1778 0.2794)
							(mid 0.249642 0.249642)
							(end 0.2794 0.1778)
						)
						(arc
							(start 0.2794 -0.1778)
							(mid 0.249642 -0.249642)
							(end 0.1778 -0.2794)
						)
					)
					(width 0)
					(fill yes)
				)
			)
		)
		(pad "2" smd custom
			(at 0 0.4445)
			(size 0.1397 0.1397)
			(layers "F.Cu" "F.Mask" "F.Paste")
			(net "ICE1_TRST#")
			(options
				(clearance outline)
				(anchor circle)
			)
			(primitives
				(gr_poly
					(pts
						(arc
							(start -0.1778 -0.2794)
							(mid -0.249642 -0.249642)
							(end -0.2794 -0.1778)
						)
						(arc
							(start -0.2794 0.1778)
							(mid -0.249642 0.249642)
							(end -0.1778 0.2794)
						)
						(arc
							(start 0.1778 0.2794)
							(mid 0.249642 0.249642)
							(end 0.2794 0.1778)
						)
						(arc
							(start 0.2794 -0.1778)
							(mid 0.249642 -0.249642)
							(end 0.1778 -0.2794)
						)
					)
					(width 0)
					(fill yes)
				)
			)
		)
	)
	(footprint ""
		(layer "F.Cu")
		(at 193.0654 -33.2486 -90)
		(property "Reference" "TP99"
			(at 0 0 270)
			(layer "F.SilkS")
			(hide yes)
			(effects
				(font
					(size 1.27 1.27)
				)
			)
		)
		(property "Value" "TPAD28-2-GP"
			(at -0.0127 -1.6637 270)
			(unlocked yes)
			(layer "F.Fab")
			(hide yes)
			(effects
				(font
					(size 1.016 1.016)
					(thickness 0.1524)
				)
			)
		)
		(property "Device Type" "TPAD28"
			(at -0.0127 -3.1877 270)
			(unlocked yes)
			(layer "F.Fab")
			(hide yes)
			(effects
				(font
					(size 1.016 1.016)
					(thickness 0.1524)
				)
			)
		)
		(duplicate_pad_numbers_are_jumpers no)
		(fp_poly
			(pts
				(arc
					(start 0 -0.3556)
					(mid 0 0.3556)
					(end 0 -0.3556)
				)
			)
			(stroke
				(width 0)
				(type default)
			)
			(fill no)
			(layer "F.CrtYd")
		)
		(fp_poly
			(pts
				(arc
					(start 0 -0.6096)
					(mid 0 0.6096)
					(end 0 -0.6096)
				)
			)
			(stroke
				(width 0)
				(type default)
			)
			(fill no)
			(layer "F.Fab")
		)
		(pad "1" smd circle
			(at 0 0 270)
			(size 0.7112 0.7112)
			(layers "F.Cu" "F.Mask" "F.Paste")
			(net "IOC_GPIO_37")
		)
	)
	(footprint ""
		(layer "F.Cu")
		(at 125.2728 -89.916)
		(property "Reference" "R113"
			(at 0 0 0)
			(layer "F.SilkS")
			(hide yes)
			(effects
				(font
					(size 1.27 1.27)
				)
			)
		)
		(property "Value" "4K75R2F-1-GP"
			(at 0.064008 -3.993896 0)
			(unlocked yes)
			(layer "F.Fab")
			(hide yes)
			(effects
				(font
					(size 1.016 1.016)
					(thickness 0.1524)
				)
			)
		)
		(property "Device Type" "R402H16"
			(at 0.064008 -5.517896 0)
			(unlocked yes)
			(layer "F.Fab")
			(hide yes)
			(effects
				(font
					(size 1.016 1.016)
					(thickness 0.1524)
				)
			)
		)
		(duplicate_pad_numbers_are_jumpers no)
		(fp_line
			(start -0.508 -0.9398)
			(end -0.508 0.9398)
			(stroke
				(width 0.1524)
				(type default)
			)
			(layer "F.SilkS")
		)
		(fp_line
			(start 0.508 -0.9398)
			(end -0.508 -0.9398)
			(stroke
				(width 0.1524)
				(type default)
			)
			(layer "F.SilkS")
		)
		(fp_rect
			(start -0.508 0.9398)
			(end 0.508 -0.9398)
			(stroke
				(width 0)
				(type default)
			)
			(fill no)
			(layer "F.CrtYd")
		)
		(fp_rect
			(start -0.508 0.9398)
			(end 0.508 -0.9398)
			(stroke
				(width 0)
				(type default)
			)
			(fill no)
			(layer "F.Fab")
		)
		(pad "1" smd custom
			(at 0 -0.4445)
			(size 0.1397 0.1397)
			(layers "F.Cu" "F.Mask" "F.Paste")
			(net "P1V8_E")
			(options
				(clearance outline)
				(anchor circle)
			)
			(primitives
				(gr_poly
					(pts
						(arc
							(start -0.1778 -0.2794)
							(mid -0.249642 -0.249642)
							(end -0.2794 -0.1778)
						)
						(arc
							(start -0.2794 0.1778)
							(mid -0.249642 0.249642)
							(end -0.1778 0.2794)
						)
						(arc
							(start 0.1778 0.2794)
							(mid 0.249642 0.249642)
							(end 0.2794 0.1778)
						)
						(arc
							(start 0.2794 -0.1778)
							(mid 0.249642 -0.249642)
							(end 0.1778 -0.2794)
						)
					)
					(width 0)
					(fill yes)
				)
			)
		)
		(pad "2" smd custom
			(at 0 0.4445)
			(size 0.1397 0.1397)
			(layers "F.Cu" "F.Mask" "F.Paste")
			(net "SDB_RX")
			(options
				(clearance outline)
				(anchor circle)
			)
			(primitives
				(gr_poly
					(pts
						(arc
							(start -0.1778 -0.2794)
							(mid -0.249642 -0.249642)
							(end -0.2794 -0.1778)
						)
						(arc
							(start -0.2794 0.1778)
							(mid -0.249642 0.249642)
							(end -0.1778 0.2794)
						)
						(arc
							(start 0.1778 0.2794)
							(mid 0.249642 0.249642)
							(end 0.2794 0.1778)
						)
						(arc
							(start 0.2794 -0.1778)
							(mid 0.249642 -0.249642)
							(end 0.1778 -0.2794)
						)
					)
					(width 0)
					(fill yes)
				)
			)
		)
	)
	(footprint ""
		(layer "F.Cu")
		(at 186.44616 -111.14786)
		(property "Reference" "Q34"
			(at 0 0 0)
			(layer "F.SilkS")
			(hide yes)
			(effects
				(font
					(size 1.27 1.27)
				)
			)
		)
		(property "Value" "2N7002E-2-GP"
			(at 0.127 -8.9662 0)
			(unlocked yes)
			(layer "F.Fab")
			(hide yes)
			(effects
				(font
					(size 1.016 1.016)
					(thickness 0.1524)
				)
			)
		)
		(property "Device Type" "SOT23DGS2D4H44"
			(at 0.127 -10.4902 0)
			(unlocked yes)
			(layer "F.Fab")
			(hide yes)
			(effects
				(font
					(size 1.016 1.016)
					(thickness 0.1524)
				)
			)
		)
		(duplicate_pad_numbers_are_jumpers no)
		(fp_line
			(start -1.651 -1.778)
			(end -1.651 1.778)
			(stroke
				(width 0.1524)
				(type default)
			)
			(layer "F.SilkS")
		)
		(fp_line
			(start -1.651 1.778)
			(end 1.651 1.778)
			(stroke
				(width 0.1524)
				(type default)
			)
			(layer "F.SilkS")
		)
		(fp_line
			(start 1.651 -1.778)
			(end -1.651 -1.778)
			(stroke
				(width 0.1524)
				(type default)
			)
			(layer "F.SilkS")
		)
		(fp_line
			(start 1.651 1.778)
			(end 1.651 -1.778)
			(stroke
				(width 0.1524)
				(type default)
			)
			(layer "F.SilkS")
		)
		(fp_poly
			(pts
				(xy -1.778 1.8796) (xy -1.778 -1.8796) (xy 1.778 -1.8796) (xy 1.778 1.8796)
			)
			(stroke
				(width 0)
				(type default)
			)
			(fill no)
			(layer "F.CrtYd")
		)
		(fp_poly
			(pts
				(xy -1.778 1.8796) (xy -1.778 -1.8796) (xy 1.778 -1.8796) (xy 1.778 1.8796)
			)
			(stroke
				(width 0)
				(type default)
			)
			(fill no)
			(layer "F.Fab")
		)
		(pad "D" smd custom
			(at 0 -0.9525)
			(size 0.1905 0.1905)
			(layers "F.Cu" "F.Mask" "F.Paste")
			(net "P1V8_C_G_PG")
			(options
				(clearance outline)
				(anchor circle)
			)
			(primitives
				(gr_poly
					(pts
						(arc
							(start -0.1778 0.5715)
							(mid -0.321484 0.511984)
							(end -0.381 0.3683)
						)
						(arc
							(start -0.381 -0.3683)
							(mid -0.321484 -0.511984)
							(end -0.1778 -0.5715)
						)
						(arc
							(start 0.1778 -0.5715)
							(mid 0.321484 -0.511984)
							(end 0.381 -0.3683)
						)
						(arc
							(start 0.381 0.3683)
							(mid 0.321484 0.511984)
							(end 0.1778 0.5715)
						)
					)
					(width 0)
					(fill yes)
				)
			)
		)
		(pad "G" smd custom
			(at -0.98425 0.9525)
			(size 0.1905 0.1905)
			(layers "F.Cu" "F.Mask" "F.Paste")
			(net "P0V9_G_PG")
			(options
				(clearance outline)
				(anchor circle)
			)
			(primitives
				(gr_poly
					(pts
						(arc
							(start -0.1778 0.5715)
							(mid -0.321484 0.511984)
							(end -0.381 0.3683)
						)
						(arc
							(start -0.381 -0.3683)
							(mid -0.321484 -0.511984)
							(end -0.1778 -0.5715)
						)
						(arc
							(start 0.1778 -0.5715)
							(mid 0.321484 -0.511984)
							(end 0.381 -0.3683)
						)
						(arc
							(start 0.381 0.3683)
							(mid 0.321484 0.511984)
							(end 0.1778 0.5715)
						)
					)
					(width 0)
					(fill yes)
				)
			)
		)
		(pad "S" smd custom
			(at 0.98425 0.9525)
			(size 0.1905 0.1905)
			(layers "F.Cu" "F.Mask" "F.Paste")
			(net "P1V8_C_S")
			(options
				(clearance outline)
				(anchor circle)
			)
			(primitives
				(gr_poly
					(pts
						(arc
							(start -0.1778 0.5715)
							(mid -0.321484 0.511984)
							(end -0.381 0.3683)
						)
						(arc
							(start -0.381 -0.3683)
							(mid -0.321484 -0.511984)
							(end -0.1778 -0.5715)
						)
						(arc
							(start 0.1778 -0.5715)
							(mid 0.321484 -0.511984)
							(end 0.381 -0.3683)
						)
						(arc
							(start 0.381 0.3683)
							(mid 0.321484 0.511984)
							(end 0.1778 0.5715)
						)
					)
					(width 0)
					(fill yes)
				)
			)
		)
	)
	(footprint ""
		(layer "F.Cu")
		(at 70.612 -35.814 90)
		(property "Reference" "R161"
			(at 0 0 90)
			(layer "F.SilkS")
			(hide yes)
			(effects
				(font
					(size 1.27 1.27)
				)
			)
		)
		(property "Value" "D51R3F-2-GP"
			(at -0.0254 -2.5146 90)
			(unlocked yes)
			(layer "F.Fab")
			(hide yes)
			(effects
				(font
					(size 1.016 1.016)
					(thickness 0.1524)
				)
			)
		)
		(property "Device Type" "R603H22"
			(at -0.0254 -4.0386 90)
			(unlocked yes)
			(layer "F.Fab")
			(hide yes)
			(effects
				(font
					(size 1.016 1.016)
					(thickness 0.1524)
				)
			)
		)
		(duplicate_pad_numbers_are_jumpers no)
		(fp_line
			(start 0.2032 0)
			(end 0.4826 0)
			(stroke
				(width 0.2032)
				(type default)
			)
			(layer "F.SilkS")
		)
		(fp_line
			(start -0.4826 0)
			(end -0.2032 0)
			(stroke
				(width 0.2032)
				(type default)
			)
			(layer "F.SilkS")
		)
		(fp_rect
			(start -0.5842 1.3335)
			(end 0.5842 -1.3335)
			(stroke
				(width 0)
				(type default)
			)
			(fill no)
			(layer "F.CrtYd")
		)
		(fp_rect
			(start -0.5842 1.3335)
			(end 0.5842 -1.3335)
			(stroke
				(width 0)
				(type default)
			)
			(fill no)
			(layer "F.Fab")
		)
		(pad "1" smd custom
			(at 0 -0.762 90)
			(size 0.2159 0.2159)
			(layers "F.Cu" "F.Mask" "F.Paste")
			(net "P0V9")
			(options
				(clearance outline)
				(anchor circle)
			)
			(primitives
				(gr_poly
					(pts
						(arc
							(start -0.3302 -0.4318)
							(mid -0.402042 -0.402042)
							(end -0.4318 -0.3302)
						)
						(arc
							(start -0.4318 0.3302)
							(mid -0.402042 0.402042)
							(end -0.3302 0.4318)
						)
						(arc
							(start 0.3302 0.4318)
							(mid 0.402042 0.402042)
							(end 0.4318 0.3302)
						)
						(arc
							(start 0.4318 -0.3302)
							(mid 0.402042 -0.402042)
							(end 0.3302 -0.4318)
						)
					)
					(width 0)
					(fill yes)
				)
			)
		)
		(pad "2" smd custom
			(at 0 0.762 90)
			(size 0.2159 0.2159)
			(layers "F.Cu" "F.Mask" "F.Paste")
			(net "GB_VDDA")
			(options
				(clearance outline)
				(anchor circle)
			)
			(primitives
				(gr_poly
					(pts
						(arc
							(start -0.3302 -0.4318)
							(mid -0.402042 -0.402042)
							(end -0.4318 -0.3302)
						)
						(arc
							(start -0.4318 0.3302)
							(mid -0.402042 0.402042)
							(end -0.3302 0.4318)
						)
						(arc
							(start 0.3302 0.4318)
							(mid 0.402042 0.402042)
							(end 0.4318 0.3302)
						)
						(arc
							(start 0.4318 -0.3302)
							(mid 0.402042 -0.402042)
							(end 0.3302 -0.4318)
						)
					)
					(width 0)
					(fill yes)
				)
			)
		)
	)
	(footprint ""
		(layer "F.Cu")
		(at 72.4916 -81.0514 180)
		(property "Reference" "R573"
			(at 0 0 180)
			(layer "F.SilkS")
			(hide yes)
			(effects
				(font
					(size 1.27 1.27)
				)
			)
		)
		(property "Value" "0R2J-2-GP"
			(at 0.064008 -3.993896 180)
			(unlocked yes)
			(layer "F.Fab")
			(hide yes)
			(effects
				(font
					(size 1.016 1.016)
					(thickness 0.1524)
				)
			)
		)
		(property "Device Type" "R402H16"
			(at 0.064008 -5.517896 180)
			(unlocked yes)
			(layer "F.Fab")
			(hide yes)
			(effects
				(font
					(size 1.016 1.016)
					(thickness 0.1524)
				)
			)
		)
		(duplicate_pad_numbers_are_jumpers no)
		(fp_line
			(start 0.508 -0.9398)
			(end -0.508 -0.9398)
			(stroke
				(width 0.1524)
				(type default)
			)
			(layer "F.SilkS")
		)
		(fp_line
			(start -0.508 -0.9398)
			(end -0.508 0.9398)
			(stroke
				(width 0.1524)
				(type default)
			)
			(layer "F.SilkS")
		)
		(fp_rect
			(start -0.508 0.9398)
			(end 0.508 -0.9398)
			(stroke
				(width 0)
				(type default)
			)
			(fill no)
			(layer "F.CrtYd")
		)
		(fp_rect
			(start -0.508 0.9398)
			(end 0.508 -0.9398)
			(stroke
				(width 0)
				(type default)
			)
			(fill no)
			(layer "F.Fab")
		)
		(pad "1" smd custom
			(at 0 -0.4445 180)
			(size 0.1397 0.1397)
			(layers "F.Cu" "F.Mask" "F.Paste")
			(net "PCIE_COMP_TO_SCC_RST_R_0")
			(options
				(clearance outline)
				(anchor circle)
			)
			(primitives
				(gr_poly
					(pts
						(arc
							(start -0.1778 -0.2794)
							(mid -0.249642 -0.249642)
							(end -0.2794 -0.1778)
						)
						(arc
							(start -0.2794 0.1778)
							(mid -0.249642 0.249642)
							(end -0.1778 0.2794)
						)
						(arc
							(start 0.1778 0.2794)
							(mid 0.249642 0.249642)
							(end 0.2794 0.1778)
						)
						(arc
							(start 0.2794 -0.1778)
							(mid 0.249642 -0.249642)
							(end 0.1778 -0.2794)
						)
					)
					(width 0)
					(fill yes)
				)
			)
		)
		(pad "2" smd custom
			(at 0 0.4445 180)
			(size 0.1397 0.1397)
			(layers "F.Cu" "F.Mask" "F.Paste")
			(net "PCIE_COMP_TO_SCC_RST_0")
			(options
				(clearance outline)
				(anchor circle)
			)
			(primitives
				(gr_poly
					(pts
						(arc
							(start -0.1778 -0.2794)
							(mid -0.249642 -0.249642)
							(end -0.2794 -0.1778)
						)
						(arc
							(start -0.2794 0.1778)
							(mid -0.249642 0.249642)
							(end -0.1778 0.2794)
						)
						(arc
							(start 0.1778 0.2794)
							(mid 0.249642 0.249642)
							(end 0.2794 0.1778)
						)
						(arc
							(start 0.2794 -0.1778)
							(mid 0.249642 -0.249642)
							(end 0.1778 -0.2794)
						)
					)
					(width 0)
					(fill yes)
				)
			)
		)
	)
	(footprint ""
		(layer "F.Cu")
		(at 20.9804 -57.277 180)
		(property "Reference" "C653"
			(at 0 0 180)
			(layer "F.SilkS")
			(hide yes)
			(effects
				(font
					(size 1.27 1.27)
				)
			)
		)
		(property "Value" "SCD1U50V3KX-GP"
			(at 0 -2.8194 180)
			(unlocked yes)
			(layer "F.Fab")
			(hide yes)
			(effects
				(font
					(size 1.016 1.016)
					(thickness 0.1524)
				)
			)
		)
		(property "Device Type" "C603H36"
			(at 0 -4.3434 180)
			(unlocked yes)
			(layer "F.Fab")
			(hide yes)
			(effects
				(font
					(size 1.016 1.016)
					(thickness 0.1524)
				)
			)
		)
		(duplicate_pad_numbers_are_jumpers no)
		(fp_line
			(start 0.508 0)
			(end -0.508 0)
			(stroke
				(width 0.2032)
				(type default)
			)
			(layer "F.SilkS")
		)
		(fp_rect
			(start -0.5842 1.3335)
			(end 0.5842 -1.3335)
			(stroke
				(width 0)
				(type default)
			)
			(fill no)
			(layer "F.CrtYd")
		)
		(fp_rect
			(start -0.5842 1.3335)
			(end 0.5842 -1.3335)
			(stroke
				(width 0)
				(type default)
			)
			(fill no)
			(layer "F.Fab")
		)
		(pad "1" smd custom
			(at 0 -0.762 180)
			(size 0.2159 0.2159)
			(layers "F.Cu" "F.Mask" "F.Paste")
			(net "MB0_ISTART_R")
			(options
				(clearance outline)
				(anchor circle)
			)
			(primitives
				(gr_poly
					(pts
						(arc
							(start -0.3302 -0.4318)
							(mid -0.402042 -0.402042)
							(end -0.4318 -0.3302)
						)
						(arc
							(start -0.4318 0.3302)
							(mid -0.402042 0.402042)
							(end -0.3302 0.4318)
						)
						(arc
							(start 0.3302 0.4318)
							(mid 0.402042 0.402042)
							(end 0.4318 0.3302)
						)
						(arc
							(start 0.4318 -0.3302)
							(mid 0.402042 -0.402042)
							(end 0.3302 -0.4318)
						)
					)
					(width 0)
					(fill yes)
				)
			)
		)
		(pad "2" smd custom
			(at 0 0.762 180)
			(size 0.2159 0.2159)
			(layers "F.Cu" "F.Mask" "F.Paste")
			(net "AGND_CURRENT_MON")
			(options
				(clearance outline)
				(anchor circle)
			)
			(primitives
				(gr_poly
					(pts
						(arc
							(start -0.3302 -0.4318)
							(mid -0.402042 -0.402042)
							(end -0.4318 -0.3302)
						)
						(arc
							(start -0.4318 0.3302)
							(mid -0.402042 0.402042)
							(end -0.3302 0.4318)
						)
						(arc
							(start 0.3302 0.4318)
							(mid 0.402042 0.402042)
							(end 0.4318 0.3302)
						)
						(arc
							(start 0.4318 -0.3302)
							(mid 0.402042 -0.402042)
							(end 0.3302 -0.4318)
						)
					)
					(width 0)
					(fill yes)
				)
			)
		)
	)
	(footprint ""
		(layer "F.Cu")
		(at 15.00632 -101.44506 -90)
		(property "Reference" "C738"
			(at 0 0 270)
			(layer "F.SilkS")
			(hide yes)
			(effects
				(font
					(size 1.27 1.27)
				)
			)
		)
		(property "Value" "SCD1U16V2KX-3GP"
			(at 1.1811 -2.7051 270)
			(unlocked yes)
			(layer "F.Fab")
			(hide yes)
			(effects
				(font
					(size 1.016 1.016)
					(thickness 0.1524)
				)
			)
		)
		(property "Device Type" "C402H22"
			(at 1.1811 -4.2291 270)
			(unlocked yes)
			(layer "F.Fab")
			(hide yes)
			(effects
				(font
					(size 1.016 1.016)
					(thickness 0.1524)
				)
			)
		)
		(duplicate_pad_numbers_are_jumpers no)
		(fp_rect
			(start -0.4318 0.9525)
			(end 0.4318 -0.9525)
			(stroke
				(width 0)
				(type default)
			)
			(fill no)
			(layer "F.CrtYd")
		)
		(fp_rect
			(start -0.4318 0.9525)
			(end 0.4318 -0.9525)
			(stroke
				(width 0)
				(type default)
			)
			(fill no)
			(layer "F.Fab")
		)
		(pad "1" smd custom
			(at 0 -0.4445 270)
			(size 0.1524 0.1524)
			(layers "F.Cu" "F.Mask" "F.Paste")
			(net "U119_EN")
			(options
				(clearance outline)
				(anchor circle)
			)
			(primitives
				(gr_poly
					(pts
						(arc
							(start 0.3048 -0.2032)
							(mid 0.275042 -0.275042)
							(end 0.2032 -0.3048)
						)
						(arc
							(start -0.2032 -0.3048)
							(mid -0.275042 -0.275042)
							(end -0.3048 -0.2032)
						)
						(arc
							(start -0.3048 0.2032)
							(mid -0.275042 0.275042)
							(end -0.2032 0.3048)
						)
						(arc
							(start 0.2032 0.3048)
							(mid 0.275042 0.275042)
							(end 0.3048 0.2032)
						)
					)
					(width 0)
					(fill yes)
				)
			)
		)
		(pad "2" smd custom
			(at 0 0.4445 270)
			(size 0.1524 0.1524)
			(layers "F.Cu" "F.Mask" "F.Paste")
			(net "GND")
			(options
				(clearance outline)
				(anchor circle)
			)
			(primitives
				(gr_poly
					(pts
						(arc
							(start 0.3048 -0.2032)
							(mid 0.275042 -0.275042)
							(end 0.2032 -0.3048)
						)
						(arc
							(start -0.2032 -0.3048)
							(mid -0.275042 -0.275042)
							(end -0.3048 -0.2032)
						)
						(arc
							(start -0.3048 0.2032)
							(mid -0.275042 0.275042)
							(end -0.2032 0.3048)
						)
						(arc
							(start 0.2032 0.3048)
							(mid 0.275042 0.275042)
							(end 0.3048 0.2032)
						)
					)
					(width 0)
					(fill yes)
				)
			)
		)
	)
	(footprint ""
		(layer "F.Cu")
		(at 43.7642 -49.7332 180)
		(property "Reference" "C670"
			(at 0 0 180)
			(layer "F.SilkS")
			(hide yes)
			(effects
				(font
					(size 1.27 1.27)
				)
			)
		)
		(property "Value" "SC10U16V5KX-7-GP-U"
			(at -0.0762 -6.1214 180)
			(unlocked yes)
			(layer "F.Fab")
			(hide yes)
			(effects
				(font
					(size 1.016 1.016)
					(thickness 0.1524)
				)
			)
		)
		(property "Device Type" "C805H58"
			(at -0.0762 -8.1534 180)
			(unlocked yes)
			(layer "F.Fab")
			(hide yes)
			(effects
				(font
					(size 1.016 1.016)
					(thickness 0.1524)
				)
			)
		)
		(duplicate_pad_numbers_are_jumpers no)
		(fp_line
			(start 0.635 0)
			(end -0.635 0)
			(stroke
				(width 0.508)
				(type default)
			)
			(layer "F.SilkS")
		)
		(fp_rect
			(start -0.9652 1.778)
			(end 0.9652 -1.778)
			(stroke
				(width 0)
				(type default)
			)
			(fill no)
			(layer "F.CrtYd")
		)
		(fp_poly
			(pts
				(xy -0.9652 -1.778) (xy 0.9652 -1.778) (xy 0.9652 1.778) (xy -0.9652 1.778)
			)
			(stroke
				(width 0)
				(type default)
			)
			(fill no)
			(layer "F.Fab")
		)
		(pad "1" smd rect
			(at 0 -0.9652 180)
			(size 1.397 1.143)
			(layers "F.Cu" "F.Mask" "F.Paste")
			(net "P12V_STBY_VIN_Q7")
		)
		(pad "2" smd rect
			(at 0 0.9652 180)
			(size 1.397 1.143)
			(layers "F.Cu" "F.Mask" "F.Paste")
			(net "GND")
		)
	)
	(footprint ""
		(layer "F.Cu")
		(at 55.88 -122.936 -90)
		(property "Reference" "C705"
			(at 0 0 270)
			(layer "F.SilkS")
			(hide yes)
			(effects
				(font
					(size 1.27 1.27)
				)
			)
		)
		(property "Value" "SCD1U16V2KX-3GP"
			(at 1.1811 -2.7051 270)
			(unlocked yes)
			(layer "F.Fab")
			(hide yes)
			(effects
				(font
					(size 1.016 1.016)
					(thickness 0.1524)
				)
			)
		)
		(property "Device Type" "C402H22"
			(at 1.1811 -4.2291 270)
			(unlocked yes)
			(layer "F.Fab")
			(hide yes)
			(effects
				(font
					(size 1.016 1.016)
					(thickness 0.1524)
				)
			)
		)
		(duplicate_pad_numbers_are_jumpers no)
		(fp_rect
			(start -0.4318 0.9525)
			(end 0.4318 -0.9525)
			(stroke
				(width 0)
				(type default)
			)
			(fill no)
			(layer "F.CrtYd")
		)
		(fp_rect
			(start -0.4318 0.9525)
			(end 0.4318 -0.9525)
			(stroke
				(width 0)
				(type default)
			)
			(fill no)
			(layer "F.Fab")
		)
		(pad "1" smd custom
			(at 0 -0.4445 270)
			(size 0.1524 0.1524)
			(layers "F.Cu" "F.Mask" "F.Paste")
			(net "P3V3_OUT")
			(options
				(clearance outline)
				(anchor circle)
			)
			(primitives
				(gr_poly
					(pts
						(arc
							(start 0.3048 -0.2032)
							(mid 0.275042 -0.275042)
							(end 0.2032 -0.3048)
						)
						(arc
							(start -0.2032 -0.3048)
							(mid -0.275042 -0.275042)
							(end -0.3048 -0.2032)
						)
						(arc
							(start -0.3048 0.2032)
							(mid -0.275042 0.275042)
							(end -0.2032 0.3048)
						)
						(arc
							(start 0.2032 0.3048)
							(mid 0.275042 0.275042)
							(end 0.3048 0.2032)
						)
					)
					(width 0)
					(fill yes)
				)
			)
		)
		(pad "2" smd custom
			(at 0 0.4445 270)
			(size 0.1524 0.1524)
			(layers "F.Cu" "F.Mask" "F.Paste")
			(net "GND")
			(options
				(clearance outline)
				(anchor circle)
			)
			(primitives
				(gr_poly
					(pts
						(arc
							(start 0.3048 -0.2032)
							(mid 0.275042 -0.275042)
							(end 0.2032 -0.3048)
						)
						(arc
							(start -0.2032 -0.3048)
							(mid -0.275042 -0.275042)
							(end -0.3048 -0.2032)
						)
						(arc
							(start -0.3048 0.2032)
							(mid -0.275042 0.275042)
							(end -0.2032 0.3048)
						)
						(arc
							(start 0.2032 0.3048)
							(mid 0.275042 0.275042)
							(end 0.3048 0.2032)
						)
					)
					(width 0)
					(fill yes)
				)
			)
		)
	)
	(footprint ""
		(layer "F.Cu")
		(at 86.000082 -3.800094)
		(property "Reference" "CN2"
			(at 0 0 0)
			(layer "F.SilkS")
			(hide yes)
			(effects
				(font
					(size 1.27 1.27)
				)
			)
		)
		(property "Value" "AMP-CONN342-10R-3-GP"
			(at -12.8905 -12.5222 0)
			(unlocked yes)
			(layer "F.Fab")
			(hide yes)
			(effects
				(font
					(size 1.016 1.016)
					(thickness 0.1524)
				)
			)
		)
		(property "Device Type" "PREFIT-342P-648260H400"
			(at -12.8905 -14.0462 0)
			(unlocked yes)
			(layer "F.Fab")
			(hide yes)
			(effects
				(font
					(size 1.016 1.016)
					(thickness 0.1524)
				)
			)
		)
		(duplicate_pad_numbers_are_jumpers no)
		(fp_line
			(start -0.9398 -12.3444)
			(end -0.9398 3.800094)
			(stroke
				(width 0.1524)
				(type default)
			)
			(layer "F.SilkS")
		)
		(fp_line
			(start -0.9398 3.800094)
			(end 64.3382 3.800094)
			(stroke
				(width 0.1524)
				(type default)
			)
			(layer "F.SilkS")
		)
		(fp_line
			(start 64.3382 -12.3444)
			(end -0.9398 -12.3444)
			(stroke
				(width 0.1524)
				(type default)
			)
			(layer "F.SilkS")
		)
		(fp_line
			(start 64.3382 3.800094)
			(end 64.3382 -12.3444)
			(stroke
				(width 0.1524)
				(type default)
			)
			(layer "F.SilkS")
		)
		(fp_poly
			(pts
				(xy -0.9398 -10.3632) (xy -0.9398 -12.3444) (xy 26.797 -12.3444) (xy 26.797 -10.3632)
			)
			(stroke
				(width 0)
				(type default)
			)
			(fill yes)
			(layer "F.SilkS")
		)
		(fp_poly
			(pts
				(xy 37.6682 -10.3632) (xy 37.6682 -12.3444) (xy 64.3382 -12.3444) (xy 64.3382 -10.3632)
			)
			(stroke
				(width 0)
				(type default)
			)
			(fill yes)
			(layer "F.SilkS")
		)
		(fp_poly
			(pts
				(arc
					(start 0.259334 3.3782)
					(mid 0.005334 3.6322)
					(end -0.248666 3.3782)
				)
				(arc
					(start -0.248666 3.1242)
					(mid 0.005334 2.8702)
					(end 0.259334 3.1242)
				)
			)
			(stroke
				(width 0)
				(type default)
			)
			(fill yes)
			(layer "F.SilkS")
		)
		(fp_poly
			(pts
				(arc
					(start 2.059178 3.3782)
					(mid 1.805178 3.6322)
					(end 1.551178 3.3782)
				)
				(arc
					(start 1.551178 3.1242)
					(mid 1.805178 2.8702)
					(end 2.059178 3.1242)
				)
			)
			(stroke
				(width 0)
				(type default)
			)
			(fill yes)
			(layer "F.SilkS")
		)
		(fp_poly
			(pts
				(arc
					(start 3.859022 3.3782)
					(mid 3.605022 3.6322)
					(end 3.351022 3.3782)
				)
				(arc
					(start 3.351022 3.1242)
					(mid 3.605022 2.8702)
					(end 3.859022 3.1242)
				)
			)
			(stroke
				(width 0)
				(type default)
			)
			(fill yes)
			(layer "F.SilkS")
		)
		(fp_poly
			(pts
				(arc
					(start 5.658866 3.3782)
					(mid 5.404866 3.6322)
					(end 5.150866 3.3782)
				)
				(arc
					(start 5.150866 3.1242)
					(mid 5.404866 2.8702)
					(end 5.658866 3.1242)
				)
			)
			(stroke
				(width 0)
				(type default)
			)
			(fill yes)
			(layer "F.SilkS")
		)
		(fp_poly
			(pts
				(arc
					(start 7.45871 3.3782)
					(mid 7.20471 3.6322)
					(end 6.95071 3.3782)
				)
				(arc
					(start 6.95071 3.1242)
					(mid 7.20471 2.8702)
					(end 7.45871 3.1242)
				)
			)
			(stroke
				(width 0)
				(type default)
			)
			(fill yes)
			(layer "F.SilkS")
		)
		(fp_poly
			(pts
				(arc
					(start 9.258554 3.3782)
					(mid 9.004554 3.6322)
					(end 8.750554 3.3782)
				)
				(arc
					(start 8.750554 3.1242)
					(mid 9.004554 2.8702)
					(end 9.258554 3.1242)
				)
			)
			(stroke
				(width 0)
				(type default)
			)
			(fill yes)
			(layer "F.SilkS")
		)
		(fp_poly
			(pts
				(arc
					(start 11.058398 3.3782)
					(mid 10.804398 3.6322)
					(end 10.550398 3.3782)
				)
				(arc
					(start 10.550398 3.1242)
					(mid 10.804398 2.8702)
					(end 11.058398 3.1242)
				)
			)
			(stroke
				(width 0)
				(type default)
			)
			(fill yes)
			(layer "F.SilkS")
		)
		(fp_poly
			(pts
				(arc
					(start 12.858242 3.3782)
					(mid 12.604242 3.6322)
					(end 12.350242 3.3782)
				)
				(arc
					(start 12.350242 3.1242)
					(mid 12.604242 2.8702)
					(end 12.858242 3.1242)
				)
			)
			(stroke
				(width 0)
				(type default)
			)
			(fill yes)
			(layer "F.SilkS")
		)
		(fp_poly
			(pts
				(arc
					(start 14.658086 3.3782)
					(mid 14.404086 3.6322)
					(end 14.150086 3.3782)
				)
				(arc
					(start 14.150086 3.1242)
					(mid 14.404086 2.8702)
					(end 14.658086 3.1242)
				)
			)
			(stroke
				(width 0)
				(type default)
			)
			(fill yes)
			(layer "F.SilkS")
		)
		(fp_poly
			(pts
				(arc
					(start 16.45793 3.3782)
					(mid 16.20393 3.6322)
					(end 15.94993 3.3782)
				)
				(arc
					(start 15.94993 3.1242)
					(mid 16.20393 2.8702)
					(end 16.45793 3.1242)
				)
			)
			(stroke
				(width 0)
				(type default)
			)
			(fill yes)
			(layer "F.SilkS")
		)
		(fp_poly
			(pts
				(arc
					(start 18.257774 3.3782)
					(mid 18.003774 3.6322)
					(end 17.749774 3.3782)
				)
				(arc
					(start 17.749774 3.1242)
					(mid 18.003774 2.8702)
					(end 18.257774 3.1242)
				)
			)
			(stroke
				(width 0)
				(type default)
			)
			(fill yes)
			(layer "F.SilkS")
		)
		(fp_poly
			(pts
				(arc
					(start 20.057618 3.3782)
					(mid 19.803618 3.6322)
					(end 19.549618 3.3782)
				)
				(arc
					(start 19.549618 3.1242)
					(mid 19.803618 2.8702)
					(end 20.057618 3.1242)
				)
			)
			(stroke
				(width 0)
				(type default)
			)
			(fill yes)
			(layer "F.SilkS")
		)
		(fp_poly
			(pts
				(arc
					(start 21.857462 3.3782)
					(mid 21.603462 3.6322)
					(end 21.349462 3.3782)
				)
				(arc
					(start 21.349462 3.1242)
					(mid 21.603462 2.8702)
					(end 21.857462 3.1242)
				)
			)
			(stroke
				(width 0)
				(type default)
			)
			(fill yes)
			(layer "F.SilkS")
		)
		(fp_poly
			(pts
				(arc
					(start 23.657306 3.3782)
					(mid 23.403306 3.6322)
					(end 23.149306 3.3782)
				)
				(arc
					(start 23.149306 3.1242)
					(mid 23.403306 2.8702)
					(end 23.657306 3.1242)
				)
			)
			(stroke
				(width 0)
				(type default)
			)
			(fill yes)
			(layer "F.SilkS")
		)
		(fp_poly
			(pts
				(arc
					(start 25.45715 3.3782)
					(mid 25.20315 3.6322)
					(end 24.94915 3.3782)
				)
				(arc
					(start 24.94915 3.1242)
					(mid 25.20315 2.8702)
					(end 25.45715 3.1242)
				)
			)
			(stroke
				(width 0)
				(type default)
			)
			(fill yes)
			(layer "F.SilkS")
		)
		(fp_poly
			(pts
				(arc
					(start 27.256994 3.3782)
					(mid 27.002994 3.6322)
					(end 26.748994 3.3782)
				)
				(arc
					(start 26.748994 3.1242)
					(mid 27.002994 2.8702)
					(end 27.256994 3.1242)
				)
			)
			(stroke
				(width 0)
				(type default)
			)
			(fill yes)
			(layer "F.SilkS")
		)
		(fp_poly
			(pts
				(arc
					(start 29.056838 3.3782)
					(mid 28.802838 3.6322)
					(end 28.548838 3.3782)
				)
				(arc
					(start 28.548838 3.1242)
					(mid 28.802838 2.8702)
					(end 29.056838 3.1242)
				)
			)
			(stroke
				(width 0)
				(type default)
			)
			(fill yes)
			(layer "F.SilkS")
		)
		(fp_poly
			(pts
				(arc
					(start 30.856682 3.3782)
					(mid 30.602682 3.6322)
					(end 30.348682 3.3782)
				)
				(arc
					(start 30.348682 3.1242)
					(mid 30.602682 2.8702)
					(end 30.856682 3.1242)
				)
			)
			(stroke
				(width 0)
				(type default)
			)
			(fill yes)
			(layer "F.SilkS")
		)
		(fp_poly
			(pts
				(arc
					(start 32.656526 3.3782)
					(mid 32.402526 3.6322)
					(end 32.148526 3.3782)
				)
				(arc
					(start 32.148526 3.1242)
					(mid 32.402526 2.8702)
					(end 32.656526 3.1242)
				)
			)
			(stroke
				(width 0)
				(type default)
			)
			(fill yes)
			(layer "F.SilkS")
		)
		(fp_poly
			(pts
				(arc
					(start 34.45637 3.3782)
					(mid 34.20237 3.6322)
					(end 33.94837 3.3782)
				)
				(arc
					(start 33.94837 3.1242)
					(mid 34.20237 2.8702)
					(end 34.45637 3.1242)
				)
			)
			(stroke
				(width 0)
				(type default)
			)
			(fill yes)
			(layer "F.SilkS")
		)
		(fp_poly
			(pts
				(arc
					(start 36.256214 3.3782)
					(mid 36.002214 3.6322)
					(end 35.748214 3.3782)
				)
				(arc
					(start 35.748214 3.1242)
					(mid 36.002214 2.8702)
					(end 36.256214 3.1242)
				)
			)
			(stroke
				(width 0)
				(type default)
			)
			(fill yes)
			(layer "F.SilkS")
		)
		(fp_poly
			(pts
				(arc
					(start 38.056058 3.3782)
					(mid 37.802058 3.6322)
					(end 37.548058 3.3782)
				)
				(arc
					(start 37.548058 3.1242)
					(mid 37.802058 2.8702)
					(end 38.056058 3.1242)
				)
			)
			(stroke
				(width 0)
				(type default)
			)
			(fill yes)
			(layer "F.SilkS")
		)
		(fp_poly
			(pts
				(arc
					(start 39.855902 3.3782)
					(mid 39.601902 3.6322)
					(end 39.347902 3.3782)
				)
				(arc
					(start 39.347902 3.1242)
					(mid 39.601902 2.8702)
					(end 39.855902 3.1242)
				)
			)
			(stroke
				(width 0)
				(type default)
			)
			(fill yes)
			(layer "F.SilkS")
		)
		(fp_poly
			(pts
				(arc
					(start 41.655746 3.3782)
					(mid 41.401746 3.6322)
					(end 41.147746 3.3782)
				)
				(arc
					(start 41.147746 3.1242)
					(mid 41.401746 2.8702)
					(end 41.655746 3.1242)
				)
			)
			(stroke
				(width 0)
				(type default)
			)
			(fill yes)
			(layer "F.SilkS")
		)
		(fp_poly
			(pts
				(arc
					(start 43.45559 3.3782)
					(mid 43.20159 3.6322)
					(end 42.94759 3.3782)
				)
				(arc
					(start 42.94759 3.1242)
					(mid 43.20159 2.8702)
					(end 43.45559 3.1242)
				)
			)
			(stroke
				(width 0)
				(type default)
			)
			(fill yes)
			(layer "F.SilkS")
		)
		(fp_poly
			(pts
				(arc
					(start 45.255434 3.3782)
					(mid 45.001434 3.6322)
					(end 44.747434 3.3782)
				)
				(arc
					(start 44.747434 3.1242)
					(mid 45.001434 2.8702)
					(end 45.255434 3.1242)
				)
			)
			(stroke
				(width 0)
				(type default)
			)
			(fill yes)
			(layer "F.SilkS")
		)
		(fp_poly
			(pts
				(arc
					(start 47.055278 3.3782)
					(mid 46.801278 3.6322)
					(end 46.547278 3.3782)
				)
				(arc
					(start 46.547278 3.1242)
					(mid 46.801278 2.8702)
					(end 47.055278 3.1242)
				)
			)
			(stroke
				(width 0)
				(type default)
			)
			(fill yes)
			(layer "F.SilkS")
		)
		(fp_poly
			(pts
				(arc
					(start 48.855122 3.3782)
					(mid 48.601122 3.6322)
					(end 48.347122 3.3782)
				)
				(arc
					(start 48.347122 3.1242)
					(mid 48.601122 2.8702)
					(end 48.855122 3.1242)
				)
			)
			(stroke
				(width 0)
				(type default)
			)
			(fill yes)
			(layer "F.SilkS")
		)
		(fp_poly
			(pts
				(arc
					(start 50.654966 3.3782)
					(mid 50.400966 3.6322)
					(end 50.146966 3.3782)
				)
				(arc
					(start 50.146966 3.1242)
					(mid 50.400966 2.8702)
					(end 50.654966 3.1242)
				)
			)
			(stroke
				(width 0)
				(type default)
			)
			(fill yes)
			(layer "F.SilkS")
		)
		(fp_poly
			(pts
				(arc
					(start 52.45481 3.3782)
					(mid 52.20081 3.6322)
					(end 51.94681 3.3782)
				)
				(arc
					(start 51.94681 3.1242)
					(mid 52.20081 2.8702)
					(end 52.45481 3.1242)
				)
			)
			(stroke
				(width 0)
				(type default)
			)
			(fill yes)
			(layer "F.SilkS")
		)
		(fp_poly
			(pts
				(arc
					(start 54.254654 3.3782)
					(mid 54.000654 3.6322)
					(end 53.746654 3.3782)
				)
				(arc
					(start 53.746654 3.1242)
					(mid 54.000654 2.8702)
					(end 54.254654 3.1242)
				)
			)
			(stroke
				(width 0)
				(type default)
			)
			(fill yes)
			(layer "F.SilkS")
		)
		(fp_poly
			(pts
				(arc
					(start 56.054498 3.3782)
					(mid 55.800498 3.6322)
					(end 55.546498 3.3782)
				)
				(arc
					(start 55.546498 3.1242)
					(mid 55.800498 2.8702)
					(end 56.054498 3.1242)
				)
			)
			(stroke
				(width 0)
				(type default)
			)
			(fill yes)
			(layer "F.SilkS")
		)
		(fp_poly
			(pts
				(arc
					(start 57.854342 3.3782)
					(mid 57.600342 3.6322)
					(end 57.346342 3.3782)
				)
				(arc
					(start 57.346342 3.1242)
					(mid 57.600342 2.8702)
					(end 57.854342 3.1242)
				)
			)
			(stroke
				(width 0)
				(type default)
			)
			(fill yes)
			(layer "F.SilkS")
		)
		(fp_poly
			(pts
				(arc
					(start 59.654186 3.3782)
					(mid 59.400186 3.6322)
					(end 59.146186 3.3782)
				)
				(arc
					(start 59.146186 3.1242)
					(mid 59.400186 2.8702)
					(end 59.654186 3.1242)
				)
			)
			(stroke
				(width 0)
				(type default)
			)
			(fill yes)
			(layer "F.SilkS")
		)
		(fp_poly
			(pts
				(arc
					(start 61.45403 3.3782)
					(mid 61.20003 3.6322)
					(end 60.94603 3.3782)
				)
				(arc
					(start 60.94603 3.1242)
					(mid 61.20003 2.8702)
					(end 61.45403 3.1242)
				)
			)
			(stroke
				(width 0)
				(type default)
			)
			(fill yes)
			(layer "F.SilkS")
		)
		(fp_poly
			(pts
				(arc
					(start 63.253874 3.3782)
					(mid 62.999874 3.6322)
					(end 62.745874 3.3782)
				)
				(arc
					(start 62.745874 3.1242)
					(mid 62.999874 2.8702)
					(end 63.253874 3.1242)
				)
			)
			(stroke
				(width 0)
				(type default)
			)
			(fill yes)
			(layer "F.SilkS")
		)
		(fp_rect
			(start -5.3848 7.6962)
			(end 68.3768 -15.0876)
			(stroke
				(width 0)
				(type default)
			)
			(fill no)
			(layer "B.CrtYd")
		)
		(fp_rect
			(start -0.6858 13.8938)
			(end 64.0842 -12.0904)
			(stroke
				(width 0)
				(type default)
			)
			(fill no)
			(layer "F.CrtYd")
		)
		(fp_poly
			(pts
				(xy -5.6896 18.8976) (xy -5.6896 -17.0942) (xy 69.088 -17.0942) (xy 69.088 0) (xy 64.5922 0) (xy 64.5922 -12.5984)
				(xy -1.1938 -12.5984) (xy -1.1938 14.4018) (xy 64.5922 14.4018) (xy 64.5922 0.0127) (xy 69.088 0.0127)
				(xy 69.088 18.8976)
			)
			(stroke
				(width 0)
				(type default)
			)
			(fill no)
			(layer "F.CrtYd")
		)
		(fp_poly
			(pts
				(xy -1.1938 14.4018) (xy -1.1938 -12.5984) (xy 64.5922 -12.5984) (xy 64.5922 0) (xy 64.0842 0) (xy 64.0842 -12.0904)
				(xy -0.6858 -12.0904) (xy -0.6858 13.8938) (xy 64.0842 13.8938) (xy 64.0842 0.0127) (xy 64.5922 0.0127)
				(xy 64.5922 14.4018)
			)
			(stroke
				(width 0)
				(type default)
			)
			(fill no)
			(layer "F.CrtYd")
		)
		(fp_rect
			(start -10.3886 12.7)
			(end 73.3806 -20.0914)
			(stroke
				(width 0)
				(type default)
			)
			(fill no)
			(layer "B.Fab")
		)
		(fp_rect
			(start -5.3848 7.6962)
			(end 68.3768 -15.0876)
			(stroke
				(width 0)
				(type default)
			)
			(fill no)
			(layer "B.Fab")
		)
		(fp_rect
			(start -10.6934 23.9014)
			(end 74.0918 -22.098)
			(stroke
				(width 0)
				(type default)
			)
			(fill no)
			(layer "F.Fab")
		)
		(fp_rect
			(start -5.6896 18.8976)
			(end 69.088 -17.0942)
			(stroke
				(width 0)
				(type default)
			)
			(fill no)
			(layer "F.Fab")
		)
		(fp_rect
			(start -1.1938 14.4018)
			(end 64.5922 -12.5984)
			(stroke
				(width 0)
				(type default)
			)
			(fill no)
			(layer "F.Fab")
		)
		(fp_text user "Press Fit"
			(at 27.1018 -11.3411 0)
			(unlocked yes)
			(layer "F.SilkS")
			(effects
				(font
					(size 1.016 1.016)
					(thickness 0.1524)
				)
				(justify left)
			)
		)
		(fp_text user "Slit"
			(at 30.172152 5.805678 0)
			(unlocked yes)
			(layer "F.SilkS")
			(effects
				(font
					(size 1.016 1.016)
					(thickness 0.1524)
				)
				(justify left)
			)
		)
		(fp_text user "Can not place BGA,CSP,Wave Solder Component"
			(at 2.4003 11.6586 0)
			(unlocked yes)
			(layer "B.Fab")
			(effects
				(font
					(size 1.016 1.016)
					(thickness 0.1524)
				)
				(justify left)
			)
		)
		(fp_text user "Can not place BGA,CSP,Wave Solder Component"
			(at 3.0099 22.3266 0)
			(unlocked yes)
			(layer "F.Fab")
			(effects
				(font
					(size 1.016 1.016)
					(thickness 0.1524)
				)
				(justify left)
			)
		)
		(fp_text user "High Limit 2mm"
			(at 26.0223 16.9291 0)
			(unlocked yes)
			(layer "F.Fab")
			(effects
				(font
					(size 1.016 1.016)
					(thickness 0.1524)
				)
				(justify left)
			)
		)
		(pad "A1" thru_hole circle
			(at 0 0)
			(size 0.762 0.762)
			(drill 0.359918)
			(layers "*.Cu" "*.Mask")
			(remove_unused_layers no)
			(net "PHY_DPB_TO_SCC_12_DN")
			(clearance 0.1651)
			(thermal_gap 0.1651)
		)
		(pad "A2" thru_hole circle
			(at 1.800098 1.199896)
			(size 0.762 0.762)
			(drill 0.359918)
			(layers "*.Cu" "*.Mask")
			(remove_unused_layers no)
			(net "PHY_DPB_TO_SCC_13_DN")
			(clearance 0.1651)
			(thermal_gap 0.1651)
		)
		(pad "A3" thru_hole circle
			(at 3.599942 0)
			(size 0.762 0.762)
			(drill 0.359918)
			(layers "*.Cu" "*.Mask")
			(remove_unused_layers no)
			(net "PHY_DPB_TO_SCC_14_DN")
			(clearance 0.1651)
			(thermal_gap 0.1651)
		)
		(pad "A4" thru_hole circle
			(at 5.40004 1.199896)
			(size 0.762 0.762)
			(drill 0.359918)
			(layers "*.Cu" "*.Mask")
			(remove_unused_layers no)
			(net "PHY_DPB_TO_SCC_15_DN")
			(clearance 0.1651)
			(thermal_gap 0.1651)
		)
		(pad "A5" thru_hole circle
			(at 7.199884 0)
			(size 0.762 0.762)
			(drill 0.359918)
			(layers "*.Cu" "*.Mask")
			(remove_unused_layers no)
			(net "PHY_DPB_TO_SCC_16_DN")
			(clearance 0.1651)
			(thermal_gap 0.1651)
		)
		(pad "A6" thru_hole circle
			(at 8.999982 1.199896)
			(size 0.762 0.762)
			(drill 0.359918)
			(layers "*.Cu" "*.Mask")
			(remove_unused_layers no)
			(net "PHY_DPB_TO_SCC_17_DN")
			(clearance 0.1651)
			(thermal_gap 0.1651)
		)
		(pad "A7" thru_hole circle
			(at 10.80008 0)
			(size 0.762 0.762)
			(drill 0.359918)
			(layers "*.Cu" "*.Mask")
			(remove_unused_layers no)
			(net "PHY_DPB_TO_SCC_18_DN")
			(clearance 0.1651)
			(thermal_gap 0.1651)
		)
		(pad "A8" thru_hole circle
			(at 12.599924 1.199896)
			(size 0.762 0.762)
			(drill 0.359918)
			(layers "*.Cu" "*.Mask")
			(remove_unused_layers no)
			(net "PHY_DPB_TO_SCC_19_DN")
			(clearance 0.1651)
			(thermal_gap 0.1651)
		)
		(pad "A9" thru_hole circle
			(at 14.400022 0)
			(size 0.762 0.762)
			(drill 0.359918)
			(layers "*.Cu" "*.Mask")
			(remove_unused_layers no)
			(net "PHY_DPB_TO_SCC_20_DN")
			(clearance 0.1651)
			(thermal_gap 0.1651)
		)
		(pad "A10" thru_hole circle
			(at 16.20012 1.199896)
			(size 0.762 0.762)
			(drill 0.359918)
			(layers "*.Cu" "*.Mask")
			(remove_unused_layers no)
			(net "PHY_DPB_TO_SCC_21_DN")
			(clearance 0.1651)
			(thermal_gap 0.1651)
		)
		(pad "A11" thru_hole circle
			(at 17.999964 0)
			(size 0.762 0.762)
			(drill 0.359918)
			(layers "*.Cu" "*.Mask")
			(remove_unused_layers no)
			(net "PHY_DPB_TO_SCC_22_DN")
			(clearance 0.1651)
			(thermal_gap 0.1651)
		)
		(pad "A12" thru_hole circle
			(at 19.800062 1.199896)
			(size 0.762 0.762)
			(drill 0.359918)
			(layers "*.Cu" "*.Mask")
			(remove_unused_layers no)
			(net "PHY_DPB_TO_SCC_23_DN")
			(clearance 0.1651)
			(thermal_gap 0.1651)
		)
		(pad "A13" thru_hole circle
			(at 21.599906 0)
			(size 0.762 0.762)
			(drill 0.359918)
			(layers "*.Cu" "*.Mask")
			(remove_unused_layers no)
			(net "PHY_DPB_TO_SCC_24_DN")
			(clearance 0.1651)
			(thermal_gap 0.1651)
		)
		(pad "A14" thru_hole circle
			(at 23.400004 1.199896)
			(size 0.762 0.762)
			(drill 0.359918)
			(layers "*.Cu" "*.Mask")
			(remove_unused_layers no)
			(net "PHY_DPB_TO_SCC_25_DN")
			(clearance 0.1651)
			(thermal_gap 0.1651)
		)
		(pad "A15" thru_hole circle
			(at 25.200102 0)
			(size 0.762 0.762)
			(drill 0.359918)
			(layers "*.Cu" "*.Mask")
			(remove_unused_layers no)
			(net "PHY_DPB_TO_SCC_26_DN")
			(clearance 0.1651)
			(thermal_gap 0.1651)
		)
		(pad "A16" thru_hole circle
			(at 26.999946 1.199896)
			(size 0.762 0.762)
			(drill 0.359918)
			(layers "*.Cu" "*.Mask")
			(remove_unused_layers no)
			(net "PHY_DPB_TO_SCC_27_DN")
			(clearance 0.1651)
			(thermal_gap 0.1651)
		)
		(pad "A17" thru_hole circle
			(at 28.800044 0)
			(size 0.762 0.762)
			(drill 0.359918)
			(layers "*.Cu" "*.Mask")
			(remove_unused_layers no)
			(net "PHY_DPB_TO_SCC_32_DN")
			(clearance 0.1651)
			(thermal_gap 0.1651)
		)
		(pad "A18" thru_hole circle
			(at 30.599888 1.199896)
			(size 0.762 0.762)
			(drill 0.359918)
			(layers "*.Cu" "*.Mask")
			(remove_unused_layers no)
			(net "PHY_DPB_TO_SCC_33_DN")
			(clearance 0.1651)
			(thermal_gap 0.1651)
		)
		(pad "A19" thru_hole circle
			(at 32.399986 0)
			(size 0.762 0.762)
			(drill 0.359918)
			(layers "*.Cu" "*.Mask")
			(remove_unused_layers no)
			(net "PHY_DPB_TO_SCC_34_DN")
			(clearance 0.1651)
			(thermal_gap 0.1651)
		)
		(pad "A20" thru_hole circle
			(at 34.200084 1.199896)
			(size 0.762 0.762)
			(drill 0.359918)
			(layers "*.Cu" "*.Mask")
			(remove_unused_layers no)
			(net "PHY_DPB_TO_SCC_35_DN")
			(clearance 0.1651)
			(thermal_gap 0.1651)
		)
		(pad "A21" thru_hole circle
			(at 35.999928 0)
			(size 0.762 0.762)
			(drill 0.359918)
			(layers "*.Cu" "*.Mask")
			(remove_unused_layers no)
			(net "PHY_DPB_TO_SCC_36_DN")
			(clearance 0.1651)
			(thermal_gap 0.1651)
		)
		(pad "A22" thru_hole circle
			(at 37.800026 1.199896)
			(size 0.762 0.762)
			(drill 0.359918)
			(layers "*.Cu" "*.Mask")
			(remove_unused_layers no)
			(net "PHY_DPB_TO_SCC_37_DN")
			(clearance 0.1651)
			(thermal_gap 0.1651)
		)
		(pad "A23" thru_hole circle
			(at 39.600124 0)
			(size 0.762 0.762)
			(drill 0.359918)
			(layers "*.Cu" "*.Mask")
			(remove_unused_layers no)
			(net "PHY_DPB_TO_SCC_38_DN")
			(clearance 0.1651)
			(thermal_gap 0.1651)
		)
		(pad "A24" thru_hole circle
			(at 41.399968 1.199896)
			(size 0.762 0.762)
			(drill 0.359918)
			(layers "*.Cu" "*.Mask")
			(remove_unused_layers no)
			(net "PHY_DPB_TO_SCC_39_DN")
			(clearance 0.1651)
			(thermal_gap 0.1651)
		)
		(pad "A25" thru_hole circle
			(at 43.200066 0)
			(size 0.762 0.762)
			(drill 0.359918)
			(layers "*.Cu" "*.Mask")
			(remove_unused_layers no)
			(net "PHY_DPB_TO_SCC_28_DN")
			(clearance 0.1651)
			(thermal_gap 0.1651)
		)
		(pad "A26" thru_hole circle
			(at 44.99991 1.199896)
			(size 0.762 0.762)
			(drill 0.359918)
			(layers "*.Cu" "*.Mask")
			(remove_unused_layers no)
			(net "PHY_DPB_TO_SCC_29_DN")
			(clearance 0.1651)
			(thermal_gap 0.1651)
		)
		(pad "A27" thru_hole circle
			(at 46.800008 0)
			(size 0.762 0.762)
			(drill 0.359918)
			(layers "*.Cu" "*.Mask")
			(remove_unused_layers no)
			(net "PHY_DPB_TO_SCC_30_DN")
			(clearance 0.1651)
			(thermal_gap 0.1651)
		)
		(pad "A28" thru_hole circle
			(at 48.600106 1.199896)
			(size 0.762 0.762)
			(drill 0.359918)
			(layers "*.Cu" "*.Mask")
			(remove_unused_layers no)
			(net "PHY_DPB_TO_SCC_31_DN")
			(clearance 0.1651)
			(thermal_gap 0.1651)
		)
		(pad "A29" thru_hole circle
			(at 50.39995 0)
			(size 0.762 0.762)
			(drill 0.359918)
			(layers "*.Cu" "*.Mask")
			(remove_unused_layers no)
			(net "PHY_DPB_TO_SCC_0_DN")
			(clearance 0.1651)
			(thermal_gap 0.1651)
		)
		(pad "A30" thru_hole circle
			(at 52.200048 1.199896)
			(size 0.762 0.762)
			(drill 0.359918)
			(layers "*.Cu" "*.Mask")
			(remove_unused_layers no)
			(net "PHY_DPB_TO_SCC_1_DN")
			(clearance 0.1651)
			(thermal_gap 0.1651)
		)
		(pad "A31" thru_hole circle
			(at 53.999892 0)
			(size 0.762 0.762)
			(drill 0.359918)
			(layers "*.Cu" "*.Mask")
			(remove_unused_layers no)
			(net "PHY_DPB_TO_SCC_2_DN")
			(clearance 0.1651)
			(thermal_gap 0.1651)
		)
		(pad "A32" thru_hole circle
			(at 55.79999 1.199896)
			(size 0.762 0.762)
			(drill 0.359918)
			(layers "*.Cu" "*.Mask")
			(remove_unused_layers no)
			(net "PHY_DPB_TO_SCC_3_DN")
			(clearance 0.1651)
			(thermal_gap 0.1651)
		)
		(pad "A33" thru_hole circle
			(at 57.600088 0)
			(size 0.762 0.762)
			(drill 0.359918)
			(layers "*.Cu" "*.Mask")
			(remove_unused_layers no)
			(net "PHY_DPB_TO_SCC_4_DN")
			(clearance 0.1651)
			(thermal_gap 0.1651)
		)
		(pad "A34" thru_hole circle
			(at 59.399932 1.199896)
			(size 0.762 0.762)
			(drill 0.359918)
			(layers "*.Cu" "*.Mask")
			(remove_unused_layers no)
			(net "PHY_DPB_TO_SCC_5_DN")
			(clearance 0.1651)
			(thermal_gap 0.1651)
		)
		(pad "A35" thru_hole circle
			(at 61.20003 0)
			(size 0.762 0.762)
			(drill 0.359918)
			(layers "*.Cu" "*.Mask")
			(remove_unused_layers no)
			(net "PHY_DPB_TO_SCC_6_DN")
			(clearance 0.1651)
			(thermal_gap 0.1651)
		)
		(pad "A36" thru_hole circle
			(at 62.999874 1.199896)
			(size 0.762 0.762)
			(drill 0.359918)
			(layers "*.Cu" "*.Mask")
			(remove_unused_layers no)
			(net "PHY_DPB_TO_SCC_7_DN")
			(clearance 0.1651)
			(thermal_gap 0.1651)
		)
		(pad "B1" thru_hole circle
			(at 0 -1.400048)
			(size 0.762 0.762)
			(drill 0.359918)
			(layers "*.Cu" "*.Mask")
			(remove_unused_layers no)
			(net "PHY_DPB_TO_SCC_12_DP")
			(clearance 0.1651)
			(thermal_gap 0.1651)
		)
		(pad "B2" thru_hole circle
			(at 1.800098 -0.199898)
			(size 0.762 0.762)
			(drill 0.359918)
			(layers "*.Cu" "*.Mask")
			(remove_unused_layers no)
			(net "PHY_DPB_TO_SCC_13_DP")
			(clearance 0.1651)
			(thermal_gap 0.1651)
		)
		(pad "B3" thru_hole circle
			(at 3.599942 -1.400048)
			(size 0.762 0.762)
			(drill 0.359918)
			(layers "*.Cu" "*.Mask")
			(remove_unused_layers no)
			(net "PHY_DPB_TO_SCC_14_DP")
			(clearance 0.1651)
			(thermal_gap 0.1651)
		)
		(pad "B4" thru_hole circle
			(at 5.40004 -0.199898)
			(size 0.762 0.762)
			(drill 0.359918)
			(layers "*.Cu" "*.Mask")
			(remove_unused_layers no)
			(net "PHY_DPB_TO_SCC_15_DP")
			(clearance 0.1651)
			(thermal_gap 0.1651)
		)
		(pad "B5" thru_hole circle
			(at 7.199884 -1.400048)
			(size 0.762 0.762)
			(drill 0.359918)
			(layers "*.Cu" "*.Mask")
			(remove_unused_layers no)
			(net "PHY_DPB_TO_SCC_16_DP")
			(clearance 0.1651)
			(thermal_gap 0.1651)
		)
		(pad "B6" thru_hole circle
			(at 8.999982 -0.199898)
			(size 0.762 0.762)
			(drill 0.359918)
			(layers "*.Cu" "*.Mask")
			(remove_unused_layers no)
			(net "PHY_DPB_TO_SCC_17_DP")
			(clearance 0.1651)
			(thermal_gap 0.1651)
		)
		(pad "B7" thru_hole circle
			(at 10.80008 -1.400048)
			(size 0.762 0.762)
			(drill 0.359918)
			(layers "*.Cu" "*.Mask")
			(remove_unused_layers no)
			(net "PHY_DPB_TO_SCC_18_DP")
			(clearance 0.1651)
			(thermal_gap 0.1651)
		)
		(pad "B8" thru_hole circle
			(at 12.599924 -0.199898)
			(size 0.762 0.762)
			(drill 0.359918)
			(layers "*.Cu" "*.Mask")
			(remove_unused_layers no)
			(net "PHY_DPB_TO_SCC_19_DP")
			(clearance 0.1651)
			(thermal_gap 0.1651)
		)
		(pad "B9" thru_hole circle
			(at 14.400022 -1.400048)
			(size 0.762 0.762)
			(drill 0.359918)
			(layers "*.Cu" "*.Mask")
			(remove_unused_layers no)
			(net "PHY_DPB_TO_SCC_20_DP")
			(clearance 0.1651)
			(thermal_gap 0.1651)
		)
		(pad "B10" thru_hole circle
			(at 16.20012 -0.199898)
			(size 0.762 0.762)
			(drill 0.359918)
			(layers "*.Cu" "*.Mask")
			(remove_unused_layers no)
			(net "PHY_DPB_TO_SCC_21_DP")
			(clearance 0.1651)
			(thermal_gap 0.1651)
		)
		(pad "B11" thru_hole circle
			(at 17.999964 -1.400048)
			(size 0.762 0.762)
			(drill 0.359918)
			(layers "*.Cu" "*.Mask")
			(remove_unused_layers no)
			(net "PHY_DPB_TO_SCC_22_DP")
			(clearance 0.1651)
			(thermal_gap 0.1651)
		)
		(pad "B12" thru_hole circle
			(at 19.800062 -0.199898)
			(size 0.762 0.762)
			(drill 0.359918)
			(layers "*.Cu" "*.Mask")
			(remove_unused_layers no)
			(net "PHY_DPB_TO_SCC_23_DP")
			(clearance 0.1651)
			(thermal_gap 0.1651)
		)
		(pad "B13" thru_hole circle
			(at 21.599906 -1.400048)
			(size 0.762 0.762)
			(drill 0.359918)
			(layers "*.Cu" "*.Mask")
			(remove_unused_layers no)
			(net "PHY_DPB_TO_SCC_24_DP")
			(clearance 0.1651)
			(thermal_gap 0.1651)
		)
		(pad "B14" thru_hole circle
			(at 23.400004 -0.199898)
			(size 0.762 0.762)
			(drill 0.359918)
			(layers "*.Cu" "*.Mask")
			(remove_unused_layers no)
			(net "PHY_DPB_TO_SCC_25_DP")
			(clearance 0.1651)
			(thermal_gap 0.1651)
		)
		(pad "B15" thru_hole circle
			(at 25.200102 -1.400048)
			(size 0.762 0.762)
			(drill 0.359918)
			(layers "*.Cu" "*.Mask")
			(remove_unused_layers no)
			(net "PHY_DPB_TO_SCC_26_DP")
			(clearance 0.1651)
			(thermal_gap 0.1651)
		)
		(pad "B16" thru_hole circle
			(at 26.999946 -0.199898)
			(size 0.762 0.762)
			(drill 0.359918)
			(layers "*.Cu" "*.Mask")
			(remove_unused_layers no)
			(net "PHY_DPB_TO_SCC_27_DP")
			(clearance 0.1651)
			(thermal_gap 0.1651)
		)
		(pad "B17" thru_hole circle
			(at 28.800044 -1.400048)
			(size 0.762 0.762)
			(drill 0.359918)
			(layers "*.Cu" "*.Mask")
			(remove_unused_layers no)
			(net "PHY_DPB_TO_SCC_32_DP")
			(clearance 0.1651)
			(thermal_gap 0.1651)
		)
		(pad "B18" thru_hole circle
			(at 30.599888 -0.199898)
			(size 0.762 0.762)
			(drill 0.359918)
			(layers "*.Cu" "*.Mask")
			(remove_unused_layers no)
			(net "PHY_DPB_TO_SCC_33_DP")
			(clearance 0.1651)
			(thermal_gap 0.1651)
		)
		(pad "B19" thru_hole circle
			(at 32.399986 -1.400048)
			(size 0.762 0.762)
			(drill 0.359918)
			(layers "*.Cu" "*.Mask")
			(remove_unused_layers no)
			(net "PHY_DPB_TO_SCC_34_DP")
			(clearance 0.1651)
			(thermal_gap 0.1651)
		)
		(pad "B20" thru_hole circle
			(at 34.200084 -0.199898)
			(size 0.762 0.762)
			(drill 0.359918)
			(layers "*.Cu" "*.Mask")
			(remove_unused_layers no)
			(net "PHY_DPB_TO_SCC_35_DP")
			(clearance 0.1651)
			(thermal_gap 0.1651)
		)
		(pad "B21" thru_hole circle
			(at 35.999928 -1.400048)
			(size 0.762 0.762)
			(drill 0.359918)
			(layers "*.Cu" "*.Mask")
			(remove_unused_layers no)
			(net "PHY_DPB_TO_SCC_36_DP")
			(clearance 0.1651)
			(thermal_gap 0.1651)
		)
		(pad "B22" thru_hole circle
			(at 37.800026 -0.199898)
			(size 0.762 0.762)
			(drill 0.359918)
			(layers "*.Cu" "*.Mask")
			(remove_unused_layers no)
			(net "PHY_DPB_TO_SCC_37_DP")
			(clearance 0.1651)
			(thermal_gap 0.1651)
		)
		(pad "B23" thru_hole circle
			(at 39.600124 -1.400048)
			(size 0.762 0.762)
			(drill 0.359918)
			(layers "*.Cu" "*.Mask")
			(remove_unused_layers no)
			(net "PHY_DPB_TO_SCC_38_DP")
			(clearance 0.1651)
			(thermal_gap 0.1651)
		)
		(pad "B24" thru_hole circle
			(at 41.399968 -0.199898)
			(size 0.762 0.762)
			(drill 0.359918)
			(layers "*.Cu" "*.Mask")
			(remove_unused_layers no)
			(net "PHY_DPB_TO_SCC_39_DP")
			(clearance 0.1651)
			(thermal_gap 0.1651)
		)
		(pad "B25" thru_hole circle
			(at 43.200066 -1.400048)
			(size 0.762 0.762)
			(drill 0.359918)
			(layers "*.Cu" "*.Mask")
			(remove_unused_layers no)
			(net "PHY_DPB_TO_SCC_28_DP")
			(clearance 0.1651)
			(thermal_gap 0.1651)
		)
		(pad "B26" thru_hole circle
			(at 44.99991 -0.199898)
			(size 0.762 0.762)
			(drill 0.359918)
			(layers "*.Cu" "*.Mask")
			(remove_unused_layers no)
			(net "PHY_DPB_TO_SCC_29_DP")
			(clearance 0.1651)
			(thermal_gap 0.1651)
		)
		(pad "B27" thru_hole circle
			(at 46.800008 -1.400048)
			(size 0.762 0.762)
			(drill 0.359918)
			(layers "*.Cu" "*.Mask")
			(remove_unused_layers no)
			(net "PHY_DPB_TO_SCC_30_DP")
			(clearance 0.1651)
			(thermal_gap 0.1651)
		)
		(pad "B28" thru_hole circle
			(at 48.600106 -0.199898)
			(size 0.762 0.762)
			(drill 0.359918)
			(layers "*.Cu" "*.Mask")
			(remove_unused_layers no)
			(net "PHY_DPB_TO_SCC_31_DP")
			(clearance 0.1651)
			(thermal_gap 0.1651)
		)
		(pad "B29" thru_hole circle
			(at 50.39995 -1.400048)
			(size 0.762 0.762)
			(drill 0.359918)
			(layers "*.Cu" "*.Mask")
			(remove_unused_layers no)
			(net "PHY_DPB_TO_SCC_0_DP")
			(clearance 0.1651)
			(thermal_gap 0.1651)
		)
		(pad "B30" thru_hole circle
			(at 52.200048 -0.199898)
			(size 0.762 0.762)
			(drill 0.359918)
			(layers "*.Cu" "*.Mask")
			(remove_unused_layers no)
			(net "PHY_DPB_TO_SCC_1_DP")
			(clearance 0.1651)
			(thermal_gap 0.1651)
		)
		(pad "B31" thru_hole circle
			(at 53.999892 -1.400048)
			(size 0.762 0.762)
			(drill 0.359918)
			(layers "*.Cu" "*.Mask")
			(remove_unused_layers no)
			(net "PHY_DPB_TO_SCC_2_DP")
			(clearance 0.1651)
			(thermal_gap 0.1651)
		)
		(pad "B32" thru_hole circle
			(at 55.79999 -0.199898)
			(size 0.762 0.762)
			(drill 0.359918)
			(layers "*.Cu" "*.Mask")
			(remove_unused_layers no)
			(net "PHY_DPB_TO_SCC_3_DP")
			(clearance 0.1651)
			(thermal_gap 0.1651)
		)
		(pad "B33" thru_hole circle
			(at 57.600088 -1.400048)
			(size 0.762 0.762)
			(drill 0.359918)
			(layers "*.Cu" "*.Mask")
			(remove_unused_layers no)
			(net "PHY_DPB_TO_SCC_4_DP")
			(clearance 0.1651)
			(thermal_gap 0.1651)
		)
		(pad "B34" thru_hole circle
			(at 59.399932 -0.199898)
			(size 0.762 0.762)
			(drill 0.359918)
			(layers "*.Cu" "*.Mask")
			(remove_unused_layers no)
			(net "PHY_DPB_TO_SCC_5_DP")
			(clearance 0.1651)
			(thermal_gap 0.1651)
		)
		(pad "B35" thru_hole circle
			(at 61.20003 -1.400048)
			(size 0.762 0.762)
			(drill 0.359918)
			(layers "*.Cu" "*.Mask")
			(remove_unused_layers no)
			(net "PHY_DPB_TO_SCC_6_DP")
			(clearance 0.1651)
			(thermal_gap 0.1651)
		)
		(pad "B36" thru_hole circle
			(at 62.999874 -0.199898)
			(size 0.762 0.762)
			(drill 0.359918)
			(layers "*.Cu" "*.Mask")
			(remove_unused_layers no)
			(net "PHY_DPB_TO_SCC_7_DP")
			(clearance 0.1651)
			(thermal_gap 0.1651)
		)
		(pad "C1" thru_hole circle
			(at 0 -3.599942)
			(size 0.762 0.762)
			(drill 0.359918)
			(layers "*.Cu" "*.Mask")
			(remove_unused_layers no)
			(net "SCC_STBY_PGOOD")
			(clearance 0.1651)
			(thermal_gap 0.1651)
		)
		(pad "C2" thru_hole circle
			(at 1.800098 -2.400046)
			(size 0.762 0.762)
			(drill 0.359918)
			(layers "*.Cu" "*.Mask")
			(remove_unused_layers no)
			(net "P3V3_DPB")
			(clearance 0.1651)
			(thermal_gap 0.1651)
		)
		(pad "C3" thru_hole circle
			(at 3.599942 -3.599942)
			(size 0.762 0.762)
			(drill 0.359918)
			(layers "*.Cu" "*.Mask")
			(remove_unused_layers no)
			(net "SCC_LOC_HEARTBEAT")
			(clearance 0.1651)
			(thermal_gap 0.1651)
		)
		(pad "C4" thru_hole circle
			(at 5.40004 -2.400046)
			(size 0.762 0.762)
			(drill 0.359918)
			(layers "*.Cu" "*.Mask")
			(remove_unused_layers no)
			(net "SLOT_ID_0")
			(clearance 0.1651)
			(thermal_gap 0.1651)
		)
		(pad "C5" thru_hole circle
			(at 7.199884 -3.599942)
			(size 0.762 0.762)
			(drill 0.359918)
			(layers "*.Cu" "*.Mask")
			(remove_unused_layers no)
			(net "SCC_TYPE_0")
			(clearance 0.1651)
			(thermal_gap 0.1651)
		)
		(pad "C6" thru_hole circle
			(at 8.999982 -2.400046)
			(size 0.762 0.762)
			(drill 0.359918)
			(layers "*.Cu" "*.Mask")
			(remove_unused_layers no)
			(net "SCC_TYPE_2")
			(clearance 0.1651)
			(thermal_gap 0.1651)
		)
		(pad "C7" thru_hole circle
			(at 10.80008 -3.599942)
			(size 0.762 0.762)
			(drill 0.359918)
			(layers "*.Cu" "*.Mask")
			(remove_unused_layers no)
			(net "UART_SDB_TX")
			(clearance 0.1651)
			(thermal_gap 0.1651)
		)
		(pad "C8" thru_hole circle
			(at 12.599924 -2.400046)
			(size 0.762 0.762)
			(drill 0.359918)
			(layers "*.Cu" "*.Mask")
			(remove_unused_layers no)
			(net "PWM_OUT_ZONE_C")
			(clearance 0.1651)
			(thermal_gap 0.1651)
		)
		(pad "C9" thru_hole circle
			(at 14.400022 -3.599942)
			(size 0.762 0.762)
			(drill 0.359918)
			(layers "*.Cu" "*.Mask")
			(remove_unused_layers no)
			(net "SYS_PWR_LED_N")
			(clearance 0.1651)
			(thermal_gap 0.1651)
		)
		(pad "C10" thru_hole circle
			(at 16.20012 -2.400046)
			(size 0.762 0.762)
			(drill 0.359918)
			(layers "*.Cu" "*.Mask")
			(remove_unused_layers no)
			(net "ENCL_FAULT_LED")
			(clearance 0.1651)
			(thermal_gap 0.1651)
		)
		(pad "C11" thru_hole circle
			(at 17.999964 -3.599942)
			(size 0.762 0.762)
			(drill 0.359918)
			(layers "*.Cu" "*.Mask")
			(remove_unused_layers no)
			(net "DRIVE_INSERT_ALERT_N")
			(clearance 0.1651)
			(thermal_gap 0.1651)
		)
		(pad "C12" thru_hole circle
			(at 19.800062 -2.400046)
			(size 0.762 0.762)
			(drill 0.359918)
			(layers "*.Cu" "*.Mask")
			(remove_unused_layers no)
			(net "I2C_CLIP_SCL7")
			(clearance 0.1651)
			(thermal_gap 0.1651)
		)
		(pad "C13" thru_hole circle
			(at 21.599906 -3.599942)
			(size 0.762 0.762)
			(drill 0.359918)
			(layers "*.Cu" "*.Mask")
			(remove_unused_layers no)
			(net "UART_EXP_TX")
			(clearance 0.1651)
			(thermal_gap 0.1651)
		)
		(pad "C14" thru_hole circle
			(at 23.400004 -2.400046)
			(size 0.762 0.762)
			(drill 0.359918)
			(layers "*.Cu" "*.Mask")
			(remove_unused_layers no)
			(net "I2C_DPB_SCL3")
			(clearance 0.1651)
			(thermal_gap 0.1651)
		)
		(pad "C15" thru_hole circle
			(at 25.200102 -3.599942)
			(size 0.762 0.762)
			(drill 0.359918)
			(layers "*.Cu" "*.Mask")
			(remove_unused_layers no)
			(net "I2C_DRIVE_PWR_SCL4")
			(clearance 0.1651)
			(thermal_gap 0.1651)
		)
		(pad "C16" thru_hole circle
			(at 26.999946 -2.400046)
			(size 0.762 0.762)
			(drill 0.359918)
			(layers "*.Cu" "*.Mask")
			(remove_unused_layers no)
			(net "I2C_DRIVE_INS_SCL5")
			(clearance 0.1651)
			(thermal_gap 0.1651)
		)
		(pad "C17" thru_hole circle
			(at 28.800044 -3.599942)
			(size 0.762 0.762)
			(drill 0.359918)
			(layers "*.Cu" "*.Mask")
			(remove_unused_layers no)
			(net "I2C_DRIVE_FLT_LED_SCL6")
			(clearance 0.1651)
			(thermal_gap 0.1651)
		)
		(pad "C18" thru_hole circle
			(at 30.599888 -2.400046)
			(size 0.762 0.762)
			(drill 0.359918)
			(layers "*.Cu" "*.Mask")
			(remove_unused_layers no)
			(net "DRIVE_0_ACT")
			(clearance 0.1651)
			(thermal_gap 0.1651)
		)
		(pad "C19" thru_hole circle
			(at 32.399986 -3.599942)
			(size 0.762 0.762)
			(drill 0.359918)
			(layers "*.Cu" "*.Mask")
			(remove_unused_layers no)
			(net "DRIVE_2_ACT")
			(clearance 0.1651)
			(thermal_gap 0.1651)
		)
		(pad "C20" thru_hole circle
			(at 34.200084 -2.400046)
			(size 0.762 0.762)
			(drill 0.359918)
			(layers "*.Cu" "*.Mask")
			(remove_unused_layers no)
			(net "DRIVE_4_ACT")
			(clearance 0.1651)
			(thermal_gap 0.1651)
		)
		(pad "C21" thru_hole circle
			(at 35.999928 -3.599942)
			(size 0.762 0.762)
			(drill 0.359918)
			(layers "*.Cu" "*.Mask")
			(remove_unused_layers no)
			(net "DRIVE_6_ACT")
			(clearance 0.1651)
			(thermal_gap 0.1651)
		)
		(pad "C22" thru_hole circle
			(at 37.800026 -2.400046)
			(size 0.762 0.762)
			(drill 0.359918)
			(layers "*.Cu" "*.Mask")
			(remove_unused_layers no)
			(net "DRIVE_12_ACT")
			(clearance 0.1651)
			(thermal_gap 0.1651)
		)
		(pad "C23" thru_hole circle
			(at 39.600124 -3.599942)
			(size 0.762 0.762)
			(drill 0.359918)
			(layers "*.Cu" "*.Mask")
			(remove_unused_layers no)
			(net "DRIVE_14_ACT")
			(clearance 0.1651)
			(thermal_gap 0.1651)
		)
		(pad "C24" thru_hole circle
			(at 41.399968 -2.400046)
			(size 0.762 0.762)
			(drill 0.359918)
			(layers "*.Cu" "*.Mask")
			(remove_unused_layers no)
			(net "DRIVE_16_ACT")
			(clearance 0.1651)
			(thermal_gap 0.1651)
		)
		(pad "C25" thru_hole circle
			(at 43.200066 -3.599942)
			(size 0.762 0.762)
			(drill 0.359918)
			(layers "*.Cu" "*.Mask")
			(remove_unused_layers no)
			(net "DRIVE_18_ACT")
			(clearance 0.1651)
			(thermal_gap 0.1651)
		)
		(pad "C26" thru_hole circle
			(at 44.99991 -2.400046)
			(size 0.762 0.762)
			(drill 0.359918)
			(layers "*.Cu" "*.Mask")
			(remove_unused_layers no)
			(net "DRIVE_20_ACT")
			(clearance 0.1651)
			(thermal_gap 0.1651)
		)
		(pad "C27" thru_hole circle
			(at 46.800008 -3.599942)
			(size 0.762 0.762)
			(drill 0.359918)
			(layers "*.Cu" "*.Mask")
			(remove_unused_layers no)
			(net "DRIVE_22_ACT")
			(clearance 0.1651)
			(thermal_gap 0.1651)
		)
		(pad "C28" thru_hole circle
			(at 48.600106 -2.400046)
			(size 0.762 0.762)
			(drill 0.359918)
			(layers "*.Cu" "*.Mask")
			(remove_unused_layers no)
			(net "DRIVE_24_ACT")
			(clearance 0.1651)
			(thermal_gap 0.1651)
		)
		(pad "C29" thru_hole circle
			(at 50.39995 -3.599942)
			(size 0.762 0.762)
			(drill 0.359918)
			(layers "*.Cu" "*.Mask")
			(remove_unused_layers no)
			(net "DRIVE_26_ACT")
			(clearance 0.1651)
			(thermal_gap 0.1651)
		)
		(pad "C30" thru_hole circle
			(at 52.200048 -2.400046)
			(size 0.762 0.762)
			(drill 0.359918)
			(layers "*.Cu" "*.Mask")
			(remove_unused_layers no)
			(net "DRIVE_28_ACT")
			(clearance 0.1651)
			(thermal_gap 0.1651)
		)
		(pad "C31" thru_hole circle
			(at 53.999892 -3.599942)
			(size 0.762 0.762)
			(drill 0.359918)
			(layers "*.Cu" "*.Mask")
			(remove_unused_layers no)
			(net "DRIVE_30_ACT")
			(clearance 0.1651)
			(thermal_gap 0.1651)
		)
		(pad "C32" thru_hole circle
			(at 55.79999 -2.400046)
			(size 0.762 0.762)
			(drill 0.359918)
			(layers "*.Cu" "*.Mask")
			(remove_unused_layers no)
			(net "DRIVE_32_ACT")
			(clearance 0.1651)
			(thermal_gap 0.1651)
		)
		(pad "C33" thru_hole circle
			(at 57.600088 -3.599942)
			(size 0.762 0.762)
			(drill 0.359918)
			(layers "*.Cu" "*.Mask")
			(remove_unused_layers no)
			(net "DRIVE_34_ACT")
			(clearance 0.1651)
			(thermal_gap 0.1651)
		)
		(pad "C34" thru_hole circle
			(at 59.399932 -2.400046)
			(size 0.762 0.762)
			(drill 0.359918)
			(layers "*.Cu" "*.Mask")
			(remove_unused_layers no)
			(net "DRIVE_36_ACT")
			(clearance 0.1651)
			(thermal_gap 0.1651)
		)
		(pad "C35" thru_hole circle
			(at 61.20003 -3.599942)
			(size 0.762 0.762)
			(drill 0.359918)
			(layers "*.Cu" "*.Mask")
			(remove_unused_layers no)
			(net "DRIVE_38_ACT")
			(clearance 0.1651)
			(thermal_gap 0.1651)
		)
		(pad "C36" thru_hole circle
			(at 62.999874 -2.400046)
			(size 0.762 0.762)
			(drill 0.359918)
			(layers "*.Cu" "*.Mask")
			(remove_unused_layers no)
			(net "SCC_HSC_N")
			(clearance 0.1651)
			(thermal_gap 0.1651)
		)
		(pad "D1" thru_hole circle
			(at 0 -4.99999)
			(size 0.762 0.762)
			(drill 0.359918)
			(layers "*.Cu" "*.Mask")
			(remove_unused_layers no)
			(net "BMC_LOC_HEARTBEAT")
			(clearance 0.1651)
			(thermal_gap 0.1651)
		)
		(pad "D2" thru_hole circle
			(at 1.800098 -3.800094)
			(size 0.762 0.762)
			(drill 0.359918)
			(layers "*.Cu" "*.Mask")
			(remove_unused_layers no)
			(net "SCC_STBY_PWR_EN")
			(clearance 0.1651)
			(thermal_gap 0.1651)
		)
		(pad "D3" thru_hole circle
			(at 3.599942 -4.99999)
			(size 0.762 0.762)
			(drill 0.359918)
			(layers "*.Cu" "*.Mask")
			(remove_unused_layers no)
			(net "SCC_RMT_HEARTBEAT")
			(clearance 0.1651)
			(thermal_gap 0.1651)
		)
		(pad "D4" thru_hole circle
			(at 5.40004 -3.800094)
			(size 0.762 0.762)
			(drill 0.359918)
			(layers "*.Cu" "*.Mask")
			(remove_unused_layers no)
			(net "SLOT_ID_1")
			(clearance 0.1651)
			(thermal_gap 0.1651)
		)
		(pad "D5" thru_hole circle
			(at 7.199884 -4.99999)
			(size 0.762 0.762)
			(drill 0.359918)
			(layers "*.Cu" "*.Mask")
			(remove_unused_layers no)
			(net "SCC_TYPE_1")
			(clearance 0.1651)
			(thermal_gap 0.1651)
		)
		(pad "D6" thru_hole circle
			(at 8.999982 -3.800094)
			(size 0.762 0.762)
			(drill 0.359918)
			(layers "*.Cu" "*.Mask")
			(remove_unused_layers no)
			(net "SCC_TYPE_3")
			(clearance 0.1651)
			(thermal_gap 0.1651)
		)
		(pad "D7" thru_hole circle
			(at 10.80008 -4.99999)
			(size 0.762 0.762)
			(drill 0.359918)
			(layers "*.Cu" "*.Mask")
			(remove_unused_layers no)
			(net "UART_SDB_RX")
			(clearance 0.1651)
			(thermal_gap 0.1651)
		)
		(pad "D8" thru_hole circle
			(at 12.599924 -3.800094)
			(size 0.762 0.762)
			(drill 0.359918)
			(layers "*.Cu" "*.Mask")
			(remove_unused_layers no)
			(net "PWM_OUT_ZONE_D")
			(clearance 0.1651)
			(thermal_gap 0.1651)
		)
		(pad "D9" thru_hole circle
			(at 14.400022 -4.99999)
			(size 0.762 0.762)
			(drill 0.359918)
			(layers "*.Cu" "*.Mask")
			(remove_unused_layers no)
			(net "SCC_FULL_PWR_EN")
			(clearance 0.1651)
			(thermal_gap 0.1651)
		)
		(pad "D10" thru_hole circle
			(at 16.20012 -3.800094)
			(size 0.762 0.762)
			(drill 0.359918)
			(layers "*.Cu" "*.Mask")
			(remove_unused_layers no)
			(net "SCC_RESET_N")
			(clearance 0.1651)
			(thermal_gap 0.1651)
		)
		(pad "D11" thru_hole circle
			(at 17.999964 -4.99999)
			(size 0.762 0.762)
			(drill 0.359918)
			(layers "*.Cu" "*.Mask")
			(remove_unused_layers no)
			(net "SCC_LOC_INS_N")
			(clearance 0.1651)
			(thermal_gap 0.1651)
		)
		(pad "D12" thru_hole circle
			(at 19.800062 -3.800094)
			(size 0.762 0.762)
			(drill 0.359918)
			(layers "*.Cu" "*.Mask")
			(remove_unused_layers no)
			(net "I2C_CLIP_SDA7")
			(clearance 0.1651)
			(thermal_gap 0.1651)
		)
		(pad "D13" thru_hole circle
			(at 21.599906 -4.99999)
			(size 0.762 0.762)
			(drill 0.359918)
			(layers "*.Cu" "*.Mask")
			(remove_unused_layers no)
			(net "UART_EXP_RX")
			(clearance 0.1651)
			(thermal_gap 0.1651)
		)
		(pad "D14" thru_hole circle
			(at 23.400004 -3.800094)
			(size 0.762 0.762)
			(drill 0.359918)
			(layers "*.Cu" "*.Mask")
			(remove_unused_layers no)
			(net "I2C_DPB_SDA3")
			(clearance 0.1651)
			(thermal_gap 0.1651)
		)
		(pad "D15" thru_hole circle
			(at 25.200102 -4.99999)
			(size 0.762 0.762)
			(drill 0.359918)
			(layers "*.Cu" "*.Mask")
			(remove_unused_layers no)
			(net "I2C_DRIVE_PWR_SDA4")
			(clearance 0.1651)
			(thermal_gap 0.1651)
		)
		(pad "D16" thru_hole circle
			(at 26.999946 -3.800094)
			(size 0.762 0.762)
			(drill 0.359918)
			(layers "*.Cu" "*.Mask")
			(remove_unused_layers no)
			(net "I2C_DRIVE_INS_SDA5")
			(clearance 0.1651)
			(thermal_gap 0.1651)
		)
		(pad "D17" thru_hole circle
			(at 28.800044 -4.99999)
			(size 0.762 0.762)
			(drill 0.359918)
			(layers "*.Cu" "*.Mask")
			(remove_unused_layers no)
			(net "I2C_DRIVE_FLT_LED_SDA6")
			(clearance 0.1651)
			(thermal_gap 0.1651)
		)
		(pad "D18" thru_hole circle
			(at 30.599888 -3.800094)
			(size 0.762 0.762)
			(drill 0.359918)
			(layers "*.Cu" "*.Mask")
			(remove_unused_layers no)
			(net "DRIVE_1_ACT")
			(clearance 0.1651)
			(thermal_gap 0.1651)
		)
		(pad "D19" thru_hole circle
			(at 32.399986 -4.99999)
			(size 0.762 0.762)
			(drill 0.359918)
			(layers "*.Cu" "*.Mask")
			(remove_unused_layers no)
			(net "DRIVE_3_ACT")
			(clearance 0.1651)
			(thermal_gap 0.1651)
		)
		(pad "D20" thru_hole circle
			(at 34.200084 -3.800094)
			(size 0.762 0.762)
			(drill 0.359918)
			(layers "*.Cu" "*.Mask")
			(remove_unused_layers no)
			(net "DRIVE_5_ACT")
			(clearance 0.1651)
			(thermal_gap 0.1651)
		)
		(pad "D21" thru_hole circle
			(at 35.999928 -4.99999)
			(size 0.762 0.762)
			(drill 0.359918)
			(layers "*.Cu" "*.Mask")
			(remove_unused_layers no)
			(net "DRIVE_7_ACT")
			(clearance 0.1651)
			(thermal_gap 0.1651)
		)
		(pad "D22" thru_hole circle
			(at 37.800026 -3.800094)
			(size 0.762 0.762)
			(drill 0.359918)
			(layers "*.Cu" "*.Mask")
			(remove_unused_layers no)
			(net "DRIVE_13_ACT")
			(clearance 0.1651)
			(thermal_gap 0.1651)
		)
		(pad "D23" thru_hole circle
			(at 39.600124 -4.99999)
			(size 0.762 0.762)
			(drill 0.359918)
			(layers "*.Cu" "*.Mask")
			(remove_unused_layers no)
			(net "DRIVE_15_ACT")
			(clearance 0.1651)
			(thermal_gap 0.1651)
		)
		(pad "D24" thru_hole circle
			(at 41.399968 -3.800094)
			(size 0.762 0.762)
			(drill 0.359918)
			(layers "*.Cu" "*.Mask")
			(remove_unused_layers no)
			(net "DRIVE_17_ACT")
			(clearance 0.1651)
			(thermal_gap 0.1651)
		)
		(pad "D25" thru_hole circle
			(at 43.200066 -4.99999)
			(size 0.762 0.762)
			(drill 0.359918)
			(layers "*.Cu" "*.Mask")
			(remove_unused_layers no)
			(net "DRIVE_19_ACT")
			(clearance 0.1651)
			(thermal_gap 0.1651)
		)
		(pad "D26" thru_hole circle
			(at 44.99991 -3.800094)
			(size 0.762 0.762)
			(drill 0.359918)
			(layers "*.Cu" "*.Mask")
			(remove_unused_layers no)
			(net "DRIVE_21_ACT")
			(clearance 0.1651)
			(thermal_gap 0.1651)
		)
		(pad "D27" thru_hole circle
			(at 46.800008 -4.99999)
			(size 0.762 0.762)
			(drill 0.359918)
			(layers "*.Cu" "*.Mask")
			(remove_unused_layers no)
			(net "DRIVE_23_ACT")
			(clearance 0.1651)
			(thermal_gap 0.1651)
		)
		(pad "D28" thru_hole circle
			(at 48.600106 -3.800094)
			(size 0.762 0.762)
			(drill 0.359918)
			(layers "*.Cu" "*.Mask")
			(remove_unused_layers no)
			(net "DRIVE_25_ACT")
			(clearance 0.1651)
			(thermal_gap 0.1651)
		)
		(pad "D29" thru_hole circle
			(at 50.39995 -4.99999)
			(size 0.762 0.762)
			(drill 0.359918)
			(layers "*.Cu" "*.Mask")
			(remove_unused_layers no)
			(net "DRIVE_27_ACT")
			(clearance 0.1651)
			(thermal_gap 0.1651)
		)
		(pad "D30" thru_hole circle
			(at 52.200048 -3.800094)
			(size 0.762 0.762)
			(drill 0.359918)
			(layers "*.Cu" "*.Mask")
			(remove_unused_layers no)
			(net "DRIVE_29_ACT")
			(clearance 0.1651)
			(thermal_gap 0.1651)
		)
		(pad "D31" thru_hole circle
			(at 53.999892 -4.99999)
			(size 0.762 0.762)
			(drill 0.359918)
			(layers "*.Cu" "*.Mask")
			(remove_unused_layers no)
			(net "DRIVE_31_ACT")
			(clearance 0.1651)
			(thermal_gap 0.1651)
		)
		(pad "D32" thru_hole circle
			(at 55.79999 -3.800094)
			(size 0.762 0.762)
			(drill 0.359918)
			(layers "*.Cu" "*.Mask")
			(remove_unused_layers no)
			(net "DRIVE_33_ACT")
			(clearance 0.1651)
			(thermal_gap 0.1651)
		)
		(pad "D33" thru_hole circle
			(at 57.600088 -4.99999)
			(size 0.762 0.762)
			(drill 0.359918)
			(layers "*.Cu" "*.Mask")
			(remove_unused_layers no)
			(net "DRIVE_35_ACT")
			(clearance 0.1651)
			(thermal_gap 0.1651)
		)
		(pad "D34" thru_hole circle
			(at 59.399932 -3.800094)
			(size 0.762 0.762)
			(drill 0.359918)
			(layers "*.Cu" "*.Mask")
			(remove_unused_layers no)
			(net "DRIVE_37_ACT")
			(clearance 0.1651)
			(thermal_gap 0.1651)
		)
		(pad "D35" thru_hole circle
			(at 61.20003 -4.99999)
			(size 0.762 0.762)
			(drill 0.359918)
			(layers "*.Cu" "*.Mask")
			(remove_unused_layers no)
			(net "DRIVE_39_ACT")
			(clearance 0.1651)
			(thermal_gap 0.1651)
		)
		(pad "D36" thru_hole circle
			(at 62.999874 -3.800094)
			(size 0.762 0.762)
			(drill 0.359918)
			(layers "*.Cu" "*.Mask")
			(remove_unused_layers no)
			(net "SCC_FULL_PGOOD_BUF")
			(clearance 0.1651)
			(thermal_gap 0.1651)
		)
		(pad "E1" thru_hole circle
			(at 0 -7.199884)
			(size 0.762 0.762)
			(drill 0.359918)
			(layers "*.Cu" "*.Mask")
			(remove_unused_layers no)
			(net "PHY_SCC_TO_DPB_12_DP")
			(clearance 0.1651)
			(thermal_gap 0.1651)
		)
		(pad "E2" thru_hole circle
			(at 1.800098 -5.999988)
			(size 0.762 0.762)
			(drill 0.359918)
			(layers "*.Cu" "*.Mask")
			(remove_unused_layers no)
			(net "PHY_SCC_TO_DPB_13_DP")
			(clearance 0.1651)
			(thermal_gap 0.1651)
		)
		(pad "E3" thru_hole circle
			(at 3.599942 -7.199884)
			(size 0.762 0.762)
			(drill 0.359918)
			(layers "*.Cu" "*.Mask")
			(remove_unused_layers no)
			(net "PHY_SCC_TO_DPB_14_DP")
			(clearance 0.1651)
			(thermal_gap 0.1651)
		)
		(pad "E4" thru_hole circle
			(at 5.40004 -5.999988)
			(size 0.762 0.762)
			(drill 0.359918)
			(layers "*.Cu" "*.Mask")
			(remove_unused_layers no)
			(net "PHY_SCC_TO_DPB_15_DP")
			(clearance 0.1651)
			(thermal_gap 0.1651)
		)
		(pad "E5" thru_hole circle
			(at 7.199884 -7.199884)
			(size 0.762 0.762)
			(drill 0.359918)
			(layers "*.Cu" "*.Mask")
			(remove_unused_layers no)
			(net "PHY_SCC_TO_DPB_16_DP")
			(clearance 0.1651)
			(thermal_gap 0.1651)
		)
		(pad "E6" thru_hole circle
			(at 8.999982 -5.999988)
			(size 0.762 0.762)
			(drill 0.359918)
			(layers "*.Cu" "*.Mask")
			(remove_unused_layers no)
			(net "PHY_SCC_TO_DPB_17_DP")
			(clearance 0.1651)
			(thermal_gap 0.1651)
		)
		(pad "E7" thru_hole circle
			(at 10.80008 -7.199884)
			(size 0.762 0.762)
			(drill 0.359918)
			(layers "*.Cu" "*.Mask")
			(remove_unused_layers no)
			(net "PHY_SCC_TO_DPB_18_DP")
			(clearance 0.1651)
			(thermal_gap 0.1651)
		)
		(pad "E8" thru_hole circle
			(at 12.599924 -5.999988)
			(size 0.762 0.762)
			(drill 0.359918)
			(layers "*.Cu" "*.Mask")
			(remove_unused_layers no)
			(net "PHY_SCC_TO_DPB_19_DP")
			(clearance 0.1651)
			(thermal_gap 0.1651)
		)
		(pad "E9" thru_hole circle
			(at 14.400022 -7.199884)
			(size 0.762 0.762)
			(drill 0.359918)
			(layers "*.Cu" "*.Mask")
			(remove_unused_layers no)
			(net "PHY_SCC_TO_DPB_20_DP")
			(clearance 0.1651)
			(thermal_gap 0.1651)
		)
		(pad "E10" thru_hole circle
			(at 16.20012 -5.999988)
			(size 0.762 0.762)
			(drill 0.359918)
			(layers "*.Cu" "*.Mask")
			(remove_unused_layers no)
			(net "PHY_SCC_TO_DPB_21_DP")
			(clearance 0.1651)
			(thermal_gap 0.1651)
		)
		(pad "E11" thru_hole circle
			(at 17.999964 -7.199884)
			(size 0.762 0.762)
			(drill 0.359918)
			(layers "*.Cu" "*.Mask")
			(remove_unused_layers no)
			(net "PHY_SCC_TO_DPB_22_DP")
			(clearance 0.1651)
			(thermal_gap 0.1651)
		)
		(pad "E12" thru_hole circle
			(at 19.800062 -5.999988)
			(size 0.762 0.762)
			(drill 0.359918)
			(layers "*.Cu" "*.Mask")
			(remove_unused_layers no)
			(net "PHY_SCC_TO_DPB_23_DP")
			(clearance 0.1651)
			(thermal_gap 0.1651)
		)
		(pad "E13" thru_hole circle
			(at 21.599906 -7.199884)
			(size 0.762 0.762)
			(drill 0.359918)
			(layers "*.Cu" "*.Mask")
			(remove_unused_layers no)
			(net "PHY_SCC_TO_DPB_24_DP")
			(clearance 0.1651)
			(thermal_gap 0.1651)
		)
		(pad "E14" thru_hole circle
			(at 23.400004 -5.999988)
			(size 0.762 0.762)
			(drill 0.359918)
			(layers "*.Cu" "*.Mask")
			(remove_unused_layers no)
			(net "PHY_SCC_TO_DPB_25_DP")
			(clearance 0.1651)
			(thermal_gap 0.1651)
		)
		(pad "E15" thru_hole circle
			(at 25.200102 -7.199884)
			(size 0.762 0.762)
			(drill 0.359918)
			(layers "*.Cu" "*.Mask")
			(remove_unused_layers no)
			(net "PHY_SCC_TO_DPB_26_DP")
			(clearance 0.1651)
			(thermal_gap 0.1651)
		)
		(pad "E16" thru_hole circle
			(at 26.999946 -5.999988)
			(size 0.762 0.762)
			(drill 0.359918)
			(layers "*.Cu" "*.Mask")
			(remove_unused_layers no)
			(net "PHY_SCC_TO_DPB_27_DP")
			(clearance 0.1651)
			(thermal_gap 0.1651)
		)
		(pad "E17" thru_hole circle
			(at 28.800044 -7.199884)
			(size 0.762 0.762)
			(drill 0.359918)
			(layers "*.Cu" "*.Mask")
			(remove_unused_layers no)
			(net "PHY_SCC_TO_DPB_32_DP")
			(clearance 0.1651)
			(thermal_gap 0.1651)
		)
		(pad "E18" thru_hole circle
			(at 30.599888 -5.999988)
			(size 0.762 0.762)
			(drill 0.359918)
			(layers "*.Cu" "*.Mask")
			(remove_unused_layers no)
			(net "PHY_SCC_TO_DPB_33_DP")
			(clearance 0.1651)
			(thermal_gap 0.1651)
		)
		(pad "E19" thru_hole circle
			(at 32.399986 -7.199884)
			(size 0.762 0.762)
			(drill 0.359918)
			(layers "*.Cu" "*.Mask")
			(remove_unused_layers no)
			(net "PHY_SCC_TO_DPB_34_DP")
			(clearance 0.1651)
			(thermal_gap 0.1651)
		)
		(pad "E20" thru_hole circle
			(at 34.200084 -5.999988)
			(size 0.762 0.762)
			(drill 0.359918)
			(layers "*.Cu" "*.Mask")
			(remove_unused_layers no)
			(net "PHY_SCC_TO_DPB_35_DP")
			(clearance 0.1651)
			(thermal_gap 0.1651)
		)
		(pad "E21" thru_hole circle
			(at 35.999928 -7.199884)
			(size 0.762 0.762)
			(drill 0.359918)
			(layers "*.Cu" "*.Mask")
			(remove_unused_layers no)
			(net "PHY_SCC_TO_DPB_36_DP")
			(clearance 0.1651)
			(thermal_gap 0.1651)
		)
		(pad "E22" thru_hole circle
			(at 37.800026 -5.999988)
			(size 0.762 0.762)
			(drill 0.359918)
			(layers "*.Cu" "*.Mask")
			(remove_unused_layers no)
			(net "PHY_SCC_TO_DPB_37_DP")
			(clearance 0.1651)
			(thermal_gap 0.1651)
		)
		(pad "E23" thru_hole circle
			(at 39.600124 -7.199884)
			(size 0.762 0.762)
			(drill 0.359918)
			(layers "*.Cu" "*.Mask")
			(remove_unused_layers no)
			(net "PHY_SCC_TO_DPB_38_DP")
			(clearance 0.1651)
			(thermal_gap 0.1651)
		)
		(pad "E24" thru_hole circle
			(at 41.399968 -5.999988)
			(size 0.762 0.762)
			(drill 0.359918)
			(layers "*.Cu" "*.Mask")
			(remove_unused_layers no)
			(net "PHY_SCC_TO_DPB_39_DP")
			(clearance 0.1651)
			(thermal_gap 0.1651)
		)
		(pad "E25" thru_hole circle
			(at 43.200066 -7.199884)
			(size 0.762 0.762)
			(drill 0.359918)
			(layers "*.Cu" "*.Mask")
			(remove_unused_layers no)
			(net "PHY_SCC_TO_DPB_28_DP")
			(clearance 0.1651)
			(thermal_gap 0.1651)
		)
		(pad "E26" thru_hole circle
			(at 44.99991 -5.999988)
			(size 0.762 0.762)
			(drill 0.359918)
			(layers "*.Cu" "*.Mask")
			(remove_unused_layers no)
			(net "PHY_SCC_TO_DPB_29_DP")
			(clearance 0.1651)
			(thermal_gap 0.1651)
		)
		(pad "E27" thru_hole circle
			(at 46.800008 -7.199884)
			(size 0.762 0.762)
			(drill 0.359918)
			(layers "*.Cu" "*.Mask")
			(remove_unused_layers no)
			(net "PHY_SCC_TO_DPB_30_DP")
			(clearance 0.1651)
			(thermal_gap 0.1651)
		)
		(pad "E28" thru_hole circle
			(at 48.600106 -5.999988)
			(size 0.762 0.762)
			(drill 0.359918)
			(layers "*.Cu" "*.Mask")
			(remove_unused_layers no)
			(net "PHY_SCC_TO_DPB_31_DP")
			(clearance 0.1651)
			(thermal_gap 0.1651)
		)
		(pad "E29" thru_hole circle
			(at 50.39995 -7.199884)
			(size 0.762 0.762)
			(drill 0.359918)
			(layers "*.Cu" "*.Mask")
			(remove_unused_layers no)
			(net "PHY_SCC_TO_DPB_0_DP")
			(clearance 0.1651)
			(thermal_gap 0.1651)
		)
		(pad "E30" thru_hole circle
			(at 52.200048 -5.999988)
			(size 0.762 0.762)
			(drill 0.359918)
			(layers "*.Cu" "*.Mask")
			(remove_unused_layers no)
			(net "PHY_SCC_TO_DPB_1_DP")
			(clearance 0.1651)
			(thermal_gap 0.1651)
		)
		(pad "E31" thru_hole circle
			(at 53.999892 -7.199884)
			(size 0.762 0.762)
			(drill 0.359918)
			(layers "*.Cu" "*.Mask")
			(remove_unused_layers no)
			(net "PHY_SCC_TO_DPB_2_DP")
			(clearance 0.1651)
			(thermal_gap 0.1651)
		)
		(pad "E32" thru_hole circle
			(at 55.79999 -5.999988)
			(size 0.762 0.762)
			(drill 0.359918)
			(layers "*.Cu" "*.Mask")
			(remove_unused_layers no)
			(net "PHY_SCC_TO_DPB_3_DP")
			(clearance 0.1651)
			(thermal_gap 0.1651)
		)
		(pad "E33" thru_hole circle
			(at 57.600088 -7.199884)
			(size 0.762 0.762)
			(drill 0.359918)
			(layers "*.Cu" "*.Mask")
			(remove_unused_layers no)
			(net "PHY_SCC_TO_DPB_4_DP")
			(clearance 0.1651)
			(thermal_gap 0.1651)
		)
		(pad "E34" thru_hole circle
			(at 59.399932 -5.999988)
			(size 0.762 0.762)
			(drill 0.359918)
			(layers "*.Cu" "*.Mask")
			(remove_unused_layers no)
			(net "PHY_SCC_TO_DPB_5_DP")
			(clearance 0.1651)
			(thermal_gap 0.1651)
		)
		(pad "E35" thru_hole circle
			(at 61.20003 -7.199884)
			(size 0.762 0.762)
			(drill 0.359918)
			(layers "*.Cu" "*.Mask")
			(remove_unused_layers no)
			(net "PHY_SCC_TO_DPB_6_DP")
			(clearance 0.1651)
			(thermal_gap 0.1651)
		)
		(pad "E36" thru_hole circle
			(at 62.999874 -5.999988)
			(size 0.762 0.762)
			(drill 0.359918)
			(layers "*.Cu" "*.Mask")
			(remove_unused_layers no)
			(net "PHY_SCC_TO_DPB_7_DP")
			(clearance 0.1651)
			(thermal_gap 0.1651)
		)
		(pad "F1" thru_hole circle
			(at 0 -8.599932)
			(size 0.762 0.762)
			(drill 0.359918)
			(layers "*.Cu" "*.Mask")
			(remove_unused_layers no)
			(net "PHY_SCC_TO_DPB_12_DN")
			(clearance 0.1651)
			(thermal_gap 0.1651)
		)
		(pad "F2" thru_hole circle
			(at 1.800098 -7.400036)
			(size 0.762 0.762)
			(drill 0.359918)
			(layers "*.Cu" "*.Mask")
			(remove_unused_layers no)
			(net "PHY_SCC_TO_DPB_13_DN")
			(clearance 0.1651)
			(thermal_gap 0.1651)
		)
		(pad "F3" thru_hole circle
			(at 3.599942 -8.599932)
			(size 0.762 0.762)
			(drill 0.359918)
			(layers "*.Cu" "*.Mask")
			(remove_unused_layers no)
			(net "PHY_SCC_TO_DPB_14_DN")
			(clearance 0.1651)
			(thermal_gap 0.1651)
		)
		(pad "F4" thru_hole circle
			(at 5.40004 -7.400036)
			(size 0.762 0.762)
			(drill 0.359918)
			(layers "*.Cu" "*.Mask")
			(remove_unused_layers no)
			(net "PHY_SCC_TO_DPB_15_DN")
			(clearance 0.1651)
			(thermal_gap 0.1651)
		)
		(pad "F5" thru_hole circle
			(at 7.199884 -8.599932)
			(size 0.762 0.762)
			(drill 0.359918)
			(layers "*.Cu" "*.Mask")
			(remove_unused_layers no)
			(net "PHY_SCC_TO_DPB_16_DN")
			(clearance 0.1651)
			(thermal_gap 0.1651)
		)
		(pad "F6" thru_hole circle
			(at 8.999982 -7.400036)
			(size 0.762 0.762)
			(drill 0.359918)
			(layers "*.Cu" "*.Mask")
			(remove_unused_layers no)
			(net "PHY_SCC_TO_DPB_17_DN")
			(clearance 0.1651)
			(thermal_gap 0.1651)
		)
		(pad "F7" thru_hole circle
			(at 10.80008 -8.599932)
			(size 0.762 0.762)
			(drill 0.359918)
			(layers "*.Cu" "*.Mask")
			(remove_unused_layers no)
			(net "PHY_SCC_TO_DPB_18_DN")
			(clearance 0.1651)
			(thermal_gap 0.1651)
		)
		(pad "F8" thru_hole circle
			(at 12.599924 -7.400036)
			(size 0.762 0.762)
			(drill 0.359918)
			(layers "*.Cu" "*.Mask")
			(remove_unused_layers no)
			(net "PHY_SCC_TO_DPB_19_DN")
			(clearance 0.1651)
			(thermal_gap 0.1651)
		)
		(pad "F9" thru_hole circle
			(at 14.400022 -8.599932)
			(size 0.762 0.762)
			(drill 0.359918)
			(layers "*.Cu" "*.Mask")
			(remove_unused_layers no)
			(net "PHY_SCC_TO_DPB_20_DN")
			(clearance 0.1651)
			(thermal_gap 0.1651)
		)
		(pad "F10" thru_hole circle
			(at 16.20012 -7.400036)
			(size 0.762 0.762)
			(drill 0.359918)
			(layers "*.Cu" "*.Mask")
			(remove_unused_layers no)
			(net "PHY_SCC_TO_DPB_21_DN")
			(clearance 0.1651)
			(thermal_gap 0.1651)
		)
		(pad "F11" thru_hole circle
			(at 17.999964 -8.599932)
			(size 0.762 0.762)
			(drill 0.359918)
			(layers "*.Cu" "*.Mask")
			(remove_unused_layers no)
			(net "PHY_SCC_TO_DPB_22_DN")
			(clearance 0.1651)
			(thermal_gap 0.1651)
		)
		(pad "F12" thru_hole circle
			(at 19.800062 -7.400036)
			(size 0.762 0.762)
			(drill 0.359918)
			(layers "*.Cu" "*.Mask")
			(remove_unused_layers no)
			(net "PHY_SCC_TO_DPB_23_DN")
			(clearance 0.1651)
			(thermal_gap 0.1651)
		)
		(pad "F13" thru_hole circle
			(at 21.599906 -8.599932)
			(size 0.762 0.762)
			(drill 0.359918)
			(layers "*.Cu" "*.Mask")
			(remove_unused_layers no)
			(net "PHY_SCC_TO_DPB_24_DN")
			(clearance 0.1651)
			(thermal_gap 0.1651)
		)
		(pad "F14" thru_hole circle
			(at 23.400004 -7.400036)
			(size 0.762 0.762)
			(drill 0.359918)
			(layers "*.Cu" "*.Mask")
			(remove_unused_layers no)
			(net "PHY_SCC_TO_DPB_25_DN")
			(clearance 0.1651)
			(thermal_gap 0.1651)
		)
		(pad "F15" thru_hole circle
			(at 25.200102 -8.599932)
			(size 0.762 0.762)
			(drill 0.359918)
			(layers "*.Cu" "*.Mask")
			(remove_unused_layers no)
			(net "PHY_SCC_TO_DPB_26_DN")
			(clearance 0.1651)
			(thermal_gap 0.1651)
		)
		(pad "F16" thru_hole circle
			(at 26.999946 -7.400036)
			(size 0.762 0.762)
			(drill 0.359918)
			(layers "*.Cu" "*.Mask")
			(remove_unused_layers no)
			(net "PHY_SCC_TO_DPB_27_DN")
			(clearance 0.1651)
			(thermal_gap 0.1651)
		)
		(pad "F17" thru_hole circle
			(at 28.800044 -8.599932)
			(size 0.762 0.762)
			(drill 0.359918)
			(layers "*.Cu" "*.Mask")
			(remove_unused_layers no)
			(net "PHY_SCC_TO_DPB_32_DN")
			(clearance 0.1651)
			(thermal_gap 0.1651)
		)
		(pad "F18" thru_hole circle
			(at 30.599888 -7.400036)
			(size 0.762 0.762)
			(drill 0.359918)
			(layers "*.Cu" "*.Mask")
			(remove_unused_layers no)
			(net "PHY_SCC_TO_DPB_33_DN")
			(clearance 0.1651)
			(thermal_gap 0.1651)
		)
		(pad "F19" thru_hole circle
			(at 32.399986 -8.599932)
			(size 0.762 0.762)
			(drill 0.359918)
			(layers "*.Cu" "*.Mask")
			(remove_unused_layers no)
			(net "PHY_SCC_TO_DPB_34_DN")
			(clearance 0.1651)
			(thermal_gap 0.1651)
		)
		(pad "F20" thru_hole circle
			(at 34.200084 -7.400036)
			(size 0.762 0.762)
			(drill 0.359918)
			(layers "*.Cu" "*.Mask")
			(remove_unused_layers no)
			(net "PHY_SCC_TO_DPB_35_DN")
			(clearance 0.1651)
			(thermal_gap 0.1651)
		)
		(pad "F21" thru_hole circle
			(at 35.999928 -8.599932)
			(size 0.762 0.762)
			(drill 0.359918)
			(layers "*.Cu" "*.Mask")
			(remove_unused_layers no)
			(net "PHY_SCC_TO_DPB_36_DN")
			(clearance 0.1651)
			(thermal_gap 0.1651)
		)
		(pad "F22" thru_hole circle
			(at 37.800026 -7.400036)
			(size 0.762 0.762)
			(drill 0.359918)
			(layers "*.Cu" "*.Mask")
			(remove_unused_layers no)
			(net "PHY_SCC_TO_DPB_37_DN")
			(clearance 0.1651)
			(thermal_gap 0.1651)
		)
		(pad "F23" thru_hole circle
			(at 39.600124 -8.599932)
			(size 0.762 0.762)
			(drill 0.359918)
			(layers "*.Cu" "*.Mask")
			(remove_unused_layers no)
			(net "PHY_SCC_TO_DPB_38_DN")
			(clearance 0.1651)
			(thermal_gap 0.1651)
		)
		(pad "F24" thru_hole circle
			(at 41.399968 -7.400036)
			(size 0.762 0.762)
			(drill 0.359918)
			(layers "*.Cu" "*.Mask")
			(remove_unused_layers no)
			(net "PHY_SCC_TO_DPB_39_DN")
			(clearance 0.1651)
			(thermal_gap 0.1651)
		)
		(pad "F25" thru_hole circle
			(at 43.200066 -8.599932)
			(size 0.762 0.762)
			(drill 0.359918)
			(layers "*.Cu" "*.Mask")
			(remove_unused_layers no)
			(net "PHY_SCC_TO_DPB_28_DN")
			(clearance 0.1651)
			(thermal_gap 0.1651)
		)
		(pad "F26" thru_hole circle
			(at 44.99991 -7.400036)
			(size 0.762 0.762)
			(drill 0.359918)
			(layers "*.Cu" "*.Mask")
			(remove_unused_layers no)
			(net "PHY_SCC_TO_DPB_29_DN")
			(clearance 0.1651)
			(thermal_gap 0.1651)
		)
		(pad "F27" thru_hole circle
			(at 46.800008 -8.599932)
			(size 0.762 0.762)
			(drill 0.359918)
			(layers "*.Cu" "*.Mask")
			(remove_unused_layers no)
			(net "PHY_SCC_TO_DPB_30_DN")
			(clearance 0.1651)
			(thermal_gap 0.1651)
		)
		(pad "F28" thru_hole circle
			(at 48.600106 -7.400036)
			(size 0.762 0.762)
			(drill 0.359918)
			(layers "*.Cu" "*.Mask")
			(remove_unused_layers no)
			(net "PHY_SCC_TO_DPB_31_DN")
			(clearance 0.1651)
			(thermal_gap 0.1651)
		)
		(pad "F29" thru_hole circle
			(at 50.39995 -8.599932)
			(size 0.762 0.762)
			(drill 0.359918)
			(layers "*.Cu" "*.Mask")
			(remove_unused_layers no)
			(net "PHY_SCC_TO_DPB_0_DN")
			(clearance 0.1651)
			(thermal_gap 0.1651)
		)
		(pad "F30" thru_hole circle
			(at 52.200048 -7.400036)
			(size 0.762 0.762)
			(drill 0.359918)
			(layers "*.Cu" "*.Mask")
			(remove_unused_layers no)
			(net "PHY_SCC_TO_DPB_1_DN")
			(clearance 0.1651)
			(thermal_gap 0.1651)
		)
		(pad "F31" thru_hole circle
			(at 53.999892 -8.599932)
			(size 0.762 0.762)
			(drill 0.359918)
			(layers "*.Cu" "*.Mask")
			(remove_unused_layers no)
			(net "PHY_SCC_TO_DPB_2_DN")
			(clearance 0.1651)
			(thermal_gap 0.1651)
		)
		(pad "F32" thru_hole circle
			(at 55.79999 -7.400036)
			(size 0.762 0.762)
			(drill 0.359918)
			(layers "*.Cu" "*.Mask")
			(remove_unused_layers no)
			(net "PHY_SCC_TO_DPB_3_DN")
			(clearance 0.1651)
			(thermal_gap 0.1651)
		)
		(pad "F33" thru_hole circle
			(at 57.600088 -8.599932)
			(size 0.762 0.762)
			(drill 0.359918)
			(layers "*.Cu" "*.Mask")
			(remove_unused_layers no)
			(net "PHY_SCC_TO_DPB_4_DN")
			(clearance 0.1651)
			(thermal_gap 0.1651)
		)
		(pad "F34" thru_hole circle
			(at 59.399932 -7.400036)
			(size 0.762 0.762)
			(drill 0.359918)
			(layers "*.Cu" "*.Mask")
			(remove_unused_layers no)
			(net "PHY_SCC_TO_DPB_5_DN")
			(clearance 0.1651)
			(thermal_gap 0.1651)
		)
		(pad "F35" thru_hole circle
			(at 61.20003 -8.599932)
			(size 0.762 0.762)
			(drill 0.359918)
			(layers "*.Cu" "*.Mask")
			(remove_unused_layers no)
			(net "PHY_SCC_TO_DPB_6_DN")
			(clearance 0.1651)
			(thermal_gap 0.1651)
		)
		(pad "F36" thru_hole circle
			(at 62.999874 -7.400036)
			(size 0.762 0.762)
			(drill 0.359918)
			(layers "*.Cu" "*.Mask")
			(remove_unused_layers no)
			(net "PHY_SCC_TO_DPB_7_DN")
			(clearance 0.1651)
			(thermal_gap 0.1651)
		)
		(pad "GND1" thru_hole circle
			(at 0 -2.500122)
			(size 0.762 0.762)
			(drill 0.359918)
			(layers "*.Cu" "*.Mask")
			(remove_unused_layers no)
			(net "GND")
			(clearance 0.1651)
			(thermal_gap 0.1651)
		)
		(pad "GND2" thru_hole circle
			(at 0 -6.100064)
			(size 0.762 0.762)
			(drill 0.359918)
			(layers "*.Cu" "*.Mask")
			(remove_unused_layers no)
			(net "GND")
			(clearance 0.1651)
			(thermal_gap 0.1651)
		)
		(pad "GND3" thru_hole circle
			(at 0 -9.700006)
			(size 0.762 0.762)
			(drill 0.359918)
			(layers "*.Cu" "*.Mask")
			(remove_unused_layers no)
			(net "GND")
			(clearance 0.1651)
			(thermal_gap 0.1651)
		)
		(pad "GND4" thru_hole circle
			(at 1.800098 2.29997)
			(size 0.762 0.762)
			(drill 0.359918)
			(layers "*.Cu" "*.Mask")
			(remove_unused_layers no)
			(net "GND")
			(clearance 0.1651)
			(thermal_gap 0.1651)
		)
		(pad "GND5" thru_hole circle
			(at 1.800098 -1.299972)
			(size 0.762 0.762)
			(drill 0.359918)
			(layers "*.Cu" "*.Mask")
			(remove_unused_layers no)
			(net "GND")
			(clearance 0.1651)
			(thermal_gap 0.1651)
		)
		(pad "GND6" thru_hole circle
			(at 1.800098 -4.899914)
			(size 0.762 0.762)
			(drill 0.359918)
			(layers "*.Cu" "*.Mask")
			(remove_unused_layers no)
			(net "GND")
			(clearance 0.1651)
			(thermal_gap 0.1651)
		)
		(pad "GND7" thru_hole circle
			(at 1.800098 -8.50011)
			(size 0.762 0.762)
			(drill 0.359918)
			(layers "*.Cu" "*.Mask")
			(remove_unused_layers no)
			(net "GND")
			(clearance 0.1651)
			(thermal_gap 0.1651)
		)
		(pad "GND8" thru_hole circle
			(at 3.599942 -2.500122)
			(size 0.762 0.762)
			(drill 0.359918)
			(layers "*.Cu" "*.Mask")
			(remove_unused_layers no)
			(net "GND")
			(clearance 0.1651)
			(thermal_gap 0.1651)
		)
		(pad "GND9" thru_hole circle
			(at 3.599942 -6.100064)
			(size 0.762 0.762)
			(drill 0.359918)
			(layers "*.Cu" "*.Mask")
			(remove_unused_layers no)
			(net "GND")
			(clearance 0.1651)
			(thermal_gap 0.1651)
		)
		(pad "GND10" thru_hole circle
			(at 3.599942 -9.700006)
			(size 0.762 0.762)
			(drill 0.359918)
			(layers "*.Cu" "*.Mask")
			(remove_unused_layers no)
			(net "GND")
			(clearance 0.1651)
			(thermal_gap 0.1651)
		)
		(pad "GND11" thru_hole circle
			(at 5.40004 2.29997)
			(size 0.762 0.762)
			(drill 0.359918)
			(layers "*.Cu" "*.Mask")
			(remove_unused_layers no)
			(net "GND")
			(clearance 0.1651)
			(thermal_gap 0.1651)
		)
		(pad "GND12" thru_hole circle
			(at 5.40004 -1.299972)
			(size 0.762 0.762)
			(drill 0.359918)
			(layers "*.Cu" "*.Mask")
			(remove_unused_layers no)
			(net "GND")
			(clearance 0.1651)
			(thermal_gap 0.1651)
		)
		(pad "GND13" thru_hole circle
			(at 5.40004 -4.899914)
			(size 0.762 0.762)
			(drill 0.359918)
			(layers "*.Cu" "*.Mask")
			(remove_unused_layers no)
			(net "GND")
			(clearance 0.1651)
			(thermal_gap 0.1651)
		)
		(pad "GND14" thru_hole circle
			(at 5.40004 -8.50011)
			(size 0.762 0.762)
			(drill 0.359918)
			(layers "*.Cu" "*.Mask")
			(remove_unused_layers no)
			(net "GND")
			(clearance 0.1651)
			(thermal_gap 0.1651)
		)
		(pad "GND15" thru_hole circle
			(at 7.199884 -2.500122)
			(size 0.762 0.762)
			(drill 0.359918)
			(layers "*.Cu" "*.Mask")
			(remove_unused_layers no)
			(net "GND")
			(clearance 0.1651)
			(thermal_gap 0.1651)
		)
		(pad "GND16" thru_hole circle
			(at 7.199884 -6.100064)
			(size 0.762 0.762)
			(drill 0.359918)
			(layers "*.Cu" "*.Mask")
			(remove_unused_layers no)
			(net "GND")
			(clearance 0.1651)
			(thermal_gap 0.1651)
		)
		(pad "GND17" thru_hole circle
			(at 7.199884 -9.700006)
			(size 0.762 0.762)
			(drill 0.359918)
			(layers "*.Cu" "*.Mask")
			(remove_unused_layers no)
			(net "GND")
			(clearance 0.1651)
			(thermal_gap 0.1651)
		)
		(pad "GND18" thru_hole circle
			(at 8.999982 2.29997)
			(size 0.762 0.762)
			(drill 0.359918)
			(layers "*.Cu" "*.Mask")
			(remove_unused_layers no)
			(net "GND")
			(clearance 0.1651)
			(thermal_gap 0.1651)
		)
		(pad "GND19" thru_hole circle
			(at 8.999982 -1.299972)
			(size 0.762 0.762)
			(drill 0.359918)
			(layers "*.Cu" "*.Mask")
			(remove_unused_layers no)
			(net "GND")
			(clearance 0.1651)
			(thermal_gap 0.1651)
		)
		(pad "GND20" thru_hole circle
			(at 8.999982 -4.899914)
			(size 0.762 0.762)
			(drill 0.359918)
			(layers "*.Cu" "*.Mask")
			(remove_unused_layers no)
			(net "GND")
			(clearance 0.1651)
			(thermal_gap 0.1651)
		)
		(pad "GND21" thru_hole circle
			(at 8.999982 -8.50011)
			(size 0.762 0.762)
			(drill 0.359918)
			(layers "*.Cu" "*.Mask")
			(remove_unused_layers no)
			(net "GND")
			(clearance 0.1651)
			(thermal_gap 0.1651)
		)
		(pad "GND22" thru_hole circle
			(at 10.80008 -2.500122)
			(size 0.762 0.762)
			(drill 0.359918)
			(layers "*.Cu" "*.Mask")
			(remove_unused_layers no)
			(net "GND")
			(clearance 0.1651)
			(thermal_gap 0.1651)
		)
		(pad "GND23" thru_hole circle
			(at 10.80008 -6.100064)
			(size 0.762 0.762)
			(drill 0.359918)
			(layers "*.Cu" "*.Mask")
			(remove_unused_layers no)
			(net "GND")
			(clearance 0.1651)
			(thermal_gap 0.1651)
		)
		(pad "GND24" thru_hole circle
			(at 10.80008 -9.700006)
			(size 0.762 0.762)
			(drill 0.359918)
			(layers "*.Cu" "*.Mask")
			(remove_unused_layers no)
			(net "GND")
			(clearance 0.1651)
			(thermal_gap 0.1651)
		)
		(pad "GND25" thru_hole circle
			(at 12.599924 2.29997)
			(size 0.762 0.762)
			(drill 0.359918)
			(layers "*.Cu" "*.Mask")
			(remove_unused_layers no)
			(net "GND")
			(clearance 0.1651)
			(thermal_gap 0.1651)
		)
		(pad "GND26" thru_hole circle
			(at 12.599924 -1.299972)
			(size 0.762 0.762)
			(drill 0.359918)
			(layers "*.Cu" "*.Mask")
			(remove_unused_layers no)
			(net "GND")
			(clearance 0.1651)
			(thermal_gap 0.1651)
		)
		(pad "GND27" thru_hole circle
			(at 12.599924 -4.899914)
			(size 0.762 0.762)
			(drill 0.359918)
			(layers "*.Cu" "*.Mask")
			(remove_unused_layers no)
			(net "GND")
			(clearance 0.1651)
			(thermal_gap 0.1651)
		)
		(pad "GND28" thru_hole circle
			(at 12.599924 -8.50011)
			(size 0.762 0.762)
			(drill 0.359918)
			(layers "*.Cu" "*.Mask")
			(remove_unused_layers no)
			(net "GND")
			(clearance 0.1651)
			(thermal_gap 0.1651)
		)
		(pad "GND29" thru_hole circle
			(at 14.400022 -2.500122)
			(size 0.762 0.762)
			(drill 0.359918)
			(layers "*.Cu" "*.Mask")
			(remove_unused_layers no)
			(net "GND")
			(clearance 0.1651)
			(thermal_gap 0.1651)
		)
		(pad "GND30" thru_hole circle
			(at 14.400022 -6.100064)
			(size 0.762 0.762)
			(drill 0.359918)
			(layers "*.Cu" "*.Mask")
			(remove_unused_layers no)
			(net "GND")
			(clearance 0.1651)
			(thermal_gap 0.1651)
		)
		(pad "GND31" thru_hole circle
			(at 14.400022 -9.700006)
			(size 0.762 0.762)
			(drill 0.359918)
			(layers "*.Cu" "*.Mask")
			(remove_unused_layers no)
			(net "GND")
			(clearance 0.1651)
			(thermal_gap 0.1651)
		)
		(pad "GND32" thru_hole circle
			(at 16.20012 2.29997)
			(size 0.762 0.762)
			(drill 0.359918)
			(layers "*.Cu" "*.Mask")
			(remove_unused_layers no)
			(net "GND")
			(clearance 0.1651)
			(thermal_gap 0.1651)
		)
		(pad "GND33" thru_hole circle
			(at 16.20012 -1.299972)
			(size 0.762 0.762)
			(drill 0.359918)
			(layers "*.Cu" "*.Mask")
			(remove_unused_layers no)
			(net "GND")
			(clearance 0.1651)
			(thermal_gap 0.1651)
		)
		(pad "GND34" thru_hole circle
			(at 16.20012 -4.899914)
			(size 0.762 0.762)
			(drill 0.359918)
			(layers "*.Cu" "*.Mask")
			(remove_unused_layers no)
			(net "GND")
			(clearance 0.1651)
			(thermal_gap 0.1651)
		)
		(pad "GND35" thru_hole circle
			(at 16.20012 -8.50011)
			(size 0.762 0.762)
			(drill 0.359918)
			(layers "*.Cu" "*.Mask")
			(remove_unused_layers no)
			(net "GND")
			(clearance 0.1651)
			(thermal_gap 0.1651)
		)
		(pad "GND36" thru_hole circle
			(at 17.999964 -2.500122)
			(size 0.762 0.762)
			(drill 0.359918)
			(layers "*.Cu" "*.Mask")
			(remove_unused_layers no)
			(net "GND")
			(clearance 0.1651)
			(thermal_gap 0.1651)
		)
		(pad "GND37" thru_hole circle
			(at 17.999964 -6.100064)
			(size 0.762 0.762)
			(drill 0.359918)
			(layers "*.Cu" "*.Mask")
			(remove_unused_layers no)
			(net "GND")
			(clearance 0.1651)
			(thermal_gap 0.1651)
		)
		(pad "GND38" thru_hole circle
			(at 17.999964 -9.700006)
			(size 0.762 0.762)
			(drill 0.359918)
			(layers "*.Cu" "*.Mask")
			(remove_unused_layers no)
			(net "GND")
			(clearance 0.1651)
			(thermal_gap 0.1651)
		)
		(pad "GND39" thru_hole circle
			(at 19.800062 2.29997)
			(size 0.762 0.762)
			(drill 0.359918)
			(layers "*.Cu" "*.Mask")
			(remove_unused_layers no)
			(net "GND")
			(clearance 0.1651)
			(thermal_gap 0.1651)
		)
		(pad "GND40" thru_hole circle
			(at 19.800062 -1.299972)
			(size 0.762 0.762)
			(drill 0.359918)
			(layers "*.Cu" "*.Mask")
			(remove_unused_layers no)
			(net "GND")
			(clearance 0.1651)
			(thermal_gap 0.1651)
		)
		(pad "GND41" thru_hole circle
			(at 19.800062 -4.899914)
			(size 0.762 0.762)
			(drill 0.359918)
			(layers "*.Cu" "*.Mask")
			(remove_unused_layers no)
			(net "GND")
			(clearance 0.1651)
			(thermal_gap 0.1651)
		)
		(pad "GND42" thru_hole circle
			(at 19.800062 -8.50011)
			(size 0.762 0.762)
			(drill 0.359918)
			(layers "*.Cu" "*.Mask")
			(remove_unused_layers no)
			(net "GND")
			(clearance 0.1651)
			(thermal_gap 0.1651)
		)
		(pad "GND43" thru_hole circle
			(at 21.599906 -2.500122)
			(size 0.762 0.762)
			(drill 0.359918)
			(layers "*.Cu" "*.Mask")
			(remove_unused_layers no)
			(net "GND")
			(clearance 0.1651)
			(thermal_gap 0.1651)
		)
		(pad "GND44" thru_hole circle
			(at 21.599906 -6.100064)
			(size 0.762 0.762)
			(drill 0.359918)
			(layers "*.Cu" "*.Mask")
			(remove_unused_layers no)
			(net "GND")
			(clearance 0.1651)
			(thermal_gap 0.1651)
		)
		(pad "GND45" thru_hole circle
			(at 21.599906 -9.700006)
			(size 0.762 0.762)
			(drill 0.359918)
			(layers "*.Cu" "*.Mask")
			(remove_unused_layers no)
			(net "GND")
			(clearance 0.1651)
			(thermal_gap 0.1651)
		)
		(pad "GND46" thru_hole circle
			(at 23.400004 2.29997)
			(size 0.762 0.762)
			(drill 0.359918)
			(layers "*.Cu" "*.Mask")
			(remove_unused_layers no)
			(net "GND")
			(clearance 0.1651)
			(thermal_gap 0.1651)
		)
		(pad "GND47" thru_hole circle
			(at 23.400004 -1.299972)
			(size 0.762 0.762)
			(drill 0.359918)
			(layers "*.Cu" "*.Mask")
			(remove_unused_layers no)
			(net "GND")
			(clearance 0.1651)
			(thermal_gap 0.1651)
		)
		(pad "GND48" thru_hole circle
			(at 23.400004 -4.899914)
			(size 0.762 0.762)
			(drill 0.359918)
			(layers "*.Cu" "*.Mask")
			(remove_unused_layers no)
			(net "GND")
			(clearance 0.1651)
			(thermal_gap 0.1651)
		)
		(pad "GND49" thru_hole circle
			(at 23.400004 -8.50011)
			(size 0.762 0.762)
			(drill 0.359918)
			(layers "*.Cu" "*.Mask")
			(remove_unused_layers no)
			(net "GND")
			(clearance 0.1651)
			(thermal_gap 0.1651)
		)
		(pad "GND50" thru_hole circle
			(at 25.200102 -2.500122)
			(size 0.762 0.762)
			(drill 0.359918)
			(layers "*.Cu" "*.Mask")
			(remove_unused_layers no)
			(net "GND")
			(clearance 0.1651)
			(thermal_gap 0.1651)
		)
		(pad "GND51" thru_hole circle
			(at 25.200102 -6.100064)
			(size 0.762 0.762)
			(drill 0.359918)
			(layers "*.Cu" "*.Mask")
			(remove_unused_layers no)
			(net "GND")
			(clearance 0.1651)
			(thermal_gap 0.1651)
		)
		(pad "GND52" thru_hole circle
			(at 25.200102 -9.700006)
			(size 0.762 0.762)
			(drill 0.359918)
			(layers "*.Cu" "*.Mask")
			(remove_unused_layers no)
			(net "GND")
			(clearance 0.1651)
			(thermal_gap 0.1651)
		)
		(pad "GND53" thru_hole circle
			(at 26.999946 2.29997)
			(size 0.762 0.762)
			(drill 0.359918)
			(layers "*.Cu" "*.Mask")
			(remove_unused_layers no)
			(net "GND")
			(clearance 0.1651)
			(thermal_gap 0.1651)
		)
		(pad "GND54" thru_hole circle
			(at 26.999946 -1.299972)
			(size 0.762 0.762)
			(drill 0.359918)
			(layers "*.Cu" "*.Mask")
			(remove_unused_layers no)
			(net "GND")
			(clearance 0.1651)
			(thermal_gap 0.1651)
		)
		(pad "GND55" thru_hole circle
			(at 26.999946 -4.899914)
			(size 0.762 0.762)
			(drill 0.359918)
			(layers "*.Cu" "*.Mask")
			(remove_unused_layers no)
			(net "GND")
			(clearance 0.1651)
			(thermal_gap 0.1651)
		)
		(pad "GND56" thru_hole circle
			(at 26.999946 -8.50011)
			(size 0.762 0.762)
			(drill 0.359918)
			(layers "*.Cu" "*.Mask")
			(remove_unused_layers no)
			(net "GND")
			(clearance 0.1651)
			(thermal_gap 0.1651)
		)
		(pad "GND57" thru_hole circle
			(at 28.800044 -2.500122)
			(size 0.762 0.762)
			(drill 0.359918)
			(layers "*.Cu" "*.Mask")
			(remove_unused_layers no)
			(net "GND")
			(clearance 0.1651)
			(thermal_gap 0.1651)
		)
		(pad "GND58" thru_hole circle
			(at 28.800044 -6.100064)
			(size 0.762 0.762)
			(drill 0.359918)
			(layers "*.Cu" "*.Mask")
			(remove_unused_layers no)
			(net "GND")
			(clearance 0.1651)
			(thermal_gap 0.1651)
		)
		(pad "GND59" thru_hole circle
			(at 28.800044 -9.700006)
			(size 0.762 0.762)
			(drill 0.359918)
			(layers "*.Cu" "*.Mask")
			(remove_unused_layers no)
			(net "GND")
			(clearance 0.1651)
			(thermal_gap 0.1651)
		)
		(pad "GND60" thru_hole circle
			(at 30.599888 2.29997)
			(size 0.762 0.762)
			(drill 0.359918)
			(layers "*.Cu" "*.Mask")
			(remove_unused_layers no)
			(net "GND")
			(clearance 0.1651)
			(thermal_gap 0.1651)
		)
		(pad "GND61" thru_hole circle
			(at 30.599888 -1.299972)
			(size 0.762 0.762)
			(drill 0.359918)
			(layers "*.Cu" "*.Mask")
			(remove_unused_layers no)
			(net "GND")
			(clearance 0.1651)
			(thermal_gap 0.1651)
		)
		(pad "GND62" thru_hole circle
			(at 30.599888 -4.899914)
			(size 0.762 0.762)
			(drill 0.359918)
			(layers "*.Cu" "*.Mask")
			(remove_unused_layers no)
			(net "GND")
			(clearance 0.1651)
			(thermal_gap 0.1651)
		)
		(pad "GND63" thru_hole circle
			(at 30.599888 -8.50011)
			(size 0.762 0.762)
			(drill 0.359918)
			(layers "*.Cu" "*.Mask")
			(remove_unused_layers no)
			(net "GND")
			(clearance 0.1651)
			(thermal_gap 0.1651)
		)
		(pad "GND64" thru_hole circle
			(at 32.399986 -2.500122)
			(size 0.762 0.762)
			(drill 0.359918)
			(layers "*.Cu" "*.Mask")
			(remove_unused_layers no)
			(net "GND")
			(clearance 0.1651)
			(thermal_gap 0.1651)
		)
		(pad "GND65" thru_hole circle
			(at 32.399986 -6.100064)
			(size 0.762 0.762)
			(drill 0.359918)
			(layers "*.Cu" "*.Mask")
			(remove_unused_layers no)
			(net "GND")
			(clearance 0.1651)
			(thermal_gap 0.1651)
		)
		(pad "GND66" thru_hole circle
			(at 32.399986 -9.700006)
			(size 0.762 0.762)
			(drill 0.359918)
			(layers "*.Cu" "*.Mask")
			(remove_unused_layers no)
			(net "GND")
			(clearance 0.1651)
			(thermal_gap 0.1651)
		)
		(pad "GND67" thru_hole circle
			(at 34.200084 2.29997)
			(size 0.762 0.762)
			(drill 0.359918)
			(layers "*.Cu" "*.Mask")
			(remove_unused_layers no)
			(net "GND")
			(clearance 0.1651)
			(thermal_gap 0.1651)
		)
		(pad "GND68" thru_hole circle
			(at 34.200084 -1.299972)
			(size 0.762 0.762)
			(drill 0.359918)
			(layers "*.Cu" "*.Mask")
			(remove_unused_layers no)
			(net "GND")
			(clearance 0.1651)
			(thermal_gap 0.1651)
		)
		(pad "GND69" thru_hole circle
			(at 34.200084 -4.899914)
			(size 0.762 0.762)
			(drill 0.359918)
			(layers "*.Cu" "*.Mask")
			(remove_unused_layers no)
			(net "GND")
			(clearance 0.1651)
			(thermal_gap 0.1651)
		)
		(pad "GND70" thru_hole circle
			(at 34.200084 -8.50011)
			(size 0.762 0.762)
			(drill 0.359918)
			(layers "*.Cu" "*.Mask")
			(remove_unused_layers no)
			(net "GND")
			(clearance 0.1651)
			(thermal_gap 0.1651)
		)
		(pad "GND71" thru_hole circle
			(at 35.999928 -2.500122)
			(size 0.762 0.762)
			(drill 0.359918)
			(layers "*.Cu" "*.Mask")
			(remove_unused_layers no)
			(net "GND")
			(clearance 0.1651)
			(thermal_gap 0.1651)
		)
		(pad "GND72" thru_hole circle
			(at 35.999928 -6.100064)
			(size 0.762 0.762)
			(drill 0.359918)
			(layers "*.Cu" "*.Mask")
			(remove_unused_layers no)
			(net "GND")
			(clearance 0.1651)
			(thermal_gap 0.1651)
		)
		(pad "GND73" thru_hole circle
			(at 35.999928 -9.700006)
			(size 0.762 0.762)
			(drill 0.359918)
			(layers "*.Cu" "*.Mask")
			(remove_unused_layers no)
			(net "GND")
			(clearance 0.1651)
			(thermal_gap 0.1651)
		)
		(pad "GND74" thru_hole circle
			(at 37.800026 2.29997)
			(size 0.762 0.762)
			(drill 0.359918)
			(layers "*.Cu" "*.Mask")
			(remove_unused_layers no)
			(net "GND")
			(clearance 0.1651)
			(thermal_gap 0.1651)
		)
		(pad "GND75" thru_hole circle
			(at 37.800026 -1.299972)
			(size 0.762 0.762)
			(drill 0.359918)
			(layers "*.Cu" "*.Mask")
			(remove_unused_layers no)
			(net "GND")
			(clearance 0.1651)
			(thermal_gap 0.1651)
		)
		(pad "GND76" thru_hole circle
			(at 37.800026 -4.899914)
			(size 0.762 0.762)
			(drill 0.359918)
			(layers "*.Cu" "*.Mask")
			(remove_unused_layers no)
			(net "GND")
			(clearance 0.1651)
			(thermal_gap 0.1651)
		)
		(pad "GND77" thru_hole circle
			(at 37.800026 -8.50011)
			(size 0.762 0.762)
			(drill 0.359918)
			(layers "*.Cu" "*.Mask")
			(remove_unused_layers no)
			(net "GND")
			(clearance 0.1651)
			(thermal_gap 0.1651)
		)
		(pad "GND78" thru_hole circle
			(at 39.600124 -2.500122)
			(size 0.762 0.762)
			(drill 0.359918)
			(layers "*.Cu" "*.Mask")
			(remove_unused_layers no)
			(net "GND")
			(clearance 0.1651)
			(thermal_gap 0.1651)
		)
		(pad "GND79" thru_hole circle
			(at 39.600124 -6.100064)
			(size 0.762 0.762)
			(drill 0.359918)
			(layers "*.Cu" "*.Mask")
			(remove_unused_layers no)
			(net "GND")
			(clearance 0.1651)
			(thermal_gap 0.1651)
		)
		(pad "GND80" thru_hole circle
			(at 39.600124 -9.700006)
			(size 0.762 0.762)
			(drill 0.359918)
			(layers "*.Cu" "*.Mask")
			(remove_unused_layers no)
			(net "GND")
			(clearance 0.1651)
			(thermal_gap 0.1651)
		)
		(pad "GND81" thru_hole circle
			(at 41.399968 2.29997)
			(size 0.762 0.762)
			(drill 0.359918)
			(layers "*.Cu" "*.Mask")
			(remove_unused_layers no)
			(net "GND")
			(clearance 0.1651)
			(thermal_gap 0.1651)
		)
		(pad "GND82" thru_hole circle
			(at 41.399968 -1.299972)
			(size 0.762 0.762)
			(drill 0.359918)
			(layers "*.Cu" "*.Mask")
			(remove_unused_layers no)
			(net "GND")
			(clearance 0.1651)
			(thermal_gap 0.1651)
		)
		(pad "GND83" thru_hole circle
			(at 41.399968 -4.899914)
			(size 0.762 0.762)
			(drill 0.359918)
			(layers "*.Cu" "*.Mask")
			(remove_unused_layers no)
			(net "GND")
			(clearance 0.1651)
			(thermal_gap 0.1651)
		)
		(pad "GND84" thru_hole circle
			(at 41.399968 -8.50011)
			(size 0.762 0.762)
			(drill 0.359918)
			(layers "*.Cu" "*.Mask")
			(remove_unused_layers no)
			(net "GND")
			(clearance 0.1651)
			(thermal_gap 0.1651)
		)
		(pad "GND85" thru_hole circle
			(at 43.200066 -2.500122)
			(size 0.762 0.762)
			(drill 0.359918)
			(layers "*.Cu" "*.Mask")
			(remove_unused_layers no)
			(net "GND")
			(clearance 0.1651)
			(thermal_gap 0.1651)
		)
		(pad "GND86" thru_hole circle
			(at 43.200066 -6.100064)
			(size 0.762 0.762)
			(drill 0.359918)
			(layers "*.Cu" "*.Mask")
			(remove_unused_layers no)
			(net "GND")
			(clearance 0.1651)
			(thermal_gap 0.1651)
		)
		(pad "GND87" thru_hole circle
			(at 43.200066 -9.700006)
			(size 0.762 0.762)
			(drill 0.359918)
			(layers "*.Cu" "*.Mask")
			(remove_unused_layers no)
			(net "GND")
			(clearance 0.1651)
			(thermal_gap 0.1651)
		)
		(pad "GND88" thru_hole circle
			(at 44.99991 2.29997)
			(size 0.762 0.762)
			(drill 0.359918)
			(layers "*.Cu" "*.Mask")
			(remove_unused_layers no)
			(net "GND")
			(clearance 0.1651)
			(thermal_gap 0.1651)
		)
		(pad "GND89" thru_hole circle
			(at 44.99991 -1.299972)
			(size 0.762 0.762)
			(drill 0.359918)
			(layers "*.Cu" "*.Mask")
			(remove_unused_layers no)
			(net "GND")
			(clearance 0.1651)
			(thermal_gap 0.1651)
		)
		(pad "GND90" thru_hole circle
			(at 44.99991 -4.899914)
			(size 0.762 0.762)
			(drill 0.359918)
			(layers "*.Cu" "*.Mask")
			(remove_unused_layers no)
			(net "GND")
			(clearance 0.1651)
			(thermal_gap 0.1651)
		)
		(pad "GND91" thru_hole circle
			(at 44.99991 -8.50011)
			(size 0.762 0.762)
			(drill 0.359918)
			(layers "*.Cu" "*.Mask")
			(remove_unused_layers no)
			(net "GND")
			(clearance 0.1651)
			(thermal_gap 0.1651)
		)
		(pad "GND92" thru_hole circle
			(at 46.800008 -2.500122)
			(size 0.762 0.762)
			(drill 0.359918)
			(layers "*.Cu" "*.Mask")
			(remove_unused_layers no)
			(net "GND")
			(clearance 0.1651)
			(thermal_gap 0.1651)
		)
		(pad "GND93" thru_hole circle
			(at 46.800008 -6.100064)
			(size 0.762 0.762)
			(drill 0.359918)
			(layers "*.Cu" "*.Mask")
			(remove_unused_layers no)
			(net "GND")
			(clearance 0.1651)
			(thermal_gap 0.1651)
		)
		(pad "GND94" thru_hole circle
			(at 46.800008 -9.700006)
			(size 0.762 0.762)
			(drill 0.359918)
			(layers "*.Cu" "*.Mask")
			(remove_unused_layers no)
			(net "GND")
			(clearance 0.1651)
			(thermal_gap 0.1651)
		)
		(pad "GND95" thru_hole circle
			(at 48.600106 2.29997)
			(size 0.762 0.762)
			(drill 0.359918)
			(layers "*.Cu" "*.Mask")
			(remove_unused_layers no)
			(net "GND")
			(clearance 0.1651)
			(thermal_gap 0.1651)
		)
		(pad "GND96" thru_hole circle
			(at 48.600106 -1.299972)
			(size 0.762 0.762)
			(drill 0.359918)
			(layers "*.Cu" "*.Mask")
			(remove_unused_layers no)
			(net "GND")
			(clearance 0.1651)
			(thermal_gap 0.1651)
		)
		(pad "GND97" thru_hole circle
			(at 48.600106 -4.899914)
			(size 0.762 0.762)
			(drill 0.359918)
			(layers "*.Cu" "*.Mask")
			(remove_unused_layers no)
			(net "GND")
			(clearance 0.1651)
			(thermal_gap 0.1651)
		)
		(pad "GND98" thru_hole circle
			(at 48.600106 -8.50011)
			(size 0.762 0.762)
			(drill 0.359918)
			(layers "*.Cu" "*.Mask")
			(remove_unused_layers no)
			(net "GND")
			(clearance 0.1651)
			(thermal_gap 0.1651)
		)
		(pad "GND99" thru_hole circle
			(at 50.39995 -2.500122)
			(size 0.762 0.762)
			(drill 0.359918)
			(layers "*.Cu" "*.Mask")
			(remove_unused_layers no)
			(net "GND")
			(clearance 0.1651)
			(thermal_gap 0.1651)
		)
		(pad "GND100" thru_hole circle
			(at 50.39995 -6.100064)
			(size 0.762 0.762)
			(drill 0.359918)
			(layers "*.Cu" "*.Mask")
			(remove_unused_layers no)
			(net "GND")
			(clearance 0.1651)
			(thermal_gap 0.1651)
		)
		(pad "GND101" thru_hole circle
			(at 50.39995 -9.700006)
			(size 0.762 0.762)
			(drill 0.359918)
			(layers "*.Cu" "*.Mask")
			(remove_unused_layers no)
			(net "GND")
			(clearance 0.1651)
			(thermal_gap 0.1651)
		)
		(pad "GND102" thru_hole circle
			(at 52.200048 2.29997)
			(size 0.762 0.762)
			(drill 0.359918)
			(layers "*.Cu" "*.Mask")
			(remove_unused_layers no)
			(net "GND")
			(clearance 0.1651)
			(thermal_gap 0.1651)
		)
		(pad "GND103" thru_hole circle
			(at 52.200048 -1.299972)
			(size 0.762 0.762)
			(drill 0.359918)
			(layers "*.Cu" "*.Mask")
			(remove_unused_layers no)
			(net "GND")
			(clearance 0.1651)
			(thermal_gap 0.1651)
		)
		(pad "GND104" thru_hole circle
			(at 52.200048 -4.899914)
			(size 0.762 0.762)
			(drill 0.359918)
			(layers "*.Cu" "*.Mask")
			(remove_unused_layers no)
			(net "GND")
			(clearance 0.1651)
			(thermal_gap 0.1651)
		)
		(pad "GND105" thru_hole circle
			(at 52.200048 -8.50011)
			(size 0.762 0.762)
			(drill 0.359918)
			(layers "*.Cu" "*.Mask")
			(remove_unused_layers no)
			(net "GND")
			(clearance 0.1651)
			(thermal_gap 0.1651)
		)
		(pad "GND106" thru_hole circle
			(at 53.999892 -2.500122)
			(size 0.762 0.762)
			(drill 0.359918)
			(layers "*.Cu" "*.Mask")
			(remove_unused_layers no)
			(net "GND")
			(clearance 0.1651)
			(thermal_gap 0.1651)
		)
		(pad "GND107" thru_hole circle
			(at 53.999892 -6.100064)
			(size 0.762 0.762)
			(drill 0.359918)
			(layers "*.Cu" "*.Mask")
			(remove_unused_layers no)
			(net "GND")
			(clearance 0.1651)
			(thermal_gap 0.1651)
		)
		(pad "GND108" thru_hole circle
			(at 53.999892 -9.700006)
			(size 0.762 0.762)
			(drill 0.359918)
			(layers "*.Cu" "*.Mask")
			(remove_unused_layers no)
			(net "GND")
			(clearance 0.1651)
			(thermal_gap 0.1651)
		)
		(pad "GND109" thru_hole circle
			(at 55.79999 2.29997)
			(size 0.762 0.762)
			(drill 0.359918)
			(layers "*.Cu" "*.Mask")
			(remove_unused_layers no)
			(net "GND")
			(clearance 0.1651)
			(thermal_gap 0.1651)
		)
		(pad "GND110" thru_hole circle
			(at 55.79999 -1.299972)
			(size 0.762 0.762)
			(drill 0.359918)
			(layers "*.Cu" "*.Mask")
			(remove_unused_layers no)
			(net "GND")
			(clearance 0.1651)
			(thermal_gap 0.1651)
		)
		(pad "GND111" thru_hole circle
			(at 55.79999 -4.899914)
			(size 0.762 0.762)
			(drill 0.359918)
			(layers "*.Cu" "*.Mask")
			(remove_unused_layers no)
			(net "GND")
			(clearance 0.1651)
			(thermal_gap 0.1651)
		)
		(pad "GND112" thru_hole circle
			(at 55.79999 -8.50011)
			(size 0.762 0.762)
			(drill 0.359918)
			(layers "*.Cu" "*.Mask")
			(remove_unused_layers no)
			(net "GND")
			(clearance 0.1651)
			(thermal_gap 0.1651)
		)
		(pad "GND113" thru_hole circle
			(at 57.600088 -2.500122)
			(size 0.762 0.762)
			(drill 0.359918)
			(layers "*.Cu" "*.Mask")
			(remove_unused_layers no)
			(net "GND")
			(clearance 0.1651)
			(thermal_gap 0.1651)
		)
		(pad "GND114" thru_hole circle
			(at 57.600088 -6.100064)
			(size 0.762 0.762)
			(drill 0.359918)
			(layers "*.Cu" "*.Mask")
			(remove_unused_layers no)
			(net "GND")
			(clearance 0.1651)
			(thermal_gap 0.1651)
		)
		(pad "GND115" thru_hole circle
			(at 57.600088 -9.700006)
			(size 0.762 0.762)
			(drill 0.359918)
			(layers "*.Cu" "*.Mask")
			(remove_unused_layers no)
			(net "GND")
			(clearance 0.1651)
			(thermal_gap 0.1651)
		)
		(pad "GND116" thru_hole circle
			(at 59.399932 2.29997)
			(size 0.762 0.762)
			(drill 0.359918)
			(layers "*.Cu" "*.Mask")
			(remove_unused_layers no)
			(net "GND")
			(clearance 0.1651)
			(thermal_gap 0.1651)
		)
		(pad "GND117" thru_hole circle
			(at 59.399932 -1.299972)
			(size 0.762 0.762)
			(drill 0.359918)
			(layers "*.Cu" "*.Mask")
			(remove_unused_layers no)
			(net "GND")
			(clearance 0.1651)
			(thermal_gap 0.1651)
		)
		(pad "GND118" thru_hole circle
			(at 59.399932 -4.899914)
			(size 0.762 0.762)
			(drill 0.359918)
			(layers "*.Cu" "*.Mask")
			(remove_unused_layers no)
			(net "GND")
			(clearance 0.1651)
			(thermal_gap 0.1651)
		)
		(pad "GND119" thru_hole circle
			(at 59.399932 -8.50011)
			(size 0.762 0.762)
			(drill 0.359918)
			(layers "*.Cu" "*.Mask")
			(remove_unused_layers no)
			(net "GND")
			(clearance 0.1651)
			(thermal_gap 0.1651)
		)
		(pad "GND120" thru_hole circle
			(at 61.20003 -2.500122)
			(size 0.762 0.762)
			(drill 0.359918)
			(layers "*.Cu" "*.Mask")
			(remove_unused_layers no)
			(net "GND")
			(clearance 0.1651)
			(thermal_gap 0.1651)
		)
		(pad "GND121" thru_hole circle
			(at 61.20003 -6.100064)
			(size 0.762 0.762)
			(drill 0.359918)
			(layers "*.Cu" "*.Mask")
			(remove_unused_layers no)
			(net "GND")
			(clearance 0.1651)
			(thermal_gap 0.1651)
		)
		(pad "GND122" thru_hole circle
			(at 61.20003 -9.700006)
			(size 0.762 0.762)
			(drill 0.359918)
			(layers "*.Cu" "*.Mask")
			(remove_unused_layers no)
			(net "GND")
			(clearance 0.1651)
			(thermal_gap 0.1651)
		)
		(pad "GND123" thru_hole circle
			(at 62.999874 2.29997)
			(size 0.762 0.762)
			(drill 0.359918)
			(layers "*.Cu" "*.Mask")
			(remove_unused_layers no)
			(net "GND")
			(clearance 0.1651)
			(thermal_gap 0.1651)
		)
		(pad "GND124" thru_hole circle
			(at 62.999874 -1.299972)
			(size 0.762 0.762)
			(drill 0.359918)
			(layers "*.Cu" "*.Mask")
			(remove_unused_layers no)
			(net "GND")
			(clearance 0.1651)
			(thermal_gap 0.1651)
		)
		(pad "GND125" thru_hole circle
			(at 62.999874 -4.899914)
			(size 0.762 0.762)
			(drill 0.359918)
			(layers "*.Cu" "*.Mask")
			(remove_unused_layers no)
			(net "GND")
			(clearance 0.1651)
			(thermal_gap 0.1651)
		)
		(pad "GND126" thru_hole circle
			(at 62.999874 -8.50011)
			(size 0.762 0.762)
			(drill 0.359918)
			(layers "*.Cu" "*.Mask")
			(remove_unused_layers no)
			(net "GND")
			(clearance 0.1651)
			(thermal_gap 0.1651)
		)
	)
	(footprint ""
		(layer "F.Cu")
		(at 176.6824 -59.817 180)
		(property "Reference" "R269"
			(at 0 0 180)
			(layer "F.SilkS")
			(hide yes)
			(effects
				(font
					(size 1.27 1.27)
				)
			)
		)
		(property "Value" "10KR2F-2-GP"
			(at 0.064008 -3.993896 180)
			(unlocked yes)
			(layer "F.Fab")
			(hide yes)
			(effects
				(font
					(size 1.016 1.016)
					(thickness 0.1524)
				)
			)
		)
		(property "Device Type" "R402H16"
			(at 0.064008 -5.517896 180)
			(unlocked yes)
			(layer "F.Fab")
			(hide yes)
			(effects
				(font
					(size 1.016 1.016)
					(thickness 0.1524)
				)
			)
		)
		(duplicate_pad_numbers_are_jumpers no)
		(fp_line
			(start 0.508 -0.9398)
			(end -0.508 -0.9398)
			(stroke
				(width 0.1524)
				(type default)
			)
			(layer "F.SilkS")
		)
		(fp_line
			(start -0.508 -0.9398)
			(end -0.508 0.9398)
			(stroke
				(width 0.1524)
				(type default)
			)
			(layer "F.SilkS")
		)
		(fp_rect
			(start -0.508 0.9398)
			(end 0.508 -0.9398)
			(stroke
				(width 0)
				(type default)
			)
			(fill no)
			(layer "F.CrtYd")
		)
		(fp_rect
			(start -0.508 0.9398)
			(end 0.508 -0.9398)
			(stroke
				(width 0)
				(type default)
			)
			(fill no)
			(layer "F.Fab")
		)
		(pad "1" smd custom
			(at 0 -0.4445 180)
			(size 0.1397 0.1397)
			(layers "F.Cu" "F.Mask" "F.Paste")
			(net "LSI_SCAN_EN")
			(options
				(clearance outline)
				(anchor circle)
			)
			(primitives
				(gr_poly
					(pts
						(arc
							(start -0.1778 -0.2794)
							(mid -0.249642 -0.249642)
							(end -0.2794 -0.1778)
						)
						(arc
							(start -0.2794 0.1778)
							(mid -0.249642 0.249642)
							(end -0.1778 0.2794)
						)
						(arc
							(start 0.1778 0.2794)
							(mid 0.249642 0.249642)
							(end 0.2794 0.1778)
						)
						(arc
							(start 0.2794 -0.1778)
							(mid 0.249642 -0.249642)
							(end 0.1778 -0.2794)
						)
					)
					(width 0)
					(fill yes)
				)
			)
		)
		(pad "2" smd custom
			(at 0 0.4445 180)
			(size 0.1397 0.1397)
			(layers "F.Cu" "F.Mask" "F.Paste")
			(net "GND")
			(options
				(clearance outline)
				(anchor circle)
			)
			(primitives
				(gr_poly
					(pts
						(arc
							(start -0.1778 -0.2794)
							(mid -0.249642 -0.249642)
							(end -0.2794 -0.1778)
						)
						(arc
							(start -0.2794 0.1778)
							(mid -0.249642 0.249642)
							(end -0.1778 0.2794)
						)
						(arc
							(start 0.1778 0.2794)
							(mid 0.249642 0.249642)
							(end 0.2794 0.1778)
						)
						(arc
							(start 0.2794 -0.1778)
							(mid 0.249642 -0.249642)
							(end 0.1778 -0.2794)
						)
					)
					(width 0)
					(fill yes)
				)
			)
		)
	)
	(footprint ""
		(layer "F.Cu")
		(at 92.208858 -79.414116 -90)
		(property "Reference" "R130"
			(at 0 0 270)
			(layer "F.SilkS")
			(hide yes)
			(effects
				(font
					(size 1.27 1.27)
				)
			)
		)
		(property "Value" "4K7R2F-GP"
			(at 0.064008 -3.993896 270)
			(unlocked yes)
			(layer "F.Fab")
			(hide yes)
			(effects
				(font
					(size 1.016 1.016)
					(thickness 0.1524)
				)
			)
		)
		(property "Device Type" "R402H16"
			(at 0.064008 -5.517896 270)
			(unlocked yes)
			(layer "F.Fab")
			(hide yes)
			(effects
				(font
					(size 1.016 1.016)
					(thickness 0.1524)
				)
			)
		)
		(duplicate_pad_numbers_are_jumpers no)
		(fp_line
			(start -0.508 -0.9398)
			(end -0.508 0.9398)
			(stroke
				(width 0.1524)
				(type default)
			)
			(layer "F.SilkS")
		)
		(fp_line
			(start 0.508 -0.9398)
			(end -0.508 -0.9398)
			(stroke
				(width 0.1524)
				(type default)
			)
			(layer "F.SilkS")
		)
		(fp_rect
			(start -0.508 0.9398)
			(end 0.508 -0.9398)
			(stroke
				(width 0)
				(type default)
			)
			(fill no)
			(layer "F.CrtYd")
		)
		(fp_rect
			(start -0.508 0.9398)
			(end 0.508 -0.9398)
			(stroke
				(width 0)
				(type default)
			)
			(fill no)
			(layer "F.Fab")
		)
		(pad "1" smd custom
			(at 0 -0.4445 270)
			(size 0.1397 0.1397)
			(layers "F.Cu" "F.Mask" "F.Paste")
			(net "P1V8_E")
			(options
				(clearance outline)
				(anchor circle)
			)
			(primitives
				(gr_poly
					(pts
						(arc
							(start -0.1778 -0.2794)
							(mid -0.249642 -0.249642)
							(end -0.2794 -0.1778)
						)
						(arc
							(start -0.2794 0.1778)
							(mid -0.249642 0.249642)
							(end -0.1778 0.2794)
						)
						(arc
							(start 0.1778 0.2794)
							(mid 0.249642 0.249642)
							(end 0.2794 0.1778)
						)
						(arc
							(start 0.2794 -0.1778)
							(mid 0.249642 -0.249642)
							(end 0.1778 -0.2794)
						)
					)
					(width 0)
					(fill yes)
				)
			)
		)
		(pad "2" smd custom
			(at 0 0.4445 270)
			(size 0.1397 0.1397)
			(layers "F.Cu" "F.Mask" "F.Paste")
			(net "EXP_RESET_N")
			(options
				(clearance outline)
				(anchor circle)
			)
			(primitives
				(gr_poly
					(pts
						(arc
							(start -0.1778 -0.2794)
							(mid -0.249642 -0.249642)
							(end -0.2794 -0.1778)
						)
						(arc
							(start -0.2794 0.1778)
							(mid -0.249642 0.249642)
							(end -0.1778 0.2794)
						)
						(arc
							(start 0.1778 0.2794)
							(mid 0.249642 0.249642)
							(end 0.2794 0.1778)
						)
						(arc
							(start 0.2794 -0.1778)
							(mid 0.249642 -0.249642)
							(end 0.1778 -0.2794)
						)
					)
					(width 0)
					(fill yes)
				)
			)
		)
	)
	(footprint ""
		(layer "F.Cu")
		(at 127.076708 -46.415706 90)
		(property "Reference" "VIA10"
			(at 0 0 90)
			(layer "F.SilkS")
			(hide yes)
			(effects
				(font
					(size 1.27 1.27)
				)
			)
		)
		(property "Value" "100OHM-8L-1D6MM-L13-GP"
			(at 3.2893 0.0508 90)
			(unlocked yes)
			(layer "F.Fab")
			(hide yes)
			(effects
				(font
					(size 1.016 1.016)
					(thickness 0.1524)
				)
			)
		)
		(property "Device Type" "VIA-PCIE-4P-409091"
			(at 3.2893 -1.4732 90)
			(unlocked yes)
			(layer "F.Fab")
			(hide yes)
			(effects
				(font
					(size 1.016 1.016)
					(thickness 0.1524)
				)
			)
		)
		(duplicate_pad_numbers_are_jumpers no)
		(fp_rect
			(start -2.0447 0.4572)
			(end 2.0447 -0.4572)
			(stroke
				(width 0)
				(type default)
			)
			(fill no)
			(layer "F.CrtYd")
		)
		(fp_rect
			(start -2.0447 0.4572)
			(end 2.0447 -0.4572)
			(stroke
				(width 0)
				(type default)
			)
			(fill no)
			(layer "F.Fab")
		)
		(pad "1" thru_hole circle
			(at -1.5875 0 90)
			(size 0.508 0.508)
			(drill 0.254)
			(layers "*.Cu" "*.Mask")
			(remove_unused_layers no)
			(net "GND")
			(clearance 0.2032)
			(thermal_gap 0.2032)
		)
		(pad "2" thru_hole circle
			(at -0.5715 0 90)
			(size 0.508 0.508)
			(drill 0.254)
			(layers "*.Cu" "*.Mask")
			(remove_unused_layers no)
			(net "PHY_IOC_TO_SCC_C_41_DP")
			(clearance 0.2032)
			(thermal_gap 0.2032)
		)
		(pad "3" thru_hole circle
			(at 0.5715 0 90)
			(size 0.508 0.508)
			(drill 0.254)
			(layers "*.Cu" "*.Mask")
			(remove_unused_layers no)
			(net "PHY_IOC_TO_SCC_C_41_DN")
			(clearance 0.2032)
			(thermal_gap 0.2032)
		)
		(pad "4" thru_hole circle
			(at 1.5875 0 90)
			(size 0.508 0.508)
			(drill 0.254)
			(layers "*.Cu" "*.Mask")
			(remove_unused_layers no)
			(net "GND")
			(clearance 0.2032)
			(thermal_gap 0.2032)
		)
	)
	(footprint ""
		(layer "F.Cu")
		(at 191.039242 -37.65423 -90)
		(property "Reference" "R254"
			(at 0 0 270)
			(layer "F.SilkS")
			(hide yes)
			(effects
				(font
					(size 1.27 1.27)
				)
			)
		)
		(property "Value" "10KR2F-2-GP"
			(at 0.064008 -3.993896 270)
			(unlocked yes)
			(layer "F.Fab")
			(hide yes)
			(effects
				(font
					(size 1.016 1.016)
					(thickness 0.1524)
				)
			)
		)
		(property "Device Type" "R402H16"
			(at 0.064008 -5.517896 270)
			(unlocked yes)
			(layer "F.Fab")
			(hide yes)
			(effects
				(font
					(size 1.016 1.016)
					(thickness 0.1524)
				)
			)
		)
		(duplicate_pad_numbers_are_jumpers no)
		(fp_line
			(start -0.508 -0.9398)
			(end -0.508 0.9398)
			(stroke
				(width 0.1524)
				(type default)
			)
			(layer "F.SilkS")
		)
		(fp_line
			(start 0.508 -0.9398)
			(end -0.508 -0.9398)
			(stroke
				(width 0.1524)
				(type default)
			)
			(layer "F.SilkS")
		)
		(fp_rect
			(start -0.508 0.9398)
			(end 0.508 -0.9398)
			(stroke
				(width 0)
				(type default)
			)
			(fill no)
			(layer "F.CrtYd")
		)
		(fp_rect
			(start -0.508 0.9398)
			(end 0.508 -0.9398)
			(stroke
				(width 0)
				(type default)
			)
			(fill no)
			(layer "F.Fab")
		)
		(pad "1" smd custom
			(at 0 -0.4445 270)
			(size 0.1397 0.1397)
			(layers "F.Cu" "F.Mask" "F.Paste")
			(net "P1V8_C")
			(options
				(clearance outline)
				(anchor circle)
			)
			(primitives
				(gr_poly
					(pts
						(arc
							(start -0.1778 -0.2794)
							(mid -0.249642 -0.249642)
							(end -0.2794 -0.1778)
						)
						(arc
							(start -0.2794 0.1778)
							(mid -0.249642 0.249642)
							(end -0.1778 0.2794)
						)
						(arc
							(start 0.1778 0.2794)
							(mid 0.249642 0.249642)
							(end 0.2794 0.1778)
						)
						(arc
							(start 0.2794 -0.1778)
							(mid 0.249642 -0.249642)
							(end 0.1778 -0.2794)
						)
					)
					(width 0)
					(fill yes)
				)
			)
		)
		(pad "2" smd custom
			(at 0 0.4445 270)
			(size 0.1397 0.1397)
			(layers "F.Cu" "F.Mask" "F.Paste")
			(net "CP_DONE")
			(options
				(clearance outline)
				(anchor circle)
			)
			(primitives
				(gr_poly
					(pts
						(arc
							(start -0.1778 -0.2794)
							(mid -0.249642 -0.249642)
							(end -0.2794 -0.1778)
						)
						(arc
							(start -0.2794 0.1778)
							(mid -0.249642 0.249642)
							(end -0.1778 0.2794)
						)
						(arc
							(start 0.1778 0.2794)
							(mid 0.249642 0.249642)
							(end 0.2794 0.1778)
						)
						(arc
							(start 0.2794 -0.1778)
							(mid 0.249642 -0.249642)
							(end 0.1778 -0.2794)
						)
					)
					(width 0)
					(fill yes)
				)
			)
		)
	)
	(footprint ""
		(layer "F.Cu")
		(at 7.5946 -94.831408 180)
		(property "Reference" "R412"
			(at 0 0 180)
			(layer "F.SilkS")
			(hide yes)
			(effects
				(font
					(size 1.27 1.27)
				)
			)
		)
		(property "Value" "200KR2F-L-GP"
			(at 0.064008 -3.993896 180)
			(unlocked yes)
			(layer "F.Fab")
			(hide yes)
			(effects
				(font
					(size 1.016 1.016)
					(thickness 0.1524)
				)
			)
		)
		(property "Device Type" "R402H16"
			(at 0.064008 -5.517896 180)
			(unlocked yes)
			(layer "F.Fab")
			(hide yes)
			(effects
				(font
					(size 1.016 1.016)
					(thickness 0.1524)
				)
			)
		)
		(duplicate_pad_numbers_are_jumpers no)
		(fp_line
			(start 0.508 -0.9398)
			(end -0.508 -0.9398)
			(stroke
				(width 0.1524)
				(type default)
			)
			(layer "F.SilkS")
		)
		(fp_line
			(start -0.508 -0.9398)
			(end -0.508 0.9398)
			(stroke
				(width 0.1524)
				(type default)
			)
			(layer "F.SilkS")
		)
		(fp_rect
			(start -0.508 0.9398)
			(end 0.508 -0.9398)
			(stroke
				(width 0)
				(type default)
			)
			(fill no)
			(layer "F.CrtYd")
		)
		(fp_rect
			(start -0.508 0.9398)
			(end 0.508 -0.9398)
			(stroke
				(width 0)
				(type default)
			)
			(fill no)
			(layer "F.Fab")
		)
		(pad "1" smd custom
			(at 0 -0.4445 180)
			(size 0.1397 0.1397)
			(layers "F.Cu" "F.Mask" "F.Paste")
			(net "VREF2")
			(options
				(clearance outline)
				(anchor circle)
			)
			(primitives
				(gr_poly
					(pts
						(arc
							(start -0.1778 -0.2794)
							(mid -0.249642 -0.249642)
							(end -0.2794 -0.1778)
						)
						(arc
							(start -0.2794 0.1778)
							(mid -0.249642 0.249642)
							(end -0.1778 0.2794)
						)
						(arc
							(start 0.1778 0.2794)
							(mid 0.249642 0.249642)
							(end 0.2794 0.1778)
						)
						(arc
							(start 0.2794 -0.1778)
							(mid 0.249642 -0.249642)
							(end 0.1778 -0.2794)
						)
					)
					(width 0)
					(fill yes)
				)
			)
		)
		(pad "2" smd custom
			(at 0 0.4445 180)
			(size 0.1397 0.1397)
			(layers "F.Cu" "F.Mask" "F.Paste")
			(net "P3V3")
			(options
				(clearance outline)
				(anchor circle)
			)
			(primitives
				(gr_poly
					(pts
						(arc
							(start -0.1778 -0.2794)
							(mid -0.249642 -0.249642)
							(end -0.2794 -0.1778)
						)
						(arc
							(start -0.2794 0.1778)
							(mid -0.249642 0.249642)
							(end -0.1778 0.2794)
						)
						(arc
							(start 0.1778 0.2794)
							(mid 0.249642 0.249642)
							(end 0.2794 0.1778)
						)
						(arc
							(start 0.2794 -0.1778)
							(mid 0.249642 -0.249642)
							(end 0.1778 -0.2794)
						)
					)
					(width 0)
					(fill yes)
				)
			)
		)
	)
	(footprint ""
		(layer "F.Cu")
		(at 177.6984 -59.817 180)
		(property "Reference" "R274"
			(at 0 0 180)
			(layer "F.SilkS")
			(hide yes)
			(effects
				(font
					(size 1.27 1.27)
				)
			)
		)
		(property "Value" "10KR2F-2-GP"
			(at 0.064008 -3.993896 180)
			(unlocked yes)
			(layer "F.Fab")
			(hide yes)
			(effects
				(font
					(size 1.016 1.016)
					(thickness 0.1524)
				)
			)
		)
		(property "Device Type" "R402H16"
			(at 0.064008 -5.517896 180)
			(unlocked yes)
			(layer "F.Fab")
			(hide yes)
			(effects
				(font
					(size 1.016 1.016)
					(thickness 0.1524)
				)
			)
		)
		(duplicate_pad_numbers_are_jumpers no)
		(fp_line
			(start 0.508 -0.9398)
			(end -0.508 -0.9398)
			(stroke
				(width 0.1524)
				(type default)
			)
			(layer "F.SilkS")
		)
		(fp_line
			(start -0.508 -0.9398)
			(end -0.508 0.9398)
			(stroke
				(width 0.1524)
				(type default)
			)
			(layer "F.SilkS")
		)
		(fp_rect
			(start -0.508 0.9398)
			(end 0.508 -0.9398)
			(stroke
				(width 0)
				(type default)
			)
			(fill no)
			(layer "F.CrtYd")
		)
		(fp_rect
			(start -0.508 0.9398)
			(end 0.508 -0.9398)
			(stroke
				(width 0)
				(type default)
			)
			(fill no)
			(layer "F.Fab")
		)
		(pad "1" smd custom
			(at 0 -0.4445 180)
			(size 0.1397 0.1397)
			(layers "F.Cu" "F.Mask" "F.Paste")
			(net "LSI_IDDT")
			(options
				(clearance outline)
				(anchor circle)
			)
			(primitives
				(gr_poly
					(pts
						(arc
							(start -0.1778 -0.2794)
							(mid -0.249642 -0.249642)
							(end -0.2794 -0.1778)
						)
						(arc
							(start -0.2794 0.1778)
							(mid -0.249642 0.249642)
							(end -0.1778 0.2794)
						)
						(arc
							(start 0.1778 0.2794)
							(mid 0.249642 0.249642)
							(end 0.2794 0.1778)
						)
						(arc
							(start 0.2794 -0.1778)
							(mid 0.249642 -0.249642)
							(end 0.1778 -0.2794)
						)
					)
					(width 0)
					(fill yes)
				)
			)
		)
		(pad "2" smd custom
			(at 0 0.4445 180)
			(size 0.1397 0.1397)
			(layers "F.Cu" "F.Mask" "F.Paste")
			(net "GND")
			(options
				(clearance outline)
				(anchor circle)
			)
			(primitives
				(gr_poly
					(pts
						(arc
							(start -0.1778 -0.2794)
							(mid -0.249642 -0.249642)
							(end -0.2794 -0.1778)
						)
						(arc
							(start -0.2794 0.1778)
							(mid -0.249642 0.249642)
							(end -0.1778 0.2794)
						)
						(arc
							(start 0.1778 0.2794)
							(mid 0.249642 0.249642)
							(end 0.2794 0.1778)
						)
						(arc
							(start 0.2794 -0.1778)
							(mid 0.249642 -0.249642)
							(end 0.1778 -0.2794)
						)
					)
					(width 0)
					(fill yes)
				)
			)
		)
	)
	(footprint ""
		(layer "F.Cu")
		(at 152.23236 -100.38588 90)
		(property "Reference" "R292"
			(at 0 0 90)
			(layer "F.SilkS")
			(hide yes)
			(effects
				(font
					(size 1.27 1.27)
				)
			)
		)
		(property "Value" "0R2J-2-GP"
			(at 0.064008 -3.993896 90)
			(unlocked yes)
			(layer "F.Fab")
			(hide yes)
			(effects
				(font
					(size 1.016 1.016)
					(thickness 0.1524)
				)
			)
		)
		(property "Device Type" "R402H16"
			(at 0.064008 -5.517896 90)
			(unlocked yes)
			(layer "F.Fab")
			(hide yes)
			(effects
				(font
					(size 1.016 1.016)
					(thickness 0.1524)
				)
			)
		)
		(duplicate_pad_numbers_are_jumpers no)
		(fp_line
			(start 0.508 -0.9398)
			(end -0.508 -0.9398)
			(stroke
				(width 0.1524)
				(type default)
			)
			(layer "F.SilkS")
		)
		(fp_line
			(start -0.508 -0.9398)
			(end -0.508 0.9398)
			(stroke
				(width 0.1524)
				(type default)
			)
			(layer "F.SilkS")
		)
		(fp_rect
			(start -0.508 0.9398)
			(end 0.508 -0.9398)
			(stroke
				(width 0)
				(type default)
			)
			(fill no)
			(layer "F.CrtYd")
		)
		(fp_rect
			(start -0.508 0.9398)
			(end 0.508 -0.9398)
			(stroke
				(width 0)
				(type default)
			)
			(fill no)
			(layer "F.Fab")
		)
		(pad "1" smd custom
			(at 0 -0.4445 90)
			(size 0.1397 0.1397)
			(layers "F.Cu" "F.Mask" "F.Paste")
			(net "UART_SDB_RX")
			(options
				(clearance outline)
				(anchor circle)
			)
			(primitives
				(gr_poly
					(pts
						(arc
							(start -0.1778 -0.2794)
							(mid -0.249642 -0.249642)
							(end -0.2794 -0.1778)
						)
						(arc
							(start -0.2794 0.1778)
							(mid -0.249642 0.249642)
							(end -0.1778 0.2794)
						)
						(arc
							(start 0.1778 0.2794)
							(mid 0.249642 0.249642)
							(end 0.2794 0.1778)
						)
						(arc
							(start 0.2794 -0.1778)
							(mid 0.249642 -0.249642)
							(end 0.1778 -0.2794)
						)
					)
					(width 0)
					(fill yes)
				)
			)
		)
		(pad "2" smd custom
			(at 0 0.4445 90)
			(size 0.1397 0.1397)
			(layers "F.Cu" "F.Mask" "F.Paste")
			(net "SAS_R_SDBRX")
			(options
				(clearance outline)
				(anchor circle)
			)
			(primitives
				(gr_poly
					(pts
						(arc
							(start -0.1778 -0.2794)
							(mid -0.249642 -0.249642)
							(end -0.2794 -0.1778)
						)
						(arc
							(start -0.2794 0.1778)
							(mid -0.249642 0.249642)
							(end -0.1778 0.2794)
						)
						(arc
							(start 0.1778 0.2794)
							(mid 0.249642 0.249642)
							(end 0.2794 0.1778)
						)
						(arc
							(start 0.2794 -0.1778)
							(mid 0.249642 -0.249642)
							(end 0.1778 -0.2794)
						)
					)
					(width 0)
					(fill yes)
				)
			)
		)
	)
	(footprint ""
		(layer "F.Cu")
		(at 166.233856 -55.208932)
		(property "Reference" "TP124"
			(at 0 0 0)
			(layer "F.SilkS")
			(hide yes)
			(effects
				(font
					(size 1.27 1.27)
				)
			)
		)
		(property "Value" "TPAD28-2-GP"
			(at -0.0127 -1.6637 0)
			(unlocked yes)
			(layer "F.Fab")
			(hide yes)
			(effects
				(font
					(size 1.016 1.016)
					(thickness 0.1524)
				)
			)
		)
		(property "Device Type" "TPAD28"
			(at -0.0127 -3.1877 0)
			(unlocked yes)
			(layer "F.Fab")
			(hide yes)
			(effects
				(font
					(size 1.016 1.016)
					(thickness 0.1524)
				)
			)
		)
		(duplicate_pad_numbers_are_jumpers no)
		(fp_poly
			(pts
				(arc
					(start 0.3556 0)
					(mid -0.3556 0)
					(end 0.3556 0)
				)
			)
			(stroke
				(width 0)
				(type default)
			)
			(fill no)
			(layer "F.CrtYd")
		)
		(fp_poly
			(pts
				(arc
					(start 0.6096 0)
					(mid -0.6096 0)
					(end 0.6096 0)
				)
			)
			(stroke
				(width 0)
				(type default)
			)
			(fill no)
			(layer "F.Fab")
		)
		(pad "1" smd circle
			(at 0 0)
			(size 0.7112 0.7112)
			(layers "F.Cu" "F.Mask" "F.Paste")
			(net "ICE1_TCK")
		)
	)
	(footprint ""
		(layer "F.Cu")
		(at 179.1208 -107.78744)
		(property "Reference" "Q22"
			(at 0 0 0)
			(layer "F.SilkS")
			(hide yes)
			(effects
				(font
					(size 1.27 1.27)
				)
			)
		)
		(property "Value" "2N7002K-1-GP"
			(at 0.127 -8.9662 0)
			(unlocked yes)
			(layer "F.Fab")
			(hide yes)
			(effects
				(font
					(size 1.016 1.016)
					(thickness 0.1524)
				)
			)
		)
		(property "Device Type" "SOT23DGS2D4H44"
			(at 0.127 -10.4902 0)
			(unlocked yes)
			(layer "F.Fab")
			(hide yes)
			(effects
				(font
					(size 1.016 1.016)
					(thickness 0.1524)
				)
			)
		)
		(duplicate_pad_numbers_are_jumpers no)
		(fp_line
			(start -1.651 -1.778)
			(end -1.651 1.778)
			(stroke
				(width 0.1524)
				(type default)
			)
			(layer "F.SilkS")
		)
		(fp_line
			(start -1.651 1.778)
			(end 1.651 1.778)
			(stroke
				(width 0.1524)
				(type default)
			)
			(layer "F.SilkS")
		)
		(fp_line
			(start 1.651 -1.778)
			(end -1.651 -1.778)
			(stroke
				(width 0.1524)
				(type default)
			)
			(layer "F.SilkS")
		)
		(fp_line
			(start 1.651 1.778)
			(end 1.651 -1.778)
			(stroke
				(width 0.1524)
				(type default)
			)
			(layer "F.SilkS")
		)
		(fp_poly
			(pts
				(xy -1.778 1.8796) (xy -1.778 -1.8796) (xy 1.778 -1.8796) (xy 1.778 1.8796)
			)
			(stroke
				(width 0)
				(type default)
			)
			(fill no)
			(layer "F.CrtYd")
		)
		(fp_poly
			(pts
				(xy -1.778 1.8796) (xy -1.778 -1.8796) (xy 1.778 -1.8796) (xy 1.778 1.8796)
			)
			(stroke
				(width 0)
				(type default)
			)
			(fill no)
			(layer "F.Fab")
		)
		(pad "D" smd custom
			(at 0 -0.9525)
			(size 0.1905 0.1905)
			(layers "F.Cu" "F.Mask" "F.Paste")
			(net "Q22_D")
			(options
				(clearance outline)
				(anchor circle)
			)
			(primitives
				(gr_poly
					(pts
						(arc
							(start -0.1778 0.5715)
							(mid -0.321484 0.511984)
							(end -0.381 0.3683)
						)
						(arc
							(start -0.381 -0.3683)
							(mid -0.321484 -0.511984)
							(end -0.1778 -0.5715)
						)
						(arc
							(start 0.1778 -0.5715)
							(mid 0.321484 -0.511984)
							(end 0.381 -0.3683)
						)
						(arc
							(start 0.381 0.3683)
							(mid 0.321484 0.511984)
							(end 0.1778 0.5715)
						)
					)
					(width 0)
					(fill yes)
				)
			)
		)
		(pad "G" smd custom
			(at -0.98425 0.9525)
			(size 0.1905 0.1905)
			(layers "F.Cu" "F.Mask" "F.Paste")
			(net "P12V_STBY_Q12_G")
			(options
				(clearance outline)
				(anchor circle)
			)
			(primitives
				(gr_poly
					(pts
						(arc
							(start -0.1778 0.5715)
							(mid -0.321484 0.511984)
							(end -0.381 0.3683)
						)
						(arc
							(start -0.381 -0.3683)
							(mid -0.321484 -0.511984)
							(end -0.1778 -0.5715)
						)
						(arc
							(start 0.1778 -0.5715)
							(mid 0.321484 -0.511984)
							(end 0.381 -0.3683)
						)
						(arc
							(start 0.381 0.3683)
							(mid 0.321484 0.511984)
							(end 0.1778 0.5715)
						)
					)
					(width 0)
					(fill yes)
				)
			)
		)
		(pad "S" smd custom
			(at 0.98425 0.9525)
			(size 0.1905 0.1905)
			(layers "F.Cu" "F.Mask" "F.Paste")
			(net "GND")
			(options
				(clearance outline)
				(anchor circle)
			)
			(primitives
				(gr_poly
					(pts
						(arc
							(start -0.1778 0.5715)
							(mid -0.321484 0.511984)
							(end -0.381 0.3683)
						)
						(arc
							(start -0.381 -0.3683)
							(mid -0.321484 -0.511984)
							(end -0.1778 -0.5715)
						)
						(arc
							(start 0.1778 -0.5715)
							(mid 0.321484 -0.511984)
							(end 0.381 -0.3683)
						)
						(arc
							(start 0.381 0.3683)
							(mid 0.321484 0.511984)
							(end 0.1778 0.5715)
						)
					)
					(width 0)
					(fill yes)
				)
			)
		)
	)
	(footprint ""
		(layer "F.Cu")
		(at 59.055 -97.5868 -90)
		(property "Reference" "C656"
			(at 0 0 270)
			(layer "F.SilkS")
			(hide yes)
			(effects
				(font
					(size 1.27 1.27)
				)
			)
		)
		(property "Value" "SCD1U50V3KX-GP"
			(at 0 -2.8194 270)
			(unlocked yes)
			(layer "F.Fab")
			(hide yes)
			(effects
				(font
					(size 1.016 1.016)
					(thickness 0.1524)
				)
			)
		)
		(property "Device Type" "C603H36"
			(at 0 -4.3434 270)
			(unlocked yes)
			(layer "F.Fab")
			(hide yes)
			(effects
				(font
					(size 1.016 1.016)
					(thickness 0.1524)
				)
			)
		)
		(duplicate_pad_numbers_are_jumpers no)
		(fp_line
			(start 0.508 0)
			(end -0.508 0)
			(stroke
				(width 0.2032)
				(type default)
			)
			(layer "F.SilkS")
		)
		(fp_rect
			(start -0.5842 1.3335)
			(end 0.5842 -1.3335)
			(stroke
				(width 0)
				(type default)
			)
			(fill no)
			(layer "F.CrtYd")
		)
		(fp_rect
			(start -0.5842 1.3335)
			(end 0.5842 -1.3335)
			(stroke
				(width 0)
				(type default)
			)
			(fill no)
			(layer "F.Fab")
		)
		(pad "1" smd custom
			(at 0 -0.762 270)
			(size 0.2159 0.2159)
			(layers "F.Cu" "F.Mask" "F.Paste")
			(net "P12V_STBY_VIN_U10")
			(options
				(clearance outline)
				(anchor circle)
			)
			(primitives
				(gr_poly
					(pts
						(arc
							(start -0.3302 -0.4318)
							(mid -0.402042 -0.402042)
							(end -0.4318 -0.3302)
						)
						(arc
							(start -0.4318 0.3302)
							(mid -0.402042 0.402042)
							(end -0.3302 0.4318)
						)
						(arc
							(start 0.3302 0.4318)
							(mid 0.402042 0.402042)
							(end 0.4318 0.3302)
						)
						(arc
							(start 0.4318 -0.3302)
							(mid 0.402042 -0.402042)
							(end 0.3302 -0.4318)
						)
					)
					(width 0)
					(fill yes)
				)
			)
		)
		(pad "2" smd custom
			(at 0 0.762 270)
			(size 0.2159 0.2159)
			(layers "F.Cu" "F.Mask" "F.Paste")
			(net "GND")
			(options
				(clearance outline)
				(anchor circle)
			)
			(primitives
				(gr_poly
					(pts
						(arc
							(start -0.3302 -0.4318)
							(mid -0.402042 -0.402042)
							(end -0.4318 -0.3302)
						)
						(arc
							(start -0.4318 0.3302)
							(mid -0.402042 0.402042)
							(end -0.3302 0.4318)
						)
						(arc
							(start 0.3302 0.4318)
							(mid 0.402042 0.402042)
							(end 0.4318 0.3302)
						)
						(arc
							(start 0.4318 -0.3302)
							(mid 0.402042 -0.402042)
							(end 0.3302 -0.4318)
						)
					)
					(width 0)
					(fill yes)
				)
			)
		)
	)
	(footprint ""
		(layer "F.Cu")
		(at 74.914252 -78.140306 180)
		(property "Reference" "U118"
			(at 0 0 180)
			(layer "F.SilkS")
			(hide yes)
			(effects
				(font
					(size 1.27 1.27)
				)
			)
		)
		(property "Value" "NX3L1G66GW-GP"
			(at -2.3368 -8.6868 180)
			(unlocked yes)
			(layer "F.Fab")
			(hide yes)
			(effects
				(font
					(size 1.016 1.016)
					(thickness 0.1524)
				)
			)
		)
		(property "Device Type" "SC70-5H44"
			(at -2.3114 -10.414 180)
			(unlocked yes)
			(layer "F.Fab")
			(hide yes)
			(effects
				(font
					(size 1.016 1.016)
					(thickness 0.1524)
				)
			)
		)
		(duplicate_pad_numbers_are_jumpers no)
		(fp_line
			(start 1.3843 -1.8034)
			(end 1.3843 -1.1176)
			(stroke
				(width 0.3302)
				(type default)
			)
			(layer "F.SilkS")
		)
		(fp_line
			(start 1.27 1.7018)
			(end -1.27 1.7018)
			(stroke
				(width 0.1524)
				(type default)
			)
			(layer "F.SilkS")
		)
		(fp_line
			(start 1.27 -1.7018)
			(end 1.27 1.7018)
			(stroke
				(width 0.1524)
				(type default)
			)
			(layer "F.SilkS")
		)
		(fp_line
			(start 0.6604 -1.8034)
			(end 1.3843 -1.8034)
			(stroke
				(width 0.3302)
				(type default)
			)
			(layer "F.SilkS")
		)
		(fp_line
			(start -1.27 1.7018)
			(end -1.27 -1.7018)
			(stroke
				(width 0.1524)
				(type default)
			)
			(layer "F.SilkS")
		)
		(fp_line
			(start -1.27 -1.7018)
			(end 1.27 -1.7018)
			(stroke
				(width 0.1524)
				(type default)
			)
			(layer "F.SilkS")
		)
		(fp_rect
			(start -1.524 1.9558)
			(end 1.524 -1.9558)
			(stroke
				(width 0)
				(type default)
			)
			(fill no)
			(layer "F.CrtYd")
		)
		(fp_poly
			(pts
				(xy -1.524 -1.9558) (xy 1.524 -1.9558) (xy 1.524 1.9558) (xy -1.524 1.9558)
			)
			(stroke
				(width 0)
				(type default)
			)
			(fill no)
			(layer "F.Fab")
		)
		(pad "1" smd rect
			(at 0.65024 -0.8255 180)
			(size 0.4064 1.2192)
			(layers "F.Cu" "F.Mask" "F.Paste")
			(net "I2C_EXP_IOC_SCL8")
		)
		(pad "2" smd rect
			(at 0 -0.8255 180)
			(size 0.4064 1.2192)
			(layers "F.Cu" "F.Mask" "F.Paste")
			(net "I2C_IOC_4_R_SCL")
		)
		(pad "3" smd rect
			(at -0.65024 -0.8255 180)
			(size 0.4064 1.2192)
			(layers "F.Cu" "F.Mask" "F.Paste")
			(net "GND")
		)
		(pad "4" smd rect
			(at -0.65024 0.8255 180)
			(size 0.4064 1.2192)
			(layers "F.Cu" "F.Mask" "F.Paste")
			(net "PCIE_COMP_TO_SCC_RST_R_0")
		)
		(pad "5" smd rect
			(at 0.65024 0.8255 180)
			(size 0.4064 1.2192)
			(layers "F.Cu" "F.Mask" "F.Paste")
			(net "U118_VCC")
		)
	)
	(footprint ""
		(layer "F.Cu")
		(at 157.6324 -110.9218)
		(property "Reference" "C696"
			(at 0 0 0)
			(layer "F.SilkS")
			(hide yes)
			(effects
				(font
					(size 1.27 1.27)
				)
			)
		)
		(property "Value" "SCD1U50V3KX-GP"
			(at 0 -2.8194 0)
			(unlocked yes)
			(layer "F.Fab")
			(hide yes)
			(effects
				(font
					(size 1.016 1.016)
					(thickness 0.1524)
				)
			)
		)
		(property "Device Type" "C603H36"
			(at 0 -4.3434 0)
			(unlocked yes)
			(layer "F.Fab")
			(hide yes)
			(effects
				(font
					(size 1.016 1.016)
					(thickness 0.1524)
				)
			)
		)
		(duplicate_pad_numbers_are_jumpers no)
		(fp_line
			(start 0.508 0)
			(end -0.508 0)
			(stroke
				(width 0.2032)
				(type default)
			)
			(layer "F.SilkS")
		)
		(fp_rect
			(start -0.5842 1.3335)
			(end 0.5842 -1.3335)
			(stroke
				(width 0)
				(type default)
			)
			(fill no)
			(layer "F.CrtYd")
		)
		(fp_rect
			(start -0.5842 1.3335)
			(end 0.5842 -1.3335)
			(stroke
				(width 0)
				(type default)
			)
			(fill no)
			(layer "F.Fab")
		)
		(pad "1" smd custom
			(at 0 -0.762)
			(size 0.2159 0.2159)
			(layers "F.Cu" "F.Mask" "F.Paste")
			(net "P12V_STBY_VIN_U11")
			(options
				(clearance outline)
				(anchor circle)
			)
			(primitives
				(gr_poly
					(pts
						(arc
							(start -0.3302 -0.4318)
							(mid -0.402042 -0.402042)
							(end -0.4318 -0.3302)
						)
						(arc
							(start -0.4318 0.3302)
							(mid -0.402042 0.402042)
							(end -0.3302 0.4318)
						)
						(arc
							(start 0.3302 0.4318)
							(mid 0.402042 0.402042)
							(end 0.4318 0.3302)
						)
						(arc
							(start 0.4318 -0.3302)
							(mid 0.402042 -0.402042)
							(end 0.3302 -0.4318)
						)
					)
					(width 0)
					(fill yes)
				)
			)
		)
		(pad "2" smd custom
			(at 0 0.762)
			(size 0.2159 0.2159)
			(layers "F.Cu" "F.Mask" "F.Paste")
			(net "GND")
			(options
				(clearance outline)
				(anchor circle)
			)
			(primitives
				(gr_poly
					(pts
						(arc
							(start -0.3302 -0.4318)
							(mid -0.402042 -0.402042)
							(end -0.4318 -0.3302)
						)
						(arc
							(start -0.4318 0.3302)
							(mid -0.402042 0.402042)
							(end -0.3302 0.4318)
						)
						(arc
							(start 0.3302 0.4318)
							(mid 0.402042 0.402042)
							(end 0.4318 0.3302)
						)
						(arc
							(start 0.4318 -0.3302)
							(mid 0.402042 -0.402042)
							(end 0.3302 -0.4318)
						)
					)
					(width 0)
					(fill yes)
				)
			)
		)
	)
	(footprint ""
		(layer "F.Cu")
		(at 7.5946 -52.1462)
		(property "Reference" "R543"
			(at 0 0 0)
			(layer "F.SilkS")
			(hide yes)
			(effects
				(font
					(size 1.27 1.27)
				)
			)
		)
		(property "Value" "11KR2F-L-GP"
			(at 0.064008 -3.993896 0)
			(unlocked yes)
			(layer "F.Fab")
			(hide yes)
			(effects
				(font
					(size 1.016 1.016)
					(thickness 0.1524)
				)
			)
		)
		(property "Device Type" "R402H16"
			(at 0.064008 -5.517896 0)
			(unlocked yes)
			(layer "F.Fab")
			(hide yes)
			(effects
				(font
					(size 1.016 1.016)
					(thickness 0.1524)
				)
			)
		)
		(duplicate_pad_numbers_are_jumpers no)
		(fp_line
			(start -0.508 -0.9398)
			(end -0.508 0.9398)
			(stroke
				(width 0.1524)
				(type default)
			)
			(layer "F.SilkS")
		)
		(fp_line
			(start 0.508 -0.9398)
			(end -0.508 -0.9398)
			(stroke
				(width 0.1524)
				(type default)
			)
			(layer "F.SilkS")
		)
		(fp_rect
			(start -0.508 0.9398)
			(end 0.508 -0.9398)
			(stroke
				(width 0)
				(type default)
			)
			(fill no)
			(layer "F.CrtYd")
		)
		(fp_rect
			(start -0.508 0.9398)
			(end 0.508 -0.9398)
			(stroke
				(width 0)
				(type default)
			)
			(fill no)
			(layer "F.Fab")
		)
		(pad "1" smd custom
			(at 0 -0.4445)
			(size 0.1397 0.1397)
			(layers "F.Cu" "F.Mask" "F.Paste")
			(net "MB0_P12V_PWGIN_R")
			(options
				(clearance outline)
				(anchor circle)
			)
			(primitives
				(gr_poly
					(pts
						(arc
							(start -0.1778 -0.2794)
							(mid -0.249642 -0.249642)
							(end -0.2794 -0.1778)
						)
						(arc
							(start -0.2794 0.1778)
							(mid -0.249642 0.249642)
							(end -0.1778 0.2794)
						)
						(arc
							(start 0.1778 0.2794)
							(mid 0.249642 0.249642)
							(end 0.2794 0.1778)
						)
						(arc
							(start 0.2794 -0.1778)
							(mid 0.249642 -0.249642)
							(end 0.1778 -0.2794)
						)
					)
					(width 0)
					(fill yes)
				)
			)
		)
		(pad "2" smd custom
			(at 0 0.4445)
			(size 0.1397 0.1397)
			(layers "F.Cu" "F.Mask" "F.Paste")
			(net "AGND_CURRENT_MON")
			(options
				(clearance outline)
				(anchor circle)
			)
			(primitives
				(gr_poly
					(pts
						(arc
							(start -0.1778 -0.2794)
							(mid -0.249642 -0.249642)
							(end -0.2794 -0.1778)
						)
						(arc
							(start -0.2794 0.1778)
							(mid -0.249642 0.249642)
							(end -0.1778 0.2794)
						)
						(arc
							(start 0.1778 0.2794)
							(mid 0.249642 0.249642)
							(end 0.2794 0.1778)
						)
						(arc
							(start 0.2794 -0.1778)
							(mid 0.249642 -0.249642)
							(end 0.1778 -0.2794)
						)
					)
					(width 0)
					(fill yes)
				)
			)
		)
	)
	(footprint ""
		(layer "F.Cu")
		(at 94.1832 -72.1106 -90)
		(property "Reference" "R112"
			(at 0 0 270)
			(layer "F.SilkS")
			(hide yes)
			(effects
				(font
					(size 1.27 1.27)
				)
			)
		)
		(property "Value" "4K75R2F-1-GP"
			(at 0.064008 -3.993896 270)
			(unlocked yes)
			(layer "F.Fab")
			(hide yes)
			(effects
				(font
					(size 1.016 1.016)
					(thickness 0.1524)
				)
			)
		)
		(property "Device Type" "R402H16"
			(at 0.064008 -5.517896 270)
			(unlocked yes)
			(layer "F.Fab")
			(hide yes)
			(effects
				(font
					(size 1.016 1.016)
					(thickness 0.1524)
				)
			)
		)
		(duplicate_pad_numbers_are_jumpers no)
		(fp_line
			(start -0.508 -0.9398)
			(end -0.508 0.9398)
			(stroke
				(width 0.1524)
				(type default)
			)
			(layer "F.SilkS")
		)
		(fp_line
			(start 0.508 -0.9398)
			(end -0.508 -0.9398)
			(stroke
				(width 0.1524)
				(type default)
			)
			(layer "F.SilkS")
		)
		(fp_rect
			(start -0.508 0.9398)
			(end 0.508 -0.9398)
			(stroke
				(width 0)
				(type default)
			)
			(fill no)
			(layer "F.CrtYd")
		)
		(fp_rect
			(start -0.508 0.9398)
			(end 0.508 -0.9398)
			(stroke
				(width 0)
				(type default)
			)
			(fill no)
			(layer "F.Fab")
		)
		(pad "1" smd custom
			(at 0 -0.4445 270)
			(size 0.1397 0.1397)
			(layers "F.Cu" "F.Mask" "F.Paste")
			(net "EXP_CPU_MODE_0")
			(options
				(clearance outline)
				(anchor circle)
			)
			(primitives
				(gr_poly
					(pts
						(arc
							(start -0.1778 -0.2794)
							(mid -0.249642 -0.249642)
							(end -0.2794 -0.1778)
						)
						(arc
							(start -0.2794 0.1778)
							(mid -0.249642 0.249642)
							(end -0.1778 0.2794)
						)
						(arc
							(start 0.1778 0.2794)
							(mid 0.249642 0.249642)
							(end 0.2794 0.1778)
						)
						(arc
							(start 0.2794 -0.1778)
							(mid 0.249642 -0.249642)
							(end 0.1778 -0.2794)
						)
					)
					(width 0)
					(fill yes)
				)
			)
		)
		(pad "2" smd custom
			(at 0 0.4445 270)
			(size 0.1397 0.1397)
			(layers "F.Cu" "F.Mask" "F.Paste")
			(net "GND")
			(options
				(clearance outline)
				(anchor circle)
			)
			(primitives
				(gr_poly
					(pts
						(arc
							(start -0.1778 -0.2794)
							(mid -0.249642 -0.249642)
							(end -0.2794 -0.1778)
						)
						(arc
							(start -0.2794 0.1778)
							(mid -0.249642 0.249642)
							(end -0.1778 0.2794)
						)
						(arc
							(start 0.1778 0.2794)
							(mid 0.249642 0.249642)
							(end 0.2794 0.1778)
						)
						(arc
							(start 0.2794 -0.1778)
							(mid 0.249642 -0.249642)
							(end 0.1778 -0.2794)
						)
					)
					(width 0)
					(fill yes)
				)
			)
		)
	)
	(footprint ""
		(layer "F.Cu")
		(at 53.1876 -73.1012 -90)
		(property "Reference" "C562"
			(at 0 0 270)
			(layer "F.SilkS")
			(hide yes)
			(effects
				(font
					(size 1.27 1.27)
				)
			)
		)
		(property "Value" "SCD1U16V2KX-3GP"
			(at 1.1811 -2.7051 270)
			(unlocked yes)
			(layer "F.Fab")
			(hide yes)
			(effects
				(font
					(size 1.016 1.016)
					(thickness 0.1524)
				)
			)
		)
		(property "Device Type" "C402H22"
			(at 1.1811 -4.2291 270)
			(unlocked yes)
			(layer "F.Fab")
			(hide yes)
			(effects
				(font
					(size 1.016 1.016)
					(thickness 0.1524)
				)
			)
		)
		(duplicate_pad_numbers_are_jumpers no)
		(fp_rect
			(start -0.4318 0.9525)
			(end 0.4318 -0.9525)
			(stroke
				(width 0)
				(type default)
			)
			(fill no)
			(layer "F.CrtYd")
		)
		(fp_rect
			(start -0.4318 0.9525)
			(end 0.4318 -0.9525)
			(stroke
				(width 0)
				(type default)
			)
			(fill no)
			(layer "F.Fab")
		)
		(pad "1" smd custom
			(at 0 -0.4445 270)
			(size 0.1524 0.1524)
			(layers "F.Cu" "F.Mask" "F.Paste")
			(net "VREF7")
			(options
				(clearance outline)
				(anchor circle)
			)
			(primitives
				(gr_poly
					(pts
						(arc
							(start 0.3048 -0.2032)
							(mid 0.275042 -0.275042)
							(end 0.2032 -0.3048)
						)
						(arc
							(start -0.2032 -0.3048)
							(mid -0.275042 -0.275042)
							(end -0.3048 -0.2032)
						)
						(arc
							(start -0.3048 0.2032)
							(mid -0.275042 0.275042)
							(end -0.2032 0.3048)
						)
						(arc
							(start 0.2032 0.3048)
							(mid 0.275042 0.275042)
							(end 0.3048 0.2032)
						)
					)
					(width 0)
					(fill yes)
				)
			)
		)
		(pad "2" smd custom
			(at 0 0.4445 270)
			(size 0.1524 0.1524)
			(layers "F.Cu" "F.Mask" "F.Paste")
			(net "GND")
			(options
				(clearance outline)
				(anchor circle)
			)
			(primitives
				(gr_poly
					(pts
						(arc
							(start 0.3048 -0.2032)
							(mid 0.275042 -0.275042)
							(end 0.2032 -0.3048)
						)
						(arc
							(start -0.2032 -0.3048)
							(mid -0.275042 -0.275042)
							(end -0.3048 -0.2032)
						)
						(arc
							(start -0.3048 0.2032)
							(mid -0.275042 0.275042)
							(end -0.2032 0.3048)
						)
						(arc
							(start 0.2032 0.3048)
							(mid 0.275042 0.275042)
							(end 0.3048 0.2032)
						)
					)
					(width 0)
					(fill yes)
				)
			)
		)
	)
	(footprint ""
		(layer "F.Cu")
		(at 135.382 -113.157 -90)
		(property "Reference" "TC5"
			(at 0 0 270)
			(layer "F.SilkS")
			(hide yes)
			(effects
				(font
					(size 1.27 1.27)
				)
			)
		)
		(property "Value" "ST150U6D3VDM-28-GP"
			(at 0 -9.6012 270)
			(unlocked yes)
			(layer "F.Fab")
			(hide yes)
			(effects
				(font
					(size 1.016 1.016)
					(thickness 0.1524)
				)
			)
		)
		(property "Device Type" "CT7343H83"
			(at 0 -11.1252 270)
			(unlocked yes)
			(layer "F.Fab")
			(hide yes)
			(effects
				(font
					(size 1.016 1.016)
					(thickness 0.1524)
				)
			)
		)
		(duplicate_pad_numbers_are_jumpers no)
		(fp_line
			(start -2.286 4.8768)
			(end -2.286 2.032)
			(stroke
				(width 0.1524)
				(type default)
			)
			(layer "F.SilkS")
		)
		(fp_line
			(start 2.286 4.8768)
			(end -2.286 4.8768)
			(stroke
				(width 0.1524)
				(type default)
			)
			(layer "F.SilkS")
		)
		(fp_line
			(start 2.286 2.032)
			(end 2.286 4.8768)
			(stroke
				(width 0.1524)
				(type default)
			)
			(layer "F.SilkS")
		)
		(fp_line
			(start 2.286 -2.032)
			(end 2.286 -4.8768)
			(stroke
				(width 0.1524)
				(type default)
			)
			(layer "F.SilkS")
		)
		(fp_line
			(start 2.1082 -4.699)
			(end -2.1082 -4.699)
			(stroke
				(width 0.508)
				(type default)
			)
			(layer "F.SilkS")
		)
		(fp_line
			(start -2.286 -4.8768)
			(end -2.286 -2.032)
			(stroke
				(width 0.1524)
				(type default)
			)
			(layer "F.SilkS")
		)
		(fp_line
			(start 2.286 -4.8768)
			(end -2.286 -4.8768)
			(stroke
				(width 0.1524)
				(type default)
			)
			(layer "F.SilkS")
		)
		(fp_rect
			(start -2.1463 3.6449)
			(end 2.1463 -3.6449)
			(stroke
				(width 0)
				(type default)
			)
			(fill no)
			(layer "F.CrtYd")
		)
		(fp_poly
			(pts
				(xy -2.54 4.953) (xy -2.54 4.2926) (xy -3.81 4.2926) (xy -3.81 -4.2926) (xy -2.54 -4.2926) (xy -2.54 -4.953)
				(xy 2.54 -4.953) (xy 2.54 -4.2926) (xy 3.81 -4.2926) (xy 3.81 -1.6256) (xy 2.1463 -1.6256) (xy 2.1463 -3.6449)
				(xy -2.1463 -3.6449) (xy -2.1463 3.6449) (xy 2.1463 3.6449) (xy 2.1463 -1.6129) (xy 3.81 -1.6129)
				(xy 3.81 4.2926) (xy 2.54 4.2926) (xy 2.54 4.953)
			)
			(stroke
				(width 0)
				(type default)
			)
			(fill no)
			(layer "F.CrtYd")
		)
		(fp_rect
			(start -2.54 4.953)
			(end 2.54 -4.953)
			(stroke
				(width 0)
				(type default)
			)
			(fill no)
			(layer "F.Fab")
		)
		(fp_rect
			(start -3.81 4.2926)
			(end -2.54 -4.2926)
			(stroke
				(width 0)
				(type default)
			)
			(fill no)
			(layer "F.Fab")
		)
		(fp_rect
			(start 2.54 4.2926)
			(end 3.81 -4.2926)
			(stroke
				(width 0)
				(type default)
			)
			(fill no)
			(layer "F.Fab")
		)
		(pad "1" smd rect
			(at 0 -3.1496 270)
			(size 2.413 2.286)
			(layers "F.Cu" "F.Mask" "F.Paste")
			(net "P1V5_E_OUT")
		)
		(pad "2" smd rect
			(at 0 3.1496 270)
			(size 2.413 2.286)
			(layers "F.Cu" "F.Mask" "F.Paste")
			(net "GND")
		)
		(zone
			(layer "F.Cu")
			(hatch none 0.5)
			(connect_pads
				(clearance 0)
			)
			(min_thickness 0.25)
			(keepout
				(tracks allowed)
				(vias not_allowed)
				(pads allowed)
				(copperpour not_allowed)
				(footprints allowed)
			)
			(placement
				(enabled no)
				(sheetname "")
			)
			(fill
				(thermal_gap 0.5)
				(thermal_bridge_width 0.5)
				(island_removal_mode 0)
			)
			(polygon
				(pts
					(xy 130.7846 -114.6683) (xy 130.7846 -111.6457) (xy 133.6802 -111.6457) (xy 134.0104 -111.6457)
					(xy 134.0104 -114.6683) (xy 133.6802 -114.6683)
				)
			)
		)
		(zone
			(layer "F.Cu")
			(hatch none 0.5)
			(connect_pads
				(clearance 0)
			)
			(min_thickness 0.25)
			(keepout
				(tracks allowed)
				(vias not_allowed)
				(pads allowed)
				(copperpour not_allowed)
				(footprints allowed)
			)
			(placement
				(enabled no)
				(sheetname "")
			)
			(fill
				(thermal_gap 0.5)
				(thermal_bridge_width 0.5)
				(island_removal_mode 0)
			)
			(polygon
				(pts
					(xy 137.0711 -111.6457) (xy 139.9794 -111.6457) (xy 139.9794 -114.6683) (xy 137.0838 -114.6683)
					(xy 136.7536 -114.6683) (xy 136.7536 -111.6457)
				)
			)
		)
	)
	(footprint ""
		(layer "F.Cu")
		(at 182.8419 -110.16488)
		(property "Reference" "Q12"
			(at 0 0 0)
			(layer "F.SilkS")
			(hide yes)
			(effects
				(font
					(size 1.27 1.27)
				)
			)
		)
		(property "Value" "2N7002K-1-GP"
			(at 0.127 -8.9662 0)
			(unlocked yes)
			(layer "F.Fab")
			(hide yes)
			(effects
				(font
					(size 1.016 1.016)
					(thickness 0.1524)
				)
			)
		)
		(property "Device Type" "SOT23DGS2D4H44"
			(at 0.127 -10.4902 0)
			(unlocked yes)
			(layer "F.Fab")
			(hide yes)
			(effects
				(font
					(size 1.016 1.016)
					(thickness 0.1524)
				)
			)
		)
		(duplicate_pad_numbers_are_jumpers no)
		(fp_line
			(start -1.651 -1.778)
			(end -1.651 1.778)
			(stroke
				(width 0.1524)
				(type default)
			)
			(layer "F.SilkS")
		)
		(fp_line
			(start -1.651 1.778)
			(end 1.651 1.778)
			(stroke
				(width 0.1524)
				(type default)
			)
			(layer "F.SilkS")
		)
		(fp_line
			(start 1.651 -1.778)
			(end -1.651 -1.778)
			(stroke
				(width 0.1524)
				(type default)
			)
			(layer "F.SilkS")
		)
		(fp_line
			(start 1.651 1.778)
			(end 1.651 -1.778)
			(stroke
				(width 0.1524)
				(type default)
			)
			(layer "F.SilkS")
		)
		(fp_poly
			(pts
				(xy -1.778 1.8796) (xy -1.778 -1.8796) (xy 1.778 -1.8796) (xy 1.778 1.8796)
			)
			(stroke
				(width 0)
				(type default)
			)
			(fill no)
			(layer "F.CrtYd")
		)
		(fp_poly
			(pts
				(xy -1.778 1.8796) (xy -1.778 -1.8796) (xy 1.778 -1.8796) (xy 1.778 1.8796)
			)
			(stroke
				(width 0)
				(type default)
			)
			(fill no)
			(layer "F.Fab")
		)
		(pad "D" smd custom
			(at 0 -0.9525)
			(size 0.1905 0.1905)
			(layers "F.Cu" "F.Mask" "F.Paste")
			(net "P1V8_C_PG_R_1")
			(options
				(clearance outline)
				(anchor circle)
			)
			(primitives
				(gr_poly
					(pts
						(arc
							(start -0.1778 0.5715)
							(mid -0.321484 0.511984)
							(end -0.381 0.3683)
						)
						(arc
							(start -0.381 -0.3683)
							(mid -0.321484 -0.511984)
							(end -0.1778 -0.5715)
						)
						(arc
							(start 0.1778 -0.5715)
							(mid 0.321484 -0.511984)
							(end 0.381 -0.3683)
						)
						(arc
							(start 0.381 0.3683)
							(mid 0.321484 0.511984)
							(end 0.1778 0.5715)
						)
					)
					(width 0)
					(fill yes)
				)
			)
		)
		(pad "G" smd custom
			(at -0.98425 0.9525)
			(size 0.1905 0.1905)
			(layers "F.Cu" "F.Mask" "F.Paste")
			(net "P12V_STBY_Q12_G")
			(options
				(clearance outline)
				(anchor circle)
			)
			(primitives
				(gr_poly
					(pts
						(arc
							(start -0.1778 0.5715)
							(mid -0.321484 0.511984)
							(end -0.381 0.3683)
						)
						(arc
							(start -0.381 -0.3683)
							(mid -0.321484 -0.511984)
							(end -0.1778 -0.5715)
						)
						(arc
							(start 0.1778 -0.5715)
							(mid 0.321484 -0.511984)
							(end 0.381 -0.3683)
						)
						(arc
							(start 0.381 0.3683)
							(mid 0.321484 0.511984)
							(end 0.1778 0.5715)
						)
					)
					(width 0)
					(fill yes)
				)
			)
		)
		(pad "S" smd custom
			(at 0.98425 0.9525)
			(size 0.1905 0.1905)
			(layers "F.Cu" "F.Mask" "F.Paste")
			(net "GND")
			(options
				(clearance outline)
				(anchor circle)
			)
			(primitives
				(gr_poly
					(pts
						(arc
							(start -0.1778 0.5715)
							(mid -0.321484 0.511984)
							(end -0.381 0.3683)
						)
						(arc
							(start -0.381 -0.3683)
							(mid -0.321484 -0.511984)
							(end -0.1778 -0.5715)
						)
						(arc
							(start 0.1778 -0.5715)
							(mid 0.321484 -0.511984)
							(end 0.381 -0.3683)
						)
						(arc
							(start 0.381 0.3683)
							(mid 0.321484 0.511984)
							(end 0.1778 0.5715)
						)
					)
					(width 0)
					(fill yes)
				)
			)
		)
	)
	(footprint ""
		(layer "F.Cu")
		(at 167.11168 -56.27624)
		(property "Reference" "TP121"
			(at 0 0 0)
			(layer "F.SilkS")
			(hide yes)
			(effects
				(font
					(size 1.27 1.27)
				)
			)
		)
		(property "Value" "TPAD28-2-GP"
			(at -0.0127 -1.6637 0)
			(unlocked yes)
			(layer "F.Fab")
			(hide yes)
			(effects
				(font
					(size 1.016 1.016)
					(thickness 0.1524)
				)
			)
		)
		(property "Device Type" "TPAD28"
			(at -0.0127 -3.1877 0)
			(unlocked yes)
			(layer "F.Fab")
			(hide yes)
			(effects
				(font
					(size 1.016 1.016)
					(thickness 0.1524)
				)
			)
		)
		(duplicate_pad_numbers_are_jumpers no)
		(fp_poly
			(pts
				(arc
					(start 0.3556 0)
					(mid -0.3556 0)
					(end 0.3556 0)
				)
			)
			(stroke
				(width 0)
				(type default)
			)
			(fill no)
			(layer "F.CrtYd")
		)
		(fp_poly
			(pts
				(arc
					(start 0.6096 0)
					(mid -0.6096 0)
					(end 0.6096 0)
				)
			)
			(stroke
				(width 0)
				(type default)
			)
			(fill no)
			(layer "F.Fab")
		)
		(pad "1" smd circle
			(at 0 0)
			(size 0.7112 0.7112)
			(layers "F.Cu" "F.Mask" "F.Paste")
			(net "ICE0_TDI")
		)
	)
	(footprint ""
		(layer "F.Cu")
		(at 70.104 -7.366 90)
		(property "Reference" "R89"
			(at 0 0 90)
			(layer "F.SilkS")
			(hide yes)
			(effects
				(font
					(size 1.27 1.27)
				)
			)
		)
		(property "Value" "0R2J-2-GP"
			(at 0.064008 -3.993896 90)
			(unlocked yes)
			(layer "F.Fab")
			(hide yes)
			(effects
				(font
					(size 1.016 1.016)
					(thickness 0.1524)
				)
			)
		)
		(property "Device Type" "R402H16"
			(at 0.064008 -5.517896 90)
			(unlocked yes)
			(layer "F.Fab")
			(hide yes)
			(effects
				(font
					(size 1.016 1.016)
					(thickness 0.1524)
				)
			)
		)
		(duplicate_pad_numbers_are_jumpers no)
		(fp_line
			(start 0.508 -0.9398)
			(end -0.508 -0.9398)
			(stroke
				(width 0.1524)
				(type default)
			)
			(layer "F.SilkS")
		)
		(fp_line
			(start -0.508 -0.9398)
			(end -0.508 0.9398)
			(stroke
				(width 0.1524)
				(type default)
			)
			(layer "F.SilkS")
		)
		(fp_rect
			(start -0.508 0.9398)
			(end 0.508 -0.9398)
			(stroke
				(width 0)
				(type default)
			)
			(fill no)
			(layer "F.CrtYd")
		)
		(fp_rect
			(start -0.508 0.9398)
			(end 0.508 -0.9398)
			(stroke
				(width 0)
				(type default)
			)
			(fill no)
			(layer "F.Fab")
		)
		(pad "1" smd custom
			(at 0 -0.4445 90)
			(size 0.1397 0.1397)
			(layers "F.Cu" "F.Mask" "F.Paste")
			(net "GND")
			(options
				(clearance outline)
				(anchor circle)
			)
			(primitives
				(gr_poly
					(pts
						(arc
							(start -0.1778 -0.2794)
							(mid -0.249642 -0.249642)
							(end -0.2794 -0.1778)
						)
						(arc
							(start -0.2794 0.1778)
							(mid -0.249642 0.249642)
							(end -0.1778 0.2794)
						)
						(arc
							(start 0.1778 0.2794)
							(mid 0.249642 0.249642)
							(end 0.2794 0.1778)
						)
						(arc
							(start 0.2794 -0.1778)
							(mid 0.249642 -0.249642)
							(end 0.1778 -0.2794)
						)
					)
					(width 0)
					(fill yes)
				)
			)
		)
		(pad "2" smd custom
			(at 0 0.4445 90)
			(size 0.1397 0.1397)
			(layers "F.Cu" "F.Mask" "F.Paste")
			(net "SCC_TYPE_0")
			(options
				(clearance outline)
				(anchor circle)
			)
			(primitives
				(gr_poly
					(pts
						(arc
							(start -0.1778 -0.2794)
							(mid -0.249642 -0.249642)
							(end -0.2794 -0.1778)
						)
						(arc
							(start -0.2794 0.1778)
							(mid -0.249642 0.249642)
							(end -0.1778 0.2794)
						)
						(arc
							(start 0.1778 0.2794)
							(mid 0.249642 0.249642)
							(end 0.2794 0.1778)
						)
						(arc
							(start 0.2794 -0.1778)
							(mid 0.249642 -0.249642)
							(end 0.1778 -0.2794)
						)
					)
					(width 0)
					(fill yes)
				)
			)
		)
	)
	(footprint ""
		(layer "F.Cu")
		(at 188.8744 -56.5658 180)
		(property "Reference" "R226"
			(at 0 0 180)
			(layer "F.SilkS")
			(hide yes)
			(effects
				(font
					(size 1.27 1.27)
				)
			)
		)
		(property "Value" "10KR2F-2-GP"
			(at 0.064008 -3.993896 180)
			(unlocked yes)
			(layer "F.Fab")
			(hide yes)
			(effects
				(font
					(size 1.016 1.016)
					(thickness 0.1524)
				)
			)
		)
		(property "Device Type" "R402H16"
			(at 0.064008 -5.517896 180)
			(unlocked yes)
			(layer "F.Fab")
			(hide yes)
			(effects
				(font
					(size 1.016 1.016)
					(thickness 0.1524)
				)
			)
		)
		(duplicate_pad_numbers_are_jumpers no)
		(fp_line
			(start 0.508 -0.9398)
			(end -0.508 -0.9398)
			(stroke
				(width 0.1524)
				(type default)
			)
			(layer "F.SilkS")
		)
		(fp_line
			(start -0.508 -0.9398)
			(end -0.508 0.9398)
			(stroke
				(width 0.1524)
				(type default)
			)
			(layer "F.SilkS")
		)
		(fp_rect
			(start -0.508 0.9398)
			(end 0.508 -0.9398)
			(stroke
				(width 0)
				(type default)
			)
			(fill no)
			(layer "F.CrtYd")
		)
		(fp_rect
			(start -0.508 0.9398)
			(end 0.508 -0.9398)
			(stroke
				(width 0)
				(type default)
			)
			(fill no)
			(layer "F.Fab")
		)
		(pad "1" smd custom
			(at 0 -0.4445 180)
			(size 0.1397 0.1397)
			(layers "F.Cu" "F.Mask" "F.Paste")
			(net "XM_ADDR_6")
			(options
				(clearance outline)
				(anchor circle)
			)
			(primitives
				(gr_poly
					(pts
						(arc
							(start -0.1778 -0.2794)
							(mid -0.249642 -0.249642)
							(end -0.2794 -0.1778)
						)
						(arc
							(start -0.2794 0.1778)
							(mid -0.249642 0.249642)
							(end -0.1778 0.2794)
						)
						(arc
							(start 0.1778 0.2794)
							(mid 0.249642 0.249642)
							(end 0.2794 0.1778)
						)
						(arc
							(start 0.2794 -0.1778)
							(mid 0.249642 -0.249642)
							(end 0.1778 -0.2794)
						)
					)
					(width 0)
					(fill yes)
				)
			)
		)
		(pad "2" smd custom
			(at 0 0.4445 180)
			(size 0.1397 0.1397)
			(layers "F.Cu" "F.Mask" "F.Paste")
			(net "GND")
			(options
				(clearance outline)
				(anchor circle)
			)
			(primitives
				(gr_poly
					(pts
						(arc
							(start -0.1778 -0.2794)
							(mid -0.249642 -0.249642)
							(end -0.2794 -0.1778)
						)
						(arc
							(start -0.2794 0.1778)
							(mid -0.249642 0.249642)
							(end -0.1778 0.2794)
						)
						(arc
							(start 0.1778 0.2794)
							(mid 0.249642 0.249642)
							(end 0.2794 0.1778)
						)
						(arc
							(start 0.2794 -0.1778)
							(mid 0.249642 -0.249642)
							(end 0.1778 -0.2794)
						)
					)
					(width 0)
					(fill yes)
				)
			)
		)
	)
	(footprint ""
		(layer "F.Cu")
		(at 15.1892 -47.2186 180)
		(property "Reference" "C646"
			(at 0 0 180)
			(layer "F.SilkS")
			(hide yes)
			(effects
				(font
					(size 1.27 1.27)
				)
			)
		)
		(property "Value" "SC1U25V3KX-GP"
			(at 0 -2.8194 180)
			(unlocked yes)
			(layer "F.Fab")
			(hide yes)
			(effects
				(font
					(size 1.016 1.016)
					(thickness 0.1524)
				)
			)
		)
		(property "Device Type" "C603H36"
			(at 0 -4.3434 180)
			(unlocked yes)
			(layer "F.Fab")
			(hide yes)
			(effects
				(font
					(size 1.016 1.016)
					(thickness 0.1524)
				)
			)
		)
		(duplicate_pad_numbers_are_jumpers no)
		(fp_line
			(start 0.508 0)
			(end -0.508 0)
			(stroke
				(width 0.2032)
				(type default)
			)
			(layer "F.SilkS")
		)
		(fp_rect
			(start -0.5842 1.3335)
			(end 0.5842 -1.3335)
			(stroke
				(width 0)
				(type default)
			)
			(fill no)
			(layer "F.CrtYd")
		)
		(fp_rect
			(start -0.5842 1.3335)
			(end 0.5842 -1.3335)
			(stroke
				(width 0)
				(type default)
			)
			(fill no)
			(layer "F.Fab")
		)
		(pad "1" smd custom
			(at 0 -0.762 180)
			(size 0.2159 0.2159)
			(layers "F.Cu" "F.Mask" "F.Paste")
			(net "AGND_CURRENT_MON")
			(options
				(clearance outline)
				(anchor circle)
			)
			(primitives
				(gr_poly
					(pts
						(arc
							(start -0.3302 -0.4318)
							(mid -0.402042 -0.402042)
							(end -0.4318 -0.3302)
						)
						(arc
							(start -0.4318 0.3302)
							(mid -0.402042 0.402042)
							(end -0.3302 0.4318)
						)
						(arc
							(start 0.3302 0.4318)
							(mid 0.402042 0.402042)
							(end 0.4318 0.3302)
						)
						(arc
							(start 0.4318 -0.3302)
							(mid 0.402042 -0.402042)
							(end 0.3302 -0.4318)
						)
					)
					(width 0)
					(fill yes)
				)
			)
		)
		(pad "2" smd custom
			(at 0 0.762 180)
			(size 0.2159 0.2159)
			(layers "F.Cu" "F.Mask" "F.Paste")
			(net "MB0_VCC")
			(options
				(clearance outline)
				(anchor circle)
			)
			(primitives
				(gr_poly
					(pts
						(arc
							(start -0.3302 -0.4318)
							(mid -0.402042 -0.402042)
							(end -0.4318 -0.3302)
						)
						(arc
							(start -0.4318 0.3302)
							(mid -0.402042 0.402042)
							(end -0.3302 0.4318)
						)
						(arc
							(start 0.3302 0.4318)
							(mid 0.402042 0.402042)
							(end 0.4318 0.3302)
						)
						(arc
							(start 0.4318 -0.3302)
							(mid 0.402042 -0.402042)
							(end 0.3302 -0.4318)
						)
					)
					(width 0)
					(fill yes)
				)
			)
		)
	)
	(footprint ""
		(layer "F.Cu")
		(at 159.85998 -116.41582 180)
		(property "Reference" "R316"
			(at 0 0 180)
			(layer "F.SilkS")
			(hide yes)
			(effects
				(font
					(size 1.27 1.27)
				)
			)
		)
		(property "Value" "866KR2F-GP"
			(at 0.064008 -3.993896 180)
			(unlocked yes)
			(layer "F.Fab")
			(hide yes)
			(effects
				(font
					(size 1.016 1.016)
					(thickness 0.1524)
				)
			)
		)
		(property "Device Type" "R402H16"
			(at 0.064008 -5.517896 180)
			(unlocked yes)
			(layer "F.Fab")
			(hide yes)
			(effects
				(font
					(size 1.016 1.016)
					(thickness 0.1524)
				)
			)
		)
		(duplicate_pad_numbers_are_jumpers no)
		(fp_line
			(start 0.508 -0.9398)
			(end -0.508 -0.9398)
			(stroke
				(width 0.1524)
				(type default)
			)
			(layer "F.SilkS")
		)
		(fp_line
			(start -0.508 -0.9398)
			(end -0.508 0.9398)
			(stroke
				(width 0.1524)
				(type default)
			)
			(layer "F.SilkS")
		)
		(fp_rect
			(start -0.508 0.9398)
			(end 0.508 -0.9398)
			(stroke
				(width 0)
				(type default)
			)
			(fill no)
			(layer "F.CrtYd")
		)
		(fp_rect
			(start -0.508 0.9398)
			(end 0.508 -0.9398)
			(stroke
				(width 0)
				(type default)
			)
			(fill no)
			(layer "F.Fab")
		)
		(pad "1" smd custom
			(at 0 -0.4445 180)
			(size 0.1397 0.1397)
			(layers "F.Cu" "F.Mask" "F.Paste")
			(net "P1V5_E_VREG")
			(options
				(clearance outline)
				(anchor circle)
			)
			(primitives
				(gr_poly
					(pts
						(arc
							(start -0.1778 -0.2794)
							(mid -0.249642 -0.249642)
							(end -0.2794 -0.1778)
						)
						(arc
							(start -0.2794 0.1778)
							(mid -0.249642 0.249642)
							(end -0.1778 0.2794)
						)
						(arc
							(start 0.1778 0.2794)
							(mid 0.249642 0.249642)
							(end 0.2794 0.1778)
						)
						(arc
							(start 0.2794 -0.1778)
							(mid 0.249642 -0.249642)
							(end 0.1778 -0.2794)
						)
					)
					(width 0)
					(fill yes)
				)
			)
		)
		(pad "2" smd custom
			(at 0 0.4445 180)
			(size 0.1397 0.1397)
			(layers "F.Cu" "F.Mask" "F.Paste")
			(net "P1V5_E_RF")
			(options
				(clearance outline)
				(anchor circle)
			)
			(primitives
				(gr_poly
					(pts
						(arc
							(start -0.1778 -0.2794)
							(mid -0.249642 -0.249642)
							(end -0.2794 -0.1778)
						)
						(arc
							(start -0.2794 0.1778)
							(mid -0.249642 0.249642)
							(end -0.1778 0.2794)
						)
						(arc
							(start 0.1778 0.2794)
							(mid 0.249642 0.249642)
							(end 0.2794 0.1778)
						)
						(arc
							(start 0.2794 -0.1778)
							(mid 0.249642 -0.249642)
							(end 0.1778 -0.2794)
						)
					)
					(width 0)
					(fill yes)
				)
			)
		)
	)
	(footprint ""
		(layer "F.Cu")
		(at 89.789 -66.675)
		(property "Reference" "TP165"
			(at 0 0 0)
			(layer "F.SilkS")
			(hide yes)
			(effects
				(font
					(size 1.27 1.27)
				)
			)
		)
		(property "Value" "TPAD28-2-GP"
			(at -0.0127 -1.6637 0)
			(unlocked yes)
			(layer "F.Fab")
			(hide yes)
			(effects
				(font
					(size 1.016 1.016)
					(thickness 0.1524)
				)
			)
		)
		(property "Device Type" "TPAD28"
			(at -0.0127 -3.1877 0)
			(unlocked yes)
			(layer "F.Fab")
			(hide yes)
			(effects
				(font
					(size 1.016 1.016)
					(thickness 0.1524)
				)
			)
		)
		(duplicate_pad_numbers_are_jumpers no)
		(fp_poly
			(pts
				(arc
					(start 0.3556 0)
					(mid -0.3556 0)
					(end 0.3556 0)
				)
			)
			(stroke
				(width 0)
				(type default)
			)
			(fill no)
			(layer "F.CrtYd")
		)
		(fp_poly
			(pts
				(arc
					(start 0.6096 0)
					(mid -0.6096 0)
					(end 0.6096 0)
				)
			)
			(stroke
				(width 0)
				(type default)
			)
			(fill no)
			(layer "F.Fab")
		)
		(pad "1" smd circle
			(at 0 0)
			(size 0.7112 0.7112)
			(layers "F.Cu" "F.Mask" "F.Paste")
			(net "LED46")
		)
	)
	(footprint ""
		(layer "F.Cu")
		(at 172.339 -57.785)
		(property "Reference" "TP142"
			(at 0 0 0)
			(layer "F.SilkS")
			(hide yes)
			(effects
				(font
					(size 1.27 1.27)
				)
			)
		)
		(property "Value" "TPAD28-2-GP"
			(at -0.0127 -1.6637 0)
			(unlocked yes)
			(layer "F.Fab")
			(hide yes)
			(effects
				(font
					(size 1.016 1.016)
					(thickness 0.1524)
				)
			)
		)
		(property "Device Type" "TPAD28"
			(at -0.0127 -3.1877 0)
			(unlocked yes)
			(layer "F.Fab")
			(hide yes)
			(effects
				(font
					(size 1.016 1.016)
					(thickness 0.1524)
				)
			)
		)
		(duplicate_pad_numbers_are_jumpers no)
		(fp_poly
			(pts
				(arc
					(start 0.3556 0)
					(mid -0.3556 0)
					(end 0.3556 0)
				)
			)
			(stroke
				(width 0)
				(type default)
			)
			(fill no)
			(layer "F.CrtYd")
		)
		(fp_poly
			(pts
				(arc
					(start 0.6096 0)
					(mid -0.6096 0)
					(end 0.6096 0)
				)
			)
			(stroke
				(width 0)
				(type default)
			)
			(fill no)
			(layer "F.Fab")
		)
		(pad "1" smd circle
			(at 0 0)
			(size 0.7112 0.7112)
			(layers "F.Cu" "F.Mask" "F.Paste")
			(net "LSI_TN")
		)
	)
	(footprint ""
		(layer "F.Cu")
		(at 64.00165 -80.509618 90)
		(property "Reference" "C550"
			(at 0 0 90)
			(layer "F.SilkS")
			(hide yes)
			(effects
				(font
					(size 1.27 1.27)
				)
			)
		)
		(property "Value" "SCD1U16V2KX-3GP"
			(at 1.1811 -2.7051 90)
			(unlocked yes)
			(layer "F.Fab")
			(hide yes)
			(effects
				(font
					(size 1.016 1.016)
					(thickness 0.1524)
				)
			)
		)
		(property "Device Type" "C402H22"
			(at 1.1811 -4.2291 90)
			(unlocked yes)
			(layer "F.Fab")
			(hide yes)
			(effects
				(font
					(size 1.016 1.016)
					(thickness 0.1524)
				)
			)
		)
		(duplicate_pad_numbers_are_jumpers no)
		(fp_rect
			(start -0.4318 0.9525)
			(end 0.4318 -0.9525)
			(stroke
				(width 0)
				(type default)
			)
			(fill no)
			(layer "F.CrtYd")
		)
		(fp_rect
			(start -0.4318 0.9525)
			(end 0.4318 -0.9525)
			(stroke
				(width 0)
				(type default)
			)
			(fill no)
			(layer "F.Fab")
		)
		(pad "1" smd custom
			(at 0 -0.4445 90)
			(size 0.1524 0.1524)
			(layers "F.Cu" "F.Mask" "F.Paste")
			(net "P1V8_E")
			(options
				(clearance outline)
				(anchor circle)
			)
			(primitives
				(gr_poly
					(pts
						(arc
							(start 0.3048 -0.2032)
							(mid 0.275042 -0.275042)
							(end 0.2032 -0.3048)
						)
						(arc
							(start -0.2032 -0.3048)
							(mid -0.275042 -0.275042)
							(end -0.3048 -0.2032)
						)
						(arc
							(start -0.3048 0.2032)
							(mid -0.275042 0.275042)
							(end -0.2032 0.3048)
						)
						(arc
							(start 0.2032 0.3048)
							(mid 0.275042 0.275042)
							(end 0.3048 0.2032)
						)
					)
					(width 0)
					(fill yes)
				)
			)
		)
		(pad "2" smd custom
			(at 0 0.4445 90)
			(size 0.1524 0.1524)
			(layers "F.Cu" "F.Mask" "F.Paste")
			(net "GND")
			(options
				(clearance outline)
				(anchor circle)
			)
			(primitives
				(gr_poly
					(pts
						(arc
							(start 0.3048 -0.2032)
							(mid 0.275042 -0.275042)
							(end 0.2032 -0.3048)
						)
						(arc
							(start -0.2032 -0.3048)
							(mid -0.275042 -0.275042)
							(end -0.3048 -0.2032)
						)
						(arc
							(start -0.3048 0.2032)
							(mid -0.275042 0.275042)
							(end -0.2032 0.3048)
						)
						(arc
							(start 0.2032 0.3048)
							(mid 0.275042 0.275042)
							(end 0.3048 0.2032)
						)
					)
					(width 0)
					(fill yes)
				)
			)
		)
	)
	(footprint ""
		(layer "F.Cu")
		(at 22.7584 -99.7966 180)
		(property "Reference" "R533"
			(at 0 0 180)
			(layer "F.SilkS")
			(hide yes)
			(effects
				(font
					(size 1.27 1.27)
				)
			)
		)
		(property "Value" "0R2J-2-GP"
			(at 0.064008 -3.993896 180)
			(unlocked yes)
			(layer "F.Fab")
			(hide yes)
			(effects
				(font
					(size 1.016 1.016)
					(thickness 0.1524)
				)
			)
		)
		(property "Device Type" "R402H16"
			(at 0.064008 -5.517896 180)
			(unlocked yes)
			(layer "F.Fab")
			(hide yes)
			(effects
				(font
					(size 1.016 1.016)
					(thickness 0.1524)
				)
			)
		)
		(duplicate_pad_numbers_are_jumpers no)
		(fp_line
			(start 0.508 -0.9398)
			(end -0.508 -0.9398)
			(stroke
				(width 0.1524)
				(type default)
			)
			(layer "F.SilkS")
		)
		(fp_line
			(start -0.508 -0.9398)
			(end -0.508 0.9398)
			(stroke
				(width 0.1524)
				(type default)
			)
			(layer "F.SilkS")
		)
		(fp_rect
			(start -0.508 0.9398)
			(end 0.508 -0.9398)
			(stroke
				(width 0)
				(type default)
			)
			(fill no)
			(layer "F.CrtYd")
		)
		(fp_rect
			(start -0.508 0.9398)
			(end 0.508 -0.9398)
			(stroke
				(width 0)
				(type default)
			)
			(fill no)
			(layer "F.Fab")
		)
		(pad "1" smd custom
			(at 0 -0.4445 180)
			(size 0.1397 0.1397)
			(layers "F.Cu" "F.Mask" "F.Paste")
			(net "SCC_STBY_PGOOD_BUF")
			(options
				(clearance outline)
				(anchor circle)
			)
			(primitives
				(gr_poly
					(pts
						(arc
							(start -0.1778 -0.2794)
							(mid -0.249642 -0.249642)
							(end -0.2794 -0.1778)
						)
						(arc
							(start -0.2794 0.1778)
							(mid -0.249642 0.249642)
							(end -0.1778 0.2794)
						)
						(arc
							(start 0.1778 0.2794)
							(mid 0.249642 0.249642)
							(end 0.2794 0.1778)
						)
						(arc
							(start 0.2794 -0.1778)
							(mid 0.249642 -0.249642)
							(end 0.1778 -0.2794)
						)
					)
					(width 0)
					(fill yes)
				)
			)
		)
		(pad "2" smd custom
			(at 0 0.4445 180)
			(size 0.1397 0.1397)
			(layers "F.Cu" "F.Mask" "F.Paste")
			(net "SCC_STBY_PGOOD_R")
			(options
				(clearance outline)
				(anchor circle)
			)
			(primitives
				(gr_poly
					(pts
						(arc
							(start -0.1778 -0.2794)
							(mid -0.249642 -0.249642)
							(end -0.2794 -0.1778)
						)
						(arc
							(start -0.2794 0.1778)
							(mid -0.249642 0.249642)
							(end -0.1778 0.2794)
						)
						(arc
							(start 0.1778 0.2794)
							(mid 0.249642 0.249642)
							(end 0.2794 0.1778)
						)
						(arc
							(start 0.2794 -0.1778)
							(mid 0.249642 -0.249642)
							(end 0.1778 -0.2794)
						)
					)
					(width 0)
					(fill yes)
				)
			)
		)
	)
	(footprint ""
		(layer "F.Cu")
		(at 126.4666 -87.2744 180)
		(property "Reference" "R103"
			(at 0 0 180)
			(layer "F.SilkS")
			(hide yes)
			(effects
				(font
					(size 1.27 1.27)
				)
			)
		)
		(property "Value" "0R2J-2-GP"
			(at 0.064008 -3.993896 180)
			(unlocked yes)
			(layer "F.Fab")
			(hide yes)
			(effects
				(font
					(size 1.016 1.016)
					(thickness 0.1524)
				)
			)
		)
		(property "Device Type" "R402H16"
			(at 0.064008 -5.517896 180)
			(unlocked yes)
			(layer "F.Fab")
			(hide yes)
			(effects
				(font
					(size 1.016 1.016)
					(thickness 0.1524)
				)
			)
		)
		(duplicate_pad_numbers_are_jumpers no)
		(fp_line
			(start 0.508 -0.9398)
			(end -0.508 -0.9398)
			(stroke
				(width 0.1524)
				(type default)
			)
			(layer "F.SilkS")
		)
		(fp_line
			(start -0.508 -0.9398)
			(end -0.508 0.9398)
			(stroke
				(width 0.1524)
				(type default)
			)
			(layer "F.SilkS")
		)
		(fp_rect
			(start -0.508 0.9398)
			(end 0.508 -0.9398)
			(stroke
				(width 0)
				(type default)
			)
			(fill no)
			(layer "F.CrtYd")
		)
		(fp_rect
			(start -0.508 0.9398)
			(end 0.508 -0.9398)
			(stroke
				(width 0)
				(type default)
			)
			(fill no)
			(layer "F.Fab")
		)
		(pad "1" smd custom
			(at 0 -0.4445 180)
			(size 0.1397 0.1397)
			(layers "F.Cu" "F.Mask" "F.Paste")
			(net "SDB_R_RX")
			(options
				(clearance outline)
				(anchor circle)
			)
			(primitives
				(gr_poly
					(pts
						(arc
							(start -0.1778 -0.2794)
							(mid -0.249642 -0.249642)
							(end -0.2794 -0.1778)
						)
						(arc
							(start -0.2794 0.1778)
							(mid -0.249642 0.249642)
							(end -0.1778 0.2794)
						)
						(arc
							(start 0.1778 0.2794)
							(mid 0.249642 0.249642)
							(end 0.2794 0.1778)
						)
						(arc
							(start 0.2794 -0.1778)
							(mid 0.249642 -0.249642)
							(end 0.1778 -0.2794)
						)
					)
					(width 0)
					(fill yes)
				)
			)
		)
		(pad "2" smd custom
			(at 0 0.4445 180)
			(size 0.1397 0.1397)
			(layers "F.Cu" "F.Mask" "F.Paste")
			(net "SDB_RX")
			(options
				(clearance outline)
				(anchor circle)
			)
			(primitives
				(gr_poly
					(pts
						(arc
							(start -0.1778 -0.2794)
							(mid -0.249642 -0.249642)
							(end -0.2794 -0.1778)
						)
						(arc
							(start -0.2794 0.1778)
							(mid -0.249642 0.249642)
							(end -0.1778 0.2794)
						)
						(arc
							(start 0.1778 0.2794)
							(mid 0.249642 0.249642)
							(end 0.2794 0.1778)
						)
						(arc
							(start 0.2794 -0.1778)
							(mid 0.249642 -0.249642)
							(end 0.1778 -0.2794)
						)
					)
					(width 0)
					(fill yes)
				)
			)
		)
	)
	(footprint ""
		(layer "F.Cu")
		(at 185.3946 -120.7516 -90)
		(property "Reference" "R9"
			(at 0 0 270)
			(layer "F.SilkS")
			(hide yes)
			(effects
				(font
					(size 1.27 1.27)
				)
			)
		)
		(property "Value" "1KR2F-3-GP"
			(at 0.064008 -3.993896 270)
			(unlocked yes)
			(layer "F.Fab")
			(hide yes)
			(effects
				(font
					(size 1.016 1.016)
					(thickness 0.1524)
				)
			)
		)
		(property "Device Type" "R402H16"
			(at 0.064008 -5.517896 270)
			(unlocked yes)
			(layer "F.Fab")
			(hide yes)
			(effects
				(font
					(size 1.016 1.016)
					(thickness 0.1524)
				)
			)
		)
		(duplicate_pad_numbers_are_jumpers no)
		(fp_line
			(start -0.508 -0.9398)
			(end -0.508 0.9398)
			(stroke
				(width 0.1524)
				(type default)
			)
			(layer "F.SilkS")
		)
		(fp_line
			(start 0.508 -0.9398)
			(end -0.508 -0.9398)
			(stroke
				(width 0.1524)
				(type default)
			)
			(layer "F.SilkS")
		)
		(fp_rect
			(start -0.508 0.9398)
			(end 0.508 -0.9398)
			(stroke
				(width 0)
				(type default)
			)
			(fill no)
			(layer "F.CrtYd")
		)
		(fp_rect
			(start -0.508 0.9398)
			(end 0.508 -0.9398)
			(stroke
				(width 0)
				(type default)
			)
			(fill no)
			(layer "F.Fab")
		)
		(pad "1" smd custom
			(at 0 -0.4445 270)
			(size 0.1397 0.1397)
			(layers "F.Cu" "F.Mask" "F.Paste")
			(net "P1V8_C")
			(options
				(clearance outline)
				(anchor circle)
			)
			(primitives
				(gr_poly
					(pts
						(arc
							(start -0.1778 -0.2794)
							(mid -0.249642 -0.249642)
							(end -0.2794 -0.1778)
						)
						(arc
							(start -0.2794 0.1778)
							(mid -0.249642 0.249642)
							(end -0.1778 0.2794)
						)
						(arc
							(start 0.1778 0.2794)
							(mid 0.249642 0.249642)
							(end 0.2794 0.1778)
						)
						(arc
							(start 0.2794 -0.1778)
							(mid 0.249642 -0.249642)
							(end 0.1778 -0.2794)
						)
					)
					(width 0)
					(fill yes)
				)
			)
		)
		(pad "2" smd custom
			(at 0 0.4445 270)
			(size 0.1397 0.1397)
			(layers "F.Cu" "F.Mask" "F.Paste")
			(net "GND")
			(options
				(clearance outline)
				(anchor circle)
			)
			(primitives
				(gr_poly
					(pts
						(arc
							(start -0.1778 -0.2794)
							(mid -0.249642 -0.249642)
							(end -0.2794 -0.1778)
						)
						(arc
							(start -0.2794 0.1778)
							(mid -0.249642 0.249642)
							(end -0.1778 0.2794)
						)
						(arc
							(start 0.1778 0.2794)
							(mid 0.249642 0.249642)
							(end 0.2794 0.1778)
						)
						(arc
							(start 0.2794 -0.1778)
							(mid 0.249642 -0.249642)
							(end 0.1778 -0.2794)
						)
					)
					(width 0)
					(fill yes)
				)
			)
		)
	)
	(footprint ""
		(layer "F.Cu")
		(at 72.952356 -73.638918)
		(property "Reference" "R542"
			(at 0 0 0)
			(layer "F.SilkS")
			(hide yes)
			(effects
				(font
					(size 1.27 1.27)
				)
			)
		)
		(property "Value" "0R2J-2-GP"
			(at 0.064008 -3.993896 0)
			(unlocked yes)
			(layer "F.Fab")
			(hide yes)
			(effects
				(font
					(size 1.016 1.016)
					(thickness 0.1524)
				)
			)
		)
		(property "Device Type" "R402H16"
			(at 0.064008 -5.517896 0)
			(unlocked yes)
			(layer "F.Fab")
			(hide yes)
			(effects
				(font
					(size 1.016 1.016)
					(thickness 0.1524)
				)
			)
		)
		(duplicate_pad_numbers_are_jumpers no)
		(fp_line
			(start -0.508 -0.9398)
			(end -0.508 0.9398)
			(stroke
				(width 0.1524)
				(type default)
			)
			(layer "F.SilkS")
		)
		(fp_line
			(start 0.508 -0.9398)
			(end -0.508 -0.9398)
			(stroke
				(width 0.1524)
				(type default)
			)
			(layer "F.SilkS")
		)
		(fp_rect
			(start -0.508 0.9398)
			(end 0.508 -0.9398)
			(stroke
				(width 0)
				(type default)
			)
			(fill no)
			(layer "F.CrtYd")
		)
		(fp_rect
			(start -0.508 0.9398)
			(end 0.508 -0.9398)
			(stroke
				(width 0)
				(type default)
			)
			(fill no)
			(layer "F.Fab")
		)
		(pad "1" smd custom
			(at 0 -0.4445)
			(size 0.1397 0.1397)
			(layers "F.Cu" "F.Mask" "F.Paste")
			(net "I2C_IOC_4_R_SDA")
			(options
				(clearance outline)
				(anchor circle)
			)
			(primitives
				(gr_poly
					(pts
						(arc
							(start -0.1778 -0.2794)
							(mid -0.249642 -0.249642)
							(end -0.2794 -0.1778)
						)
						(arc
							(start -0.2794 0.1778)
							(mid -0.249642 0.249642)
							(end -0.1778 0.2794)
						)
						(arc
							(start 0.1778 0.2794)
							(mid 0.249642 0.249642)
							(end 0.2794 0.1778)
						)
						(arc
							(start 0.2794 -0.1778)
							(mid 0.249642 -0.249642)
							(end 0.1778 -0.2794)
						)
					)
					(width 0)
					(fill yes)
				)
			)
		)
		(pad "2" smd custom
			(at 0 0.4445)
			(size 0.1397 0.1397)
			(layers "F.Cu" "F.Mask" "F.Paste")
			(net "I2C_IOC_4_SDA")
			(options
				(clearance outline)
				(anchor circle)
			)
			(primitives
				(gr_poly
					(pts
						(arc
							(start -0.1778 -0.2794)
							(mid -0.249642 -0.249642)
							(end -0.2794 -0.1778)
						)
						(arc
							(start -0.2794 0.1778)
							(mid -0.249642 0.249642)
							(end -0.1778 0.2794)
						)
						(arc
							(start 0.1778 0.2794)
							(mid 0.249642 0.249642)
							(end 0.2794 0.1778)
						)
						(arc
							(start 0.2794 -0.1778)
							(mid 0.249642 -0.249642)
							(end 0.1778 -0.2794)
						)
					)
					(width 0)
					(fill yes)
				)
			)
		)
	)
	(footprint ""
		(layer "F.Cu")
		(at 157.166818 -95.223076 -90)
		(property "Reference" "R314"
			(at 0 0 270)
			(layer "F.SilkS")
			(hide yes)
			(effects
				(font
					(size 1.27 1.27)
				)
			)
		)
		(property "Value" "0R2J-2-GP"
			(at 0.064008 -3.993896 270)
			(unlocked yes)
			(layer "F.Fab")
			(hide yes)
			(effects
				(font
					(size 1.016 1.016)
					(thickness 0.1524)
				)
			)
		)
		(property "Device Type" "R402H16"
			(at 0.064008 -5.517896 270)
			(unlocked yes)
			(layer "F.Fab")
			(hide yes)
			(effects
				(font
					(size 1.016 1.016)
					(thickness 0.1524)
				)
			)
		)
		(duplicate_pad_numbers_are_jumpers no)
		(fp_line
			(start -0.508 -0.9398)
			(end -0.508 0.9398)
			(stroke
				(width 0.1524)
				(type default)
			)
			(layer "F.SilkS")
		)
		(fp_line
			(start 0.508 -0.9398)
			(end -0.508 -0.9398)
			(stroke
				(width 0.1524)
				(type default)
			)
			(layer "F.SilkS")
		)
		(fp_rect
			(start -0.508 0.9398)
			(end 0.508 -0.9398)
			(stroke
				(width 0)
				(type default)
			)
			(fill no)
			(layer "F.CrtYd")
		)
		(fp_rect
			(start -0.508 0.9398)
			(end 0.508 -0.9398)
			(stroke
				(width 0)
				(type default)
			)
			(fill no)
			(layer "F.Fab")
		)
		(pad "1" smd custom
			(at 0 -0.4445 270)
			(size 0.1397 0.1397)
			(layers "F.Cu" "F.Mask" "F.Paste")
			(net "UART_EXP_TX")
			(options
				(clearance outline)
				(anchor circle)
			)
			(primitives
				(gr_poly
					(pts
						(arc
							(start -0.1778 -0.2794)
							(mid -0.249642 -0.249642)
							(end -0.2794 -0.1778)
						)
						(arc
							(start -0.2794 0.1778)
							(mid -0.249642 0.249642)
							(end -0.1778 0.2794)
						)
						(arc
							(start 0.1778 0.2794)
							(mid 0.249642 0.249642)
							(end 0.2794 0.1778)
						)
						(arc
							(start 0.2794 -0.1778)
							(mid 0.249642 -0.249642)
							(end 0.1778 -0.2794)
						)
					)
					(width 0)
					(fill yes)
				)
			)
		)
		(pad "2" smd custom
			(at 0 0.4445 270)
			(size 0.1397 0.1397)
			(layers "F.Cu" "F.Mask" "F.Paste")
			(net "EXP_SMART_TX_R")
			(options
				(clearance outline)
				(anchor circle)
			)
			(primitives
				(gr_poly
					(pts
						(arc
							(start -0.1778 -0.2794)
							(mid -0.249642 -0.249642)
							(end -0.2794 -0.1778)
						)
						(arc
							(start -0.2794 0.1778)
							(mid -0.249642 0.249642)
							(end -0.1778 0.2794)
						)
						(arc
							(start 0.1778 0.2794)
							(mid 0.249642 0.249642)
							(end 0.2794 0.1778)
						)
						(arc
							(start 0.2794 -0.1778)
							(mid 0.249642 -0.249642)
							(end 0.1778 -0.2794)
						)
					)
					(width 0)
					(fill yes)
				)
			)
		)
	)
	(footprint ""
		(layer "F.Cu")
		(at 139.37615 -63.045086)
		(property "Reference" "VIA15"
			(at 0 0 0)
			(layer "F.SilkS")
			(hide yes)
			(effects
				(font
					(size 1.27 1.27)
				)
			)
		)
		(property "Value" "100OHM-8L-1D6MM-L13-GP"
			(at 3.2893 0.0508 0)
			(unlocked yes)
			(layer "F.Fab")
			(hide yes)
			(effects
				(font
					(size 1.016 1.016)
					(thickness 0.1524)
				)
			)
		)
		(property "Device Type" "VIA-PCIE-4P-409091"
			(at 3.2893 -1.4732 0)
			(unlocked yes)
			(layer "F.Fab")
			(hide yes)
			(effects
				(font
					(size 1.016 1.016)
					(thickness 0.1524)
				)
			)
		)
		(duplicate_pad_numbers_are_jumpers no)
		(fp_rect
			(start -2.0447 0.4572)
			(end 2.0447 -0.4572)
			(stroke
				(width 0)
				(type default)
			)
			(fill no)
			(layer "F.CrtYd")
		)
		(fp_rect
			(start -2.0447 0.4572)
			(end 2.0447 -0.4572)
			(stroke
				(width 0)
				(type default)
			)
			(fill no)
			(layer "F.Fab")
		)
		(pad "1" thru_hole circle
			(at -1.5875 0)
			(size 0.508 0.508)
			(drill 0.254)
			(layers "*.Cu" "*.Mask")
			(remove_unused_layers no)
			(net "GND")
			(clearance 0.2032)
			(thermal_gap 0.2032)
		)
		(pad "2" thru_hole circle
			(at -0.5715 0)
			(size 0.508 0.508)
			(drill 0.254)
			(layers "*.Cu" "*.Mask")
			(remove_unused_layers no)
			(net "PHY_IOC_TO_SCC_C_46_DP")
			(clearance 0.2032)
			(thermal_gap 0.2032)
		)
		(pad "3" thru_hole circle
			(at 0.5715 0)
			(size 0.508 0.508)
			(drill 0.254)
			(layers "*.Cu" "*.Mask")
			(remove_unused_layers no)
			(net "PHY_IOC_TO_SCC_C_46_DN")
			(clearance 0.2032)
			(thermal_gap 0.2032)
		)
		(pad "4" thru_hole circle
			(at 1.5875 0)
			(size 0.508 0.508)
			(drill 0.254)
			(layers "*.Cu" "*.Mask")
			(remove_unused_layers no)
			(net "GND")
			(clearance 0.2032)
			(thermal_gap 0.2032)
		)
	)
	(footprint ""
		(layer "F.Cu")
		(at 160.274 -73.34123 90)
		(property "Reference" "C533"
			(at 0 0 90)
			(layer "F.SilkS")
			(hide yes)
			(effects
				(font
					(size 1.27 1.27)
				)
			)
		)
		(property "Value" "SCD1U16V2KX-3GP"
			(at 1.1811 -2.7051 90)
			(unlocked yes)
			(layer "F.Fab")
			(hide yes)
			(effects
				(font
					(size 1.016 1.016)
					(thickness 0.1524)
				)
			)
		)
		(property "Device Type" "C402H22"
			(at 1.1811 -4.2291 90)
			(unlocked yes)
			(layer "F.Fab")
			(hide yes)
			(effects
				(font
					(size 1.016 1.016)
					(thickness 0.1524)
				)
			)
		)
		(duplicate_pad_numbers_are_jumpers no)
		(fp_rect
			(start -0.4318 0.9525)
			(end 0.4318 -0.9525)
			(stroke
				(width 0)
				(type default)
			)
			(fill no)
			(layer "F.CrtYd")
		)
		(fp_rect
			(start -0.4318 0.9525)
			(end 0.4318 -0.9525)
			(stroke
				(width 0)
				(type default)
			)
			(fill no)
			(layer "F.Fab")
		)
		(pad "1" smd custom
			(at 0 -0.4445 90)
			(size 0.1524 0.1524)
			(layers "F.Cu" "F.Mask" "F.Paste")
			(net "P0V975_SENSE")
			(options
				(clearance outline)
				(anchor circle)
			)
			(primitives
				(gr_poly
					(pts
						(arc
							(start 0.3048 -0.2032)
							(mid 0.275042 -0.275042)
							(end 0.2032 -0.3048)
						)
						(arc
							(start -0.2032 -0.3048)
							(mid -0.275042 -0.275042)
							(end -0.3048 -0.2032)
						)
						(arc
							(start -0.3048 0.2032)
							(mid -0.275042 0.275042)
							(end -0.2032 0.3048)
						)
						(arc
							(start 0.2032 0.3048)
							(mid 0.275042 0.275042)
							(end 0.3048 0.2032)
						)
					)
					(width 0)
					(fill yes)
				)
			)
		)
		(pad "2" smd custom
			(at 0 0.4445 90)
			(size 0.1524 0.1524)
			(layers "F.Cu" "F.Mask" "F.Paste")
			(net "GND")
			(options
				(clearance outline)
				(anchor circle)
			)
			(primitives
				(gr_poly
					(pts
						(arc
							(start 0.3048 -0.2032)
							(mid 0.275042 -0.275042)
							(end 0.2032 -0.3048)
						)
						(arc
							(start -0.2032 -0.3048)
							(mid -0.275042 -0.275042)
							(end -0.3048 -0.2032)
						)
						(arc
							(start -0.3048 0.2032)
							(mid -0.275042 0.275042)
							(end -0.2032 0.3048)
						)
						(arc
							(start 0.2032 0.3048)
							(mid 0.275042 0.275042)
							(end 0.3048 0.2032)
						)
					)
					(width 0)
					(fill yes)
				)
			)
		)
	)
	(footprint ""
		(layer "F.Cu")
		(at 169.574718 -90.415618)
		(property "Reference" "R694"
			(at 0 0 0)
			(layer "F.SilkS")
			(hide yes)
			(effects
				(font
					(size 1.27 1.27)
				)
			)
		)
		(property "Value" "2D2R5F-2-GP"
			(at 0 -8.9535 0)
			(unlocked yes)
			(layer "F.Fab")
			(hide yes)
			(effects
				(font
					(size 1.27 1.016)
					(thickness 0.1524)
				)
			)
		)
		(property "Device Type" "R805H24"
			(at 0 -10.6299 0)
			(unlocked yes)
			(layer "F.Fab")
			(hide yes)
			(effects
				(font
					(size 1.27 1.016)
					(thickness 0.1524)
				)
			)
		)
		(duplicate_pad_numbers_are_jumpers no)
		(fp_line
			(start -0.889 -1.7018)
			(end -0.889 0.2794)
			(stroke
				(width 0.1524)
				(type default)
			)
			(layer "F.SilkS")
		)
		(fp_line
			(start -0.889 0.0762)
			(end -0.889 1.7018)
			(stroke
				(width 0.1524)
				(type default)
			)
			(layer "F.SilkS")
		)
		(fp_line
			(start -0.889 1.7018)
			(end 0.889 1.7018)
			(stroke
				(width 0.1524)
				(type default)
			)
			(layer "F.SilkS")
		)
		(fp_line
			(start 0.889 -1.7018)
			(end -0.889 -1.7018)
			(stroke
				(width 0.1524)
				(type default)
			)
			(layer "F.SilkS")
		)
		(fp_line
			(start 0.889 -1.7018)
			(end 0.889 -0.381)
			(stroke
				(width 0.1524)
				(type default)
			)
			(layer "F.SilkS")
		)
		(fp_line
			(start 0.889 1.7018)
			(end 0.889 -0.508)
			(stroke
				(width 0.1524)
				(type default)
			)
			(layer "F.SilkS")
		)
		(fp_poly
			(pts
				(xy 0.9652 -1.778) (xy 0.9652 1.778) (xy -0.9652 1.778) (xy -0.9652 -1.778)
			)
			(stroke
				(width 0)
				(type default)
			)
			(fill no)
			(layer "F.CrtYd")
		)
		(fp_rect
			(start -0.9652 1.778)
			(end 0.9652 -1.778)
			(stroke
				(width 0)
				(type default)
			)
			(fill no)
			(layer "F.Fab")
		)
		(pad "1" smd rect
			(at 0 -0.9652)
			(size 1.397 1.143)
			(layers "F.Cu" "F.Mask" "F.Paste")
			(net "VT235_VX")
		)
		(pad "2" smd rect
			(at 0 0.9652)
			(size 1.397 1.143)
			(layers "F.Cu" "F.Mask" "F.Paste")
			(net "VT235_VX_R")
		)
	)
	(footprint ""
		(layer "F.Cu")
		(at 33.9344 -46.5836)
		(property "Reference" "L30"
			(at 0 0 0)
			(layer "F.SilkS")
			(hide yes)
			(effects
				(font
					(size 1.27 1.27)
				)
			)
		)
		(property "Value" "BLM41PG600-GP"
			(at -3.690874 -7.441184 0)
			(unlocked yes)
			(layer "F.Fab")
			(hide yes)
			(effects
				(font
					(size 1.016 1.016)
					(thickness 0.1524)
				)
			)
		)
		(property "Device Type" "L451616H71"
			(at -3.690874 -5.917184 0)
			(unlocked yes)
			(layer "F.Fab")
			(hide yes)
			(effects
				(font
					(size 1.016 1.016)
					(thickness 0.1524)
				)
			)
		)
		(duplicate_pad_numbers_are_jumpers no)
		(fp_line
			(start -2.8702 -1.2954)
			(end -2.8702 1.2954)
			(stroke
				(width 0.1524)
				(type default)
			)
			(layer "F.SilkS")
		)
		(fp_line
			(start -2.8702 -1.2954)
			(end -2.8702 1.2954)
			(stroke
				(width 0.1524)
				(type default)
			)
			(layer "F.SilkS")
		)
		(fp_line
			(start -2.8702 1.2954)
			(end 2.8702 1.2954)
			(stroke
				(width 0.1524)
				(type default)
			)
			(layer "F.SilkS")
		)
		(fp_line
			(start -2.8702 1.2954)
			(end 2.8702 1.2954)
			(stroke
				(width 0.1524)
				(type default)
			)
			(layer "F.SilkS")
		)
		(fp_line
			(start 2.8702 -1.2954)
			(end -2.8702 -1.2954)
			(stroke
				(width 0.1524)
				(type default)
			)
			(layer "F.SilkS")
		)
		(fp_line
			(start 2.8702 -1.2954)
			(end -2.8702 -1.2954)
			(stroke
				(width 0.1524)
				(type default)
			)
			(layer "F.SilkS")
		)
		(fp_line
			(start 2.8702 1.2954)
			(end 2.8702 -1.2954)
			(stroke
				(width 0.1524)
				(type default)
			)
			(layer "F.SilkS")
		)
		(fp_line
			(start 2.8702 1.2954)
			(end 2.8702 -1.2954)
			(stroke
				(width 0.1524)
				(type default)
			)
			(layer "F.SilkS")
		)
		(fp_poly
			(pts
				(xy -2.8702 1.2954) (xy 2.8702 1.2954) (xy 2.8702 -1.2954) (xy -2.8702 -1.2954)
			)
			(stroke
				(width 0)
				(type default)
			)
			(fill no)
			(layer "F.CrtYd")
		)
		(fp_poly
			(pts
				(xy -2.8702 1.2954) (xy 2.8702 1.2954) (xy 2.8702 -1.2954) (xy -2.8702 -1.2954)
			)
			(stroke
				(width 0)
				(type default)
			)
			(fill no)
			(layer "F.Fab")
		)
		(pad "1" smd rect
			(at -1.9685 0)
			(size 1.3716 1.8796)
			(layers "F.Cu" "F.Mask" "F.Paste")
			(net "P12V_STBY_SCC")
		)
		(pad "2" smd rect
			(at 1.9685 0)
			(size 1.3716 1.8796)
			(layers "F.Cu" "F.Mask" "F.Paste")
			(net "P12V_STBY_VIN_Q7")
		)
	)
	(footprint ""
		(layer "F.Cu")
		(at 121.92 -92.0496 90)
		(property "Reference" "R564"
			(at 0 0 90)
			(layer "F.SilkS")
			(hide yes)
			(effects
				(font
					(size 1.27 1.27)
				)
			)
		)
		(property "Value" "10KR2F-2-GP"
			(at 0.064008 -3.993896 90)
			(unlocked yes)
			(layer "F.Fab")
			(hide yes)
			(effects
				(font
					(size 1.016 1.016)
					(thickness 0.1524)
				)
			)
		)
		(property "Device Type" "R402H16"
			(at 0.064008 -5.517896 90)
			(unlocked yes)
			(layer "F.Fab")
			(hide yes)
			(effects
				(font
					(size 1.016 1.016)
					(thickness 0.1524)
				)
			)
		)
		(duplicate_pad_numbers_are_jumpers no)
		(fp_line
			(start 0.508 -0.9398)
			(end -0.508 -0.9398)
			(stroke
				(width 0.1524)
				(type default)
			)
			(layer "F.SilkS")
		)
		(fp_line
			(start -0.508 -0.9398)
			(end -0.508 0.9398)
			(stroke
				(width 0.1524)
				(type default)
			)
			(layer "F.SilkS")
		)
		(fp_rect
			(start -0.508 0.9398)
			(end 0.508 -0.9398)
			(stroke
				(width 0)
				(type default)
			)
			(fill no)
			(layer "F.CrtYd")
		)
		(fp_rect
			(start -0.508 0.9398)
			(end 0.508 -0.9398)
			(stroke
				(width 0)
				(type default)
			)
			(fill no)
			(layer "F.Fab")
		)
		(pad "1" smd custom
			(at 0 -0.4445 90)
			(size 0.1397 0.1397)
			(layers "F.Cu" "F.Mask" "F.Paste")
			(net "BMC_SPARE_1_LS")
			(options
				(clearance outline)
				(anchor circle)
			)
			(primitives
				(gr_poly
					(pts
						(arc
							(start -0.1778 -0.2794)
							(mid -0.249642 -0.249642)
							(end -0.2794 -0.1778)
						)
						(arc
							(start -0.2794 0.1778)
							(mid -0.249642 0.249642)
							(end -0.1778 0.2794)
						)
						(arc
							(start 0.1778 0.2794)
							(mid 0.249642 0.249642)
							(end 0.2794 0.1778)
						)
						(arc
							(start 0.2794 -0.1778)
							(mid 0.249642 -0.249642)
							(end 0.1778 -0.2794)
						)
					)
					(width 0)
					(fill yes)
				)
			)
		)
		(pad "2" smd custom
			(at 0 0.4445 90)
			(size 0.1397 0.1397)
			(layers "F.Cu" "F.Mask" "F.Paste")
			(net "P1V8_E")
			(options
				(clearance outline)
				(anchor circle)
			)
			(primitives
				(gr_poly
					(pts
						(arc
							(start -0.1778 -0.2794)
							(mid -0.249642 -0.249642)
							(end -0.2794 -0.1778)
						)
						(arc
							(start -0.2794 0.1778)
							(mid -0.249642 0.249642)
							(end -0.1778 0.2794)
						)
						(arc
							(start 0.1778 0.2794)
							(mid 0.249642 0.249642)
							(end 0.2794 0.1778)
						)
						(arc
							(start 0.2794 -0.1778)
							(mid 0.249642 -0.249642)
							(end 0.1778 -0.2794)
						)
					)
					(width 0)
					(fill yes)
				)
			)
		)
	)
	(footprint ""
		(layer "F.Cu")
		(at 181.821836 -120.8024 90)
		(property "Reference" "C687"
			(at 0 0 90)
			(layer "F.SilkS")
			(hide yes)
			(effects
				(font
					(size 1.27 1.27)
				)
			)
		)
		(property "Value" "SC10U6D3V5KX-4GP"
			(at -0.0762 -6.1214 90)
			(unlocked yes)
			(layer "F.Fab")
			(hide yes)
			(effects
				(font
					(size 1.016 1.016)
					(thickness 0.1524)
				)
			)
		)
		(property "Device Type" "C805H58"
			(at -0.0762 -8.1534 90)
			(unlocked yes)
			(layer "F.Fab")
			(hide yes)
			(effects
				(font
					(size 1.016 1.016)
					(thickness 0.1524)
				)
			)
		)
		(duplicate_pad_numbers_are_jumpers no)
		(fp_line
			(start 0.635 0)
			(end -0.635 0)
			(stroke
				(width 0.508)
				(type default)
			)
			(layer "F.SilkS")
		)
		(fp_rect
			(start -0.9652 1.778)
			(end 0.9652 -1.778)
			(stroke
				(width 0)
				(type default)
			)
			(fill no)
			(layer "F.CrtYd")
		)
		(fp_poly
			(pts
				(xy -0.9652 -1.778) (xy 0.9652 -1.778) (xy 0.9652 1.778) (xy -0.9652 1.778)
			)
			(stroke
				(width 0)
				(type default)
			)
			(fill no)
			(layer "F.Fab")
		)
		(pad "1" smd rect
			(at 0 -0.9652 90)
			(size 1.397 1.143)
			(layers "F.Cu" "F.Mask" "F.Paste")
			(net "P1V8_E_OUT")
		)
		(pad "2" smd rect
			(at 0 0.9652 90)
			(size 1.397 1.143)
			(layers "F.Cu" "F.Mask" "F.Paste")
			(net "GND")
		)
	)
	(footprint ""
		(layer "F.Cu")
		(at 44.0182 -26.543 90)
		(property "Reference" "C673"
			(at 0 0 90)
			(layer "F.SilkS")
			(hide yes)
			(effects
				(font
					(size 1.27 1.27)
				)
			)
		)
		(property "Value" "SCD1U50V3KX-GP"
			(at 0 -2.8194 90)
			(unlocked yes)
			(layer "F.Fab")
			(hide yes)
			(effects
				(font
					(size 1.016 1.016)
					(thickness 0.1524)
				)
			)
		)
		(property "Device Type" "C603H36"
			(at 0 -4.3434 90)
			(unlocked yes)
			(layer "F.Fab")
			(hide yes)
			(effects
				(font
					(size 1.016 1.016)
					(thickness 0.1524)
				)
			)
		)
		(duplicate_pad_numbers_are_jumpers no)
		(fp_line
			(start 0.508 0)
			(end -0.508 0)
			(stroke
				(width 0.2032)
				(type default)
			)
			(layer "F.SilkS")
		)
		(fp_rect
			(start -0.5842 1.3335)
			(end 0.5842 -1.3335)
			(stroke
				(width 0)
				(type default)
			)
			(fill no)
			(layer "F.CrtYd")
		)
		(fp_rect
			(start -0.5842 1.3335)
			(end 0.5842 -1.3335)
			(stroke
				(width 0)
				(type default)
			)
			(fill no)
			(layer "F.Fab")
		)
		(pad "1" smd custom
			(at 0 -0.762 90)
			(size 0.2159 0.2159)
			(layers "F.Cu" "F.Mask" "F.Paste")
			(net "P0V9_VREF")
			(options
				(clearance outline)
				(anchor circle)
			)
			(primitives
				(gr_poly
					(pts
						(arc
							(start -0.3302 -0.4318)
							(mid -0.402042 -0.402042)
							(end -0.4318 -0.3302)
						)
						(arc
							(start -0.4318 0.3302)
							(mid -0.402042 0.402042)
							(end -0.3302 0.4318)
						)
						(arc
							(start 0.3302 0.4318)
							(mid 0.402042 0.402042)
							(end 0.4318 0.3302)
						)
						(arc
							(start 0.4318 -0.3302)
							(mid 0.402042 -0.402042)
							(end 0.3302 -0.4318)
						)
					)
					(width 0)
					(fill yes)
				)
			)
		)
		(pad "2" smd custom
			(at 0 0.762 90)
			(size 0.2159 0.2159)
			(layers "F.Cu" "F.Mask" "F.Paste")
			(net "P0V9_GSNS")
			(options
				(clearance outline)
				(anchor circle)
			)
			(primitives
				(gr_poly
					(pts
						(arc
							(start -0.3302 -0.4318)
							(mid -0.402042 -0.402042)
							(end -0.4318 -0.3302)
						)
						(arc
							(start -0.4318 0.3302)
							(mid -0.402042 0.402042)
							(end -0.3302 0.4318)
						)
						(arc
							(start 0.3302 0.4318)
							(mid 0.402042 0.402042)
							(end 0.4318 0.3302)
						)
						(arc
							(start 0.4318 -0.3302)
							(mid 0.402042 -0.402042)
							(end 0.3302 -0.4318)
						)
					)
					(width 0)
					(fill yes)
				)
			)
		)
	)
	(footprint ""
		(layer "F.Cu")
		(at 155.755594 -71.60387)
		(property "Reference" "R325"
			(at 0 0 0)
			(layer "F.SilkS")
			(hide yes)
			(effects
				(font
					(size 1.27 1.27)
				)
			)
		)
		(property "Value" "0R2J-2-GP"
			(at 0.064008 -3.993896 0)
			(unlocked yes)
			(layer "F.Fab")
			(hide yes)
			(effects
				(font
					(size 1.016 1.016)
					(thickness 0.1524)
				)
			)
		)
		(property "Device Type" "R402H16"
			(at 0.064008 -5.517896 0)
			(unlocked yes)
			(layer "F.Fab")
			(hide yes)
			(effects
				(font
					(size 1.016 1.016)
					(thickness 0.1524)
				)
			)
		)
		(duplicate_pad_numbers_are_jumpers no)
		(fp_line
			(start -0.508 -0.9398)
			(end -0.508 0.9398)
			(stroke
				(width 0.1524)
				(type default)
			)
			(layer "F.SilkS")
		)
		(fp_line
			(start 0.508 -0.9398)
			(end -0.508 -0.9398)
			(stroke
				(width 0.1524)
				(type default)
			)
			(layer "F.SilkS")
		)
		(fp_rect
			(start -0.508 0.9398)
			(end 0.508 -0.9398)
			(stroke
				(width 0)
				(type default)
			)
			(fill no)
			(layer "F.CrtYd")
		)
		(fp_rect
			(start -0.508 0.9398)
			(end 0.508 -0.9398)
			(stroke
				(width 0)
				(type default)
			)
			(fill no)
			(layer "F.Fab")
		)
		(pad "1" smd custom
			(at 0 -0.4445)
			(size 0.1397 0.1397)
			(layers "F.Cu" "F.Mask" "F.Paste")
			(net "VOL_SEN2_SCL")
			(options
				(clearance outline)
				(anchor circle)
			)
			(primitives
				(gr_poly
					(pts
						(arc
							(start -0.1778 -0.2794)
							(mid -0.249642 -0.249642)
							(end -0.2794 -0.1778)
						)
						(arc
							(start -0.2794 0.1778)
							(mid -0.249642 0.249642)
							(end -0.1778 0.2794)
						)
						(arc
							(start 0.1778 0.2794)
							(mid 0.249642 0.249642)
							(end 0.2794 0.1778)
						)
						(arc
							(start 0.2794 -0.1778)
							(mid 0.249642 -0.249642)
							(end 0.1778 -0.2794)
						)
					)
					(width 0)
					(fill yes)
				)
			)
		)
		(pad "2" smd custom
			(at 0 0.4445)
			(size 0.1397 0.1397)
			(layers "F.Cu" "F.Mask" "F.Paste")
			(net "I2C_SCC_SCL2")
			(options
				(clearance outline)
				(anchor circle)
			)
			(primitives
				(gr_poly
					(pts
						(arc
							(start -0.1778 -0.2794)
							(mid -0.249642 -0.249642)
							(end -0.2794 -0.1778)
						)
						(arc
							(start -0.2794 0.1778)
							(mid -0.249642 0.249642)
							(end -0.1778 0.2794)
						)
						(arc
							(start 0.1778 0.2794)
							(mid 0.249642 0.249642)
							(end 0.2794 0.1778)
						)
						(arc
							(start 0.2794 -0.1778)
							(mid 0.249642 -0.249642)
							(end 0.1778 -0.2794)
						)
					)
					(width 0)
					(fill yes)
				)
			)
		)
	)
	(footprint ""
		(layer "F.Cu")
		(at 91.44 -86.487 -90)
		(property "Reference" "R305"
			(at 0 0 270)
			(layer "F.SilkS")
			(hide yes)
			(effects
				(font
					(size 1.27 1.27)
				)
			)
		)
		(property "Value" "10KR2F-2-GP"
			(at 0.064008 -3.993896 270)
			(unlocked yes)
			(layer "F.Fab")
			(hide yes)
			(effects
				(font
					(size 1.016 1.016)
					(thickness 0.1524)
				)
			)
		)
		(property "Device Type" "R402H16"
			(at 0.064008 -5.517896 270)
			(unlocked yes)
			(layer "F.Fab")
			(hide yes)
			(effects
				(font
					(size 1.016 1.016)
					(thickness 0.1524)
				)
			)
		)
		(duplicate_pad_numbers_are_jumpers no)
		(fp_line
			(start -0.508 -0.9398)
			(end -0.508 0.9398)
			(stroke
				(width 0.1524)
				(type default)
			)
			(layer "F.SilkS")
		)
		(fp_line
			(start 0.508 -0.9398)
			(end -0.508 -0.9398)
			(stroke
				(width 0.1524)
				(type default)
			)
			(layer "F.SilkS")
		)
		(fp_rect
			(start -0.508 0.9398)
			(end 0.508 -0.9398)
			(stroke
				(width 0)
				(type default)
			)
			(fill no)
			(layer "F.CrtYd")
		)
		(fp_rect
			(start -0.508 0.9398)
			(end 0.508 -0.9398)
			(stroke
				(width 0)
				(type default)
			)
			(fill no)
			(layer "F.Fab")
		)
		(pad "1" smd custom
			(at 0 -0.4445 270)
			(size 0.1397 0.1397)
			(layers "F.Cu" "F.Mask" "F.Paste")
			(net "BMC_LOC_HEARTBEAT_LS")
			(options
				(clearance outline)
				(anchor circle)
			)
			(primitives
				(gr_poly
					(pts
						(arc
							(start -0.1778 -0.2794)
							(mid -0.249642 -0.249642)
							(end -0.2794 -0.1778)
						)
						(arc
							(start -0.2794 0.1778)
							(mid -0.249642 0.249642)
							(end -0.1778 0.2794)
						)
						(arc
							(start 0.1778 0.2794)
							(mid 0.249642 0.249642)
							(end 0.2794 0.1778)
						)
						(arc
							(start 0.2794 -0.1778)
							(mid 0.249642 -0.249642)
							(end 0.1778 -0.2794)
						)
					)
					(width 0)
					(fill yes)
				)
			)
		)
		(pad "2" smd custom
			(at 0 0.4445 270)
			(size 0.1397 0.1397)
			(layers "F.Cu" "F.Mask" "F.Paste")
			(net "GND")
			(options
				(clearance outline)
				(anchor circle)
			)
			(primitives
				(gr_poly
					(pts
						(arc
							(start -0.1778 -0.2794)
							(mid -0.249642 -0.249642)
							(end -0.2794 -0.1778)
						)
						(arc
							(start -0.2794 0.1778)
							(mid -0.249642 0.249642)
							(end -0.1778 0.2794)
						)
						(arc
							(start 0.1778 0.2794)
							(mid 0.249642 0.249642)
							(end 0.2794 0.1778)
						)
						(arc
							(start 0.2794 -0.1778)
							(mid 0.249642 -0.249642)
							(end 0.1778 -0.2794)
						)
					)
					(width 0)
					(fill yes)
				)
			)
		)
	)
	(footprint ""
		(layer "F.Cu")
		(at 179.02047 -82.652108)
		(property "Reference" "C627"
			(at 0 0 0)
			(layer "F.SilkS")
			(hide yes)
			(effects
				(font
					(size 1.27 1.27)
				)
			)
		)
		(property "Value" "SC10U6D3V5KX-4GP"
			(at -0.0762 -6.1214 0)
			(unlocked yes)
			(layer "F.Fab")
			(hide yes)
			(effects
				(font
					(size 1.016 1.016)
					(thickness 0.1524)
				)
			)
		)
		(property "Device Type" "C805H58"
			(at -0.0762 -8.1534 0)
			(unlocked yes)
			(layer "F.Fab")
			(hide yes)
			(effects
				(font
					(size 1.016 1.016)
					(thickness 0.1524)
				)
			)
		)
		(duplicate_pad_numbers_are_jumpers no)
		(fp_line
			(start 0.635 0)
			(end -0.635 0)
			(stroke
				(width 0.508)
				(type default)
			)
			(layer "F.SilkS")
		)
		(fp_rect
			(start -0.9652 1.778)
			(end 0.9652 -1.778)
			(stroke
				(width 0)
				(type default)
			)
			(fill no)
			(layer "F.CrtYd")
		)
		(fp_poly
			(pts
				(xy -0.9652 -1.778) (xy 0.9652 -1.778) (xy 0.9652 1.778) (xy -0.9652 1.778)
			)
			(stroke
				(width 0)
				(type default)
			)
			(fill no)
			(layer "F.Fab")
		)
		(pad "1" smd rect
			(at 0 -0.9652)
			(size 1.397 1.143)
			(layers "F.Cu" "F.Mask" "F.Paste")
			(net "P0V975")
		)
		(pad "2" smd rect
			(at 0 0.9652)
			(size 1.397 1.143)
			(layers "F.Cu" "F.Mask" "F.Paste")
			(net "GND")
		)
	)
	(footprint ""
		(layer "F.Cu")
		(at 132.220208 -46.386242 90)
		(property "Reference" "VIA12"
			(at 0 0 90)
			(layer "F.SilkS")
			(hide yes)
			(effects
				(font
					(size 1.27 1.27)
				)
			)
		)
		(property "Value" "100OHM-8L-1D6MM-L13-GP"
			(at 3.2893 0.0508 90)
			(unlocked yes)
			(layer "F.Fab")
			(hide yes)
			(effects
				(font
					(size 1.016 1.016)
					(thickness 0.1524)
				)
			)
		)
		(property "Device Type" "VIA-PCIE-4P-409091"
			(at 3.2893 -1.4732 90)
			(unlocked yes)
			(layer "F.Fab")
			(hide yes)
			(effects
				(font
					(size 1.016 1.016)
					(thickness 0.1524)
				)
			)
		)
		(duplicate_pad_numbers_are_jumpers no)
		(fp_rect
			(start -2.0447 0.4572)
			(end 2.0447 -0.4572)
			(stroke
				(width 0)
				(type default)
			)
			(fill no)
			(layer "F.CrtYd")
		)
		(fp_rect
			(start -2.0447 0.4572)
			(end 2.0447 -0.4572)
			(stroke
				(width 0)
				(type default)
			)
			(fill no)
			(layer "F.Fab")
		)
		(pad "1" thru_hole circle
			(at -1.5875 0 90)
			(size 0.508 0.508)
			(drill 0.254)
			(layers "*.Cu" "*.Mask")
			(remove_unused_layers no)
			(net "GND")
			(clearance 0.2032)
			(thermal_gap 0.2032)
		)
		(pad "2" thru_hole circle
			(at -0.5715 0 90)
			(size 0.508 0.508)
			(drill 0.254)
			(layers "*.Cu" "*.Mask")
			(remove_unused_layers no)
			(net "PHY_IOC_TO_SCC_C_43_DP")
			(clearance 0.2032)
			(thermal_gap 0.2032)
		)
		(pad "3" thru_hole circle
			(at 0.5715 0 90)
			(size 0.508 0.508)
			(drill 0.254)
			(layers "*.Cu" "*.Mask")
			(remove_unused_layers no)
			(net "PHY_IOC_TO_SCC_C_43_DN")
			(clearance 0.2032)
			(thermal_gap 0.2032)
		)
		(pad "4" thru_hole circle
			(at 1.5875 0 90)
			(size 0.508 0.508)
			(drill 0.254)
			(layers "*.Cu" "*.Mask")
			(remove_unused_layers no)
			(net "GND")
			(clearance 0.2032)
			(thermal_gap 0.2032)
		)
	)
	(footprint ""
		(layer "F.Cu")
		(at 190.87338 -78.49108 180)
		(property "Reference" "R365"
			(at 0 0 180)
			(layer "F.SilkS")
			(hide yes)
			(effects
				(font
					(size 1.27 1.27)
				)
			)
		)
		(property "Value" "4K7R2F-GP"
			(at 0.064008 -3.993896 180)
			(unlocked yes)
			(layer "F.Fab")
			(hide yes)
			(effects
				(font
					(size 1.016 1.016)
					(thickness 0.1524)
				)
			)
		)
		(property "Device Type" "R402H16"
			(at 0.064008 -5.517896 180)
			(unlocked yes)
			(layer "F.Fab")
			(hide yes)
			(effects
				(font
					(size 1.016 1.016)
					(thickness 0.1524)
				)
			)
		)
		(duplicate_pad_numbers_are_jumpers no)
		(fp_line
			(start 0.508 -0.9398)
			(end -0.508 -0.9398)
			(stroke
				(width 0.1524)
				(type default)
			)
			(layer "F.SilkS")
		)
		(fp_line
			(start -0.508 -0.9398)
			(end -0.508 0.9398)
			(stroke
				(width 0.1524)
				(type default)
			)
			(layer "F.SilkS")
		)
		(fp_rect
			(start -0.508 0.9398)
			(end 0.508 -0.9398)
			(stroke
				(width 0)
				(type default)
			)
			(fill no)
			(layer "F.CrtYd")
		)
		(fp_rect
			(start -0.508 0.9398)
			(end 0.508 -0.9398)
			(stroke
				(width 0)
				(type default)
			)
			(fill no)
			(layer "F.Fab")
		)
		(pad "1" smd custom
			(at 0 -0.4445 180)
			(size 0.1397 0.1397)
			(layers "F.Cu" "F.Mask" "F.Paste")
			(net "TEMP2_A1")
			(options
				(clearance outline)
				(anchor circle)
			)
			(primitives
				(gr_poly
					(pts
						(arc
							(start -0.1778 -0.2794)
							(mid -0.249642 -0.249642)
							(end -0.2794 -0.1778)
						)
						(arc
							(start -0.2794 0.1778)
							(mid -0.249642 0.249642)
							(end -0.1778 0.2794)
						)
						(arc
							(start 0.1778 0.2794)
							(mid 0.249642 0.249642)
							(end 0.2794 0.1778)
						)
						(arc
							(start 0.2794 -0.1778)
							(mid 0.249642 -0.249642)
							(end 0.1778 -0.2794)
						)
					)
					(width 0)
					(fill yes)
				)
			)
		)
		(pad "2" smd custom
			(at 0 0.4445 180)
			(size 0.1397 0.1397)
			(layers "F.Cu" "F.Mask" "F.Paste")
			(net "GND")
			(options
				(clearance outline)
				(anchor circle)
			)
			(primitives
				(gr_poly
					(pts
						(arc
							(start -0.1778 -0.2794)
							(mid -0.249642 -0.249642)
							(end -0.2794 -0.1778)
						)
						(arc
							(start -0.2794 0.1778)
							(mid -0.249642 0.249642)
							(end -0.1778 0.2794)
						)
						(arc
							(start 0.1778 0.2794)
							(mid 0.249642 0.249642)
							(end 0.2794 0.1778)
						)
						(arc
							(start 0.2794 -0.1778)
							(mid 0.249642 -0.249642)
							(end 0.1778 -0.2794)
						)
					)
					(width 0)
					(fill yes)
				)
			)
		)
	)
	(footprint ""
		(layer "F.Cu")
		(at 63.97498 -100.50018)
		(property "Reference" "U10"
			(at 0 0 0)
			(layer "F.SilkS")
			(hide yes)
			(effects
				(font
					(size 1.27 1.27)
				)
			)
		)
		(property "Value" "TPS53318DQPR-GP"
			(at -5.022088 -6.851904 0)
			(unlocked yes)
			(layer "F.Fab")
			(hide yes)
			(effects
				(font
					(size 1.016 1.016)
					(thickness 0.1524)
				)
			)
		)
		(property "Device Type" "DFN22G6050-G6133H60"
			(at -5.022088 -8.375904 0)
			(unlocked yes)
			(layer "F.Fab")
			(hide yes)
			(effects
				(font
					(size 1.016 1.016)
					(thickness 0.1524)
				)
			)
		)
		(duplicate_pad_numbers_are_jumpers no)
		(fp_line
			(start -3.5052 -3.5179)
			(end -3.5052 -2.2479)
			(stroke
				(width 0.1524)
				(type default)
			)
			(layer "F.SilkS")
		)
		(fp_line
			(start -3.5052 2.2479)
			(end -3.5052 3.5179)
			(stroke
				(width 0.1524)
				(type default)
			)
			(layer "F.SilkS")
		)
		(fp_line
			(start -3.5052 3.5179)
			(end -2.2352 3.5179)
			(stroke
				(width 0.1524)
				(type default)
			)
			(layer "F.SilkS")
		)
		(fp_line
			(start -2.2352 -3.5179)
			(end -3.5052 -3.5179)
			(stroke
				(width 0.1524)
				(type default)
			)
			(layer "F.SilkS")
		)
		(fp_line
			(start -1.999996 -3.262122)
			(end -1.999996 -4.024122)
			(stroke
				(width 0.1524)
				(type default)
			)
			(layer "F.SilkS")
		)
		(fp_line
			(start -0.999998 3.262122)
			(end -0.999998 3.770122)
			(stroke
				(width 0.1524)
				(type default)
			)
			(layer "F.SilkS")
		)
		(fp_line
			(start 0.500126 -3.262122)
			(end 0.500126 -3.770122)
			(stroke
				(width 0.1524)
				(type default)
			)
			(layer "F.SilkS")
		)
		(fp_line
			(start 1.500124 3.262122)
			(end 1.500124 4.024122)
			(stroke
				(width 0.1524)
				(type default)
			)
			(layer "F.SilkS")
		)
		(fp_line
			(start 2.2352 3.5179)
			(end 3.5052 3.5179)
			(stroke
				(width 0.1524)
				(type default)
			)
			(layer "F.SilkS")
		)
		(fp_line
			(start 3.5052 3.5179)
			(end 3.5052 2.2479)
			(stroke
				(width 0.1524)
				(type default)
			)
			(layer "F.SilkS")
		)
		(fp_poly
			(pts
				(xy 3.5052 -3.5179) (xy 2.4765 -3.5179) (xy 3.5052 -2.4892)
			)
			(stroke
				(width 0)
				(type default)
			)
			(fill yes)
			(layer "F.SilkS")
		)
		(fp_rect
			(start -2.9972 2.5019)
			(end 2.9972 -2.5019)
			(stroke
				(width 0)
				(type default)
			)
			(fill no)
			(layer "F.CrtYd")
		)
		(fp_poly
			(pts
				(xy 3.556 -2.5019) (xy -2.9972 -2.5019) (xy -2.9972 2.5019) (xy 2.9972 2.5019) (xy 2.9972 -2.4892)
				(xy 3.556 -2.4892) (xy 3.556 3.5179) (xy -3.556 3.5179) (xy -3.556 -3.5179) (xy 3.556 -3.5179)
			)
			(stroke
				(width 0)
				(type default)
			)
			(fill no)
			(layer "F.CrtYd")
		)
		(fp_rect
			(start -3.556 3.5179)
			(end 3.556 -3.5179)
			(stroke
				(width 0)
				(type default)
			)
			(fill no)
			(layer "F.Fab")
		)
		(pad "1" smd rect
			(at 2.500122 -2.449322)
			(size 0.3048 1.1176)
			(layers "F.Cu" "F.Mask" "F.Paste")
			(net "P3V3_VFB")
		)
		(pad "2" smd rect
			(at 1.999996 -2.449322)
			(size 0.3048 1.1176)
			(layers "F.Cu" "F.Mask" "F.Paste")
			(net "P3V3_EN")
		)
		(pad "3" smd rect
			(at 1.500124 -2.449322)
			(size 0.3048 1.1176)
			(layers "F.Cu" "F.Mask" "F.Paste")
			(net "SCC_STBY_PGOOD_BUF")
		)
		(pad "4" smd rect
			(at 0.999998 -2.449322)
			(size 0.3048 1.1176)
			(layers "F.Cu" "F.Mask" "F.Paste")
			(net "P3V3_VBST")
		)
		(pad "5" smd rect
			(at 0.500126 -2.449322)
			(size 0.3048 1.1176)
			(layers "F.Cu" "F.Mask" "F.Paste")
			(net "P3V3_ROVP")
		)
		(pad "6" smd rect
			(at 0 -2.449322)
			(size 0.3048 1.1176)
			(layers "F.Cu" "F.Mask" "F.Paste")
			(net "P3V3_LL")
		)
		(pad "7" smd rect
			(at -0.500126 -2.449322)
			(size 0.3048 1.1176)
			(layers "F.Cu" "F.Mask" "F.Paste")
			(net "P3V3_LL")
		)
		(pad "8" smd rect
			(at -0.999998 -2.449322)
			(size 0.3048 1.1176)
			(layers "F.Cu" "F.Mask" "F.Paste")
			(net "P3V3_LL")
		)
		(pad "9" smd rect
			(at -1.500124 -2.449322)
			(size 0.3048 1.1176)
			(layers "F.Cu" "F.Mask" "F.Paste")
			(net "P3V3_LL")
		)
		(pad "10" smd rect
			(at -1.999996 -2.449322)
			(size 0.3048 1.1176)
			(layers "F.Cu" "F.Mask" "F.Paste")
			(net "P3V3_LL")
		)
		(pad "11" smd rect
			(at -2.500122 -2.449322)
			(size 0.3048 1.1176)
			(layers "F.Cu" "F.Mask" "F.Paste")
			(net "P3V3_LL")
		)
		(pad "12" smd rect
			(at -2.500122 2.449322)
			(size 0.3048 1.1176)
			(layers "F.Cu" "F.Mask" "F.Paste")
			(net "P12V_STBY_VIN_U10")
		)
		(pad "13" smd rect
			(at -1.999996 2.449322)
			(size 0.3048 1.1176)
			(layers "F.Cu" "F.Mask" "F.Paste")
			(net "P12V_STBY_VIN_U10")
		)
		(pad "14" smd rect
			(at -1.500124 2.449322)
			(size 0.3048 1.1176)
			(layers "F.Cu" "F.Mask" "F.Paste")
			(net "P12V_STBY_VIN_U10")
		)
		(pad "15" smd rect
			(at -0.999998 2.449322)
			(size 0.3048 1.1176)
			(layers "F.Cu" "F.Mask" "F.Paste")
			(net "P12V_STBY_VIN_U10")
		)
		(pad "16" smd rect
			(at -0.500126 2.449322)
			(size 0.3048 1.1176)
			(layers "F.Cu" "F.Mask" "F.Paste")
			(net "P12V_STBY_VIN_U10")
		)
		(pad "17" smd rect
			(at 0 2.449322)
			(size 0.3048 1.1176)
			(layers "F.Cu" "F.Mask" "F.Paste")
			(net "P12V_STBY_VIN_U10")
		)
		(pad "18" smd rect
			(at 0.500126 2.449322)
			(size 0.3048 1.1176)
			(layers "F.Cu" "F.Mask" "F.Paste")
			(net "P3V3_VREG")
		)
		(pad "19" smd rect
			(at 0.999998 2.449322)
			(size 0.3048 1.1176)
			(layers "F.Cu" "F.Mask" "F.Paste")
			(net "P12V_STBY_VDD_U10")
		)
		(pad "20" smd rect
			(at 1.500124 2.449322)
			(size 0.3048 1.1176)
			(layers "F.Cu" "F.Mask" "F.Paste")
			(net "P3V3_MODE")
		)
		(pad "21" smd rect
			(at 1.999996 2.449322)
			(size 0.3048 1.1176)
			(layers "F.Cu" "F.Mask" "F.Paste")
			(net "P3V3_TRIP")
		)
		(pad "22" smd rect
			(at 2.500122 2.449322)
			(size 0.3048 1.1176)
			(layers "F.Cu" "F.Mask" "F.Paste")
			(net "P3V3_RF")
		)
		(pad "23" smd custom
			(at 0 0)
			(size 0.83185 0.83185)
			(layers "F.Cu" "F.Mask" "F.Paste")
			(net "GND")
			(options
				(clearance outline)
				(anchor circle)
			)
			(primitives
				(gr_poly
					(pts
						(xy -2.7813 1.6637) (xy -2.7813 1.2954) (xy -3.048 1.2954) (xy -3.048 0.9525) (xy -2.7813 0.9525)
						(xy -2.7813 -0.9525) (xy -3.048 -0.9525) (xy -3.048 -1.2954) (xy -2.7813 -1.2954) (xy -2.7813 -1.6637)
						(xy 2.7813 -1.6637) (xy 2.7813 -1.2954) (xy 3.048 -1.2954) (xy 3.048 -0.9525) (xy 2.7813 -0.9525)
						(xy 2.7813 0.9525) (xy 3.048 0.9525) (xy 3.048 1.2954) (xy 2.7813 1.2954) (xy 2.7813 1.6637)
					)
					(width 0)
					(fill yes)
				)
			)
		)
	)
	(footprint ""
		(layer "F.Cu")
		(at 7.366 -78.613 90)
		(property "Reference" "R336"
			(at 0 0 90)
			(layer "F.SilkS")
			(hide yes)
			(effects
				(font
					(size 1.27 1.27)
				)
			)
		)
		(property "Value" "4K7R2F-GP"
			(at 0.064008 -3.993896 90)
			(unlocked yes)
			(layer "F.Fab")
			(hide yes)
			(effects
				(font
					(size 1.016 1.016)
					(thickness 0.1524)
				)
			)
		)
		(property "Device Type" "R402H16"
			(at 0.064008 -5.517896 90)
			(unlocked yes)
			(layer "F.Fab")
			(hide yes)
			(effects
				(font
					(size 1.016 1.016)
					(thickness 0.1524)
				)
			)
		)
		(duplicate_pad_numbers_are_jumpers no)
		(fp_line
			(start 0.508 -0.9398)
			(end -0.508 -0.9398)
			(stroke
				(width 0.1524)
				(type default)
			)
			(layer "F.SilkS")
		)
		(fp_line
			(start -0.508 -0.9398)
			(end -0.508 0.9398)
			(stroke
				(width 0.1524)
				(type default)
			)
			(layer "F.SilkS")
		)
		(fp_rect
			(start -0.508 0.9398)
			(end 0.508 -0.9398)
			(stroke
				(width 0)
				(type default)
			)
			(fill no)
			(layer "F.CrtYd")
		)
		(fp_rect
			(start -0.508 0.9398)
			(end 0.508 -0.9398)
			(stroke
				(width 0)
				(type default)
			)
			(fill no)
			(layer "F.Fab")
		)
		(pad "1" smd custom
			(at 0 -0.4445 90)
			(size 0.1397 0.1397)
			(layers "F.Cu" "F.Mask" "F.Paste")
			(net "P3V3")
			(options
				(clearance outline)
				(anchor circle)
			)
			(primitives
				(gr_poly
					(pts
						(arc
							(start -0.1778 -0.2794)
							(mid -0.249642 -0.249642)
							(end -0.2794 -0.1778)
						)
						(arc
							(start -0.2794 0.1778)
							(mid -0.249642 0.249642)
							(end -0.1778 0.2794)
						)
						(arc
							(start 0.1778 0.2794)
							(mid 0.249642 0.249642)
							(end 0.2794 0.1778)
						)
						(arc
							(start 0.2794 -0.1778)
							(mid 0.249642 -0.249642)
							(end 0.1778 -0.2794)
						)
					)
					(width 0)
					(fill yes)
				)
			)
		)
		(pad "2" smd custom
			(at 0 0.4445 90)
			(size 0.1397 0.1397)
			(layers "F.Cu" "F.Mask" "F.Paste")
			(net "EXP_EEPROM_A1")
			(options
				(clearance outline)
				(anchor circle)
			)
			(primitives
				(gr_poly
					(pts
						(arc
							(start -0.1778 -0.2794)
							(mid -0.249642 -0.249642)
							(end -0.2794 -0.1778)
						)
						(arc
							(start -0.2794 0.1778)
							(mid -0.249642 0.249642)
							(end -0.1778 0.2794)
						)
						(arc
							(start 0.1778 0.2794)
							(mid 0.249642 0.249642)
							(end 0.2794 0.1778)
						)
						(arc
							(start 0.2794 -0.1778)
							(mid 0.249642 -0.249642)
							(end 0.1778 -0.2794)
						)
					)
					(width 0)
					(fill yes)
				)
			)
		)
	)
	(footprint ""
		(layer "F.Cu")
		(at 149.9489 -83.5025 180)
		(property "Reference" "R321"
			(at 0 0 180)
			(layer "F.SilkS")
			(hide yes)
			(effects
				(font
					(size 1.27 1.27)
				)
			)
		)
		(property "Value" "1KR2F-3-GP"
			(at 0.064008 -3.993896 180)
			(unlocked yes)
			(layer "F.Fab")
			(hide yes)
			(effects
				(font
					(size 1.016 1.016)
					(thickness 0.1524)
				)
			)
		)
		(property "Device Type" "R402H16"
			(at 0.064008 -5.517896 180)
			(unlocked yes)
			(layer "F.Fab")
			(hide yes)
			(effects
				(font
					(size 1.016 1.016)
					(thickness 0.1524)
				)
			)
		)
		(duplicate_pad_numbers_are_jumpers no)
		(fp_line
			(start 0.508 -0.9398)
			(end -0.508 -0.9398)
			(stroke
				(width 0.1524)
				(type default)
			)
			(layer "F.SilkS")
		)
		(fp_line
			(start -0.508 -0.9398)
			(end -0.508 0.9398)
			(stroke
				(width 0.1524)
				(type default)
			)
			(layer "F.SilkS")
		)
		(fp_rect
			(start -0.508 0.9398)
			(end 0.508 -0.9398)
			(stroke
				(width 0)
				(type default)
			)
			(fill no)
			(layer "F.CrtYd")
		)
		(fp_rect
			(start -0.508 0.9398)
			(end 0.508 -0.9398)
			(stroke
				(width 0)
				(type default)
			)
			(fill no)
			(layer "F.Fab")
		)
		(pad "1" smd custom
			(at 0 -0.4445 180)
			(size 0.1397 0.1397)
			(layers "F.Cu" "F.Mask" "F.Paste")
			(net "P1V8_E")
			(options
				(clearance outline)
				(anchor circle)
			)
			(primitives
				(gr_poly
					(pts
						(arc
							(start -0.1778 -0.2794)
							(mid -0.249642 -0.249642)
							(end -0.2794 -0.1778)
						)
						(arc
							(start -0.2794 0.1778)
							(mid -0.249642 0.249642)
							(end -0.1778 0.2794)
						)
						(arc
							(start 0.1778 0.2794)
							(mid 0.249642 0.249642)
							(end 0.2794 0.1778)
						)
						(arc
							(start 0.2794 -0.1778)
							(mid 0.249642 -0.249642)
							(end 0.1778 -0.2794)
						)
					)
					(width 0)
					(fill yes)
				)
			)
		)
		(pad "2" smd custom
			(at 0 0.4445 180)
			(size 0.1397 0.1397)
			(layers "F.Cu" "F.Mask" "F.Paste")
			(net "P1V8_E_SENSE")
			(options
				(clearance outline)
				(anchor circle)
			)
			(primitives
				(gr_poly
					(pts
						(arc
							(start -0.1778 -0.2794)
							(mid -0.249642 -0.249642)
							(end -0.2794 -0.1778)
						)
						(arc
							(start -0.2794 0.1778)
							(mid -0.249642 0.249642)
							(end -0.1778 0.2794)
						)
						(arc
							(start 0.1778 0.2794)
							(mid 0.249642 0.249642)
							(end 0.2794 0.1778)
						)
						(arc
							(start 0.2794 -0.1778)
							(mid 0.249642 -0.249642)
							(end 0.1778 -0.2794)
						)
					)
					(width 0)
					(fill yes)
				)
			)
		)
	)
	(footprint ""
		(layer "F.Cu")
		(at 40.9702 -43.4086)
		(property "Reference" "C667"
			(at 0 0 0)
			(layer "F.SilkS")
			(hide yes)
			(effects
				(font
					(size 1.27 1.27)
				)
			)
		)
		(property "Value" "SC10U16V5KX-7-GP-U"
			(at -0.0762 -6.1214 0)
			(unlocked yes)
			(layer "F.Fab")
			(hide yes)
			(effects
				(font
					(size 1.016 1.016)
					(thickness 0.1524)
				)
			)
		)
		(property "Device Type" "C805H58"
			(at -0.0762 -8.1534 0)
			(unlocked yes)
			(layer "F.Fab")
			(hide yes)
			(effects
				(font
					(size 1.016 1.016)
					(thickness 0.1524)
				)
			)
		)
		(duplicate_pad_numbers_are_jumpers no)
		(fp_line
			(start 0.635 0)
			(end -0.635 0)
			(stroke
				(width 0.508)
				(type default)
			)
			(layer "F.SilkS")
		)
		(fp_rect
			(start -0.9652 1.778)
			(end 0.9652 -1.778)
			(stroke
				(width 0)
				(type default)
			)
			(fill no)
			(layer "F.CrtYd")
		)
		(fp_poly
			(pts
				(xy -0.9652 -1.778) (xy 0.9652 -1.778) (xy 0.9652 1.778) (xy -0.9652 1.778)
			)
			(stroke
				(width 0)
				(type default)
			)
			(fill no)
			(layer "F.Fab")
		)
		(pad "1" smd rect
			(at 0 -0.9652)
			(size 1.397 1.143)
			(layers "F.Cu" "F.Mask" "F.Paste")
			(net "P12V_STBY_VIN_Q7")
		)
		(pad "2" smd rect
			(at 0 0.9652)
			(size 1.397 1.143)
			(layers "F.Cu" "F.Mask" "F.Paste")
			(net "GND")
		)
	)
	(footprint ""
		(layer "F.Cu")
		(at 121.487692 -90.564716 180)
		(property "Reference" "R206"
			(at 0 0 180)
			(layer "F.SilkS")
			(hide yes)
			(effects
				(font
					(size 1.27 1.27)
				)
			)
		)
		(property "Value" "0R2J-2-GP"
			(at 0.064008 -3.993896 180)
			(unlocked yes)
			(layer "F.Fab")
			(hide yes)
			(effects
				(font
					(size 1.016 1.016)
					(thickness 0.1524)
				)
			)
		)
		(property "Device Type" "R402H16"
			(at 0.064008 -5.517896 180)
			(unlocked yes)
			(layer "F.Fab")
			(hide yes)
			(effects
				(font
					(size 1.016 1.016)
					(thickness 0.1524)
				)
			)
		)
		(duplicate_pad_numbers_are_jumpers no)
		(fp_line
			(start 0.508 -0.9398)
			(end -0.508 -0.9398)
			(stroke
				(width 0.1524)
				(type default)
			)
			(layer "F.SilkS")
		)
		(fp_line
			(start -0.508 -0.9398)
			(end -0.508 0.9398)
			(stroke
				(width 0.1524)
				(type default)
			)
			(layer "F.SilkS")
		)
		(fp_rect
			(start -0.508 0.9398)
			(end 0.508 -0.9398)
			(stroke
				(width 0)
				(type default)
			)
			(fill no)
			(layer "F.CrtYd")
		)
		(fp_rect
			(start -0.508 0.9398)
			(end 0.508 -0.9398)
			(stroke
				(width 0)
				(type default)
			)
			(fill no)
			(layer "F.Fab")
		)
		(pad "1" smd custom
			(at 0 -0.4445 180)
			(size 0.1397 0.1397)
			(layers "F.Cu" "F.Mask" "F.Paste")
			(net "BMC_EXP_SPARE_1_R_LS")
			(options
				(clearance outline)
				(anchor circle)
			)
			(primitives
				(gr_poly
					(pts
						(arc
							(start -0.1778 -0.2794)
							(mid -0.249642 -0.249642)
							(end -0.2794 -0.1778)
						)
						(arc
							(start -0.2794 0.1778)
							(mid -0.249642 0.249642)
							(end -0.1778 0.2794)
						)
						(arc
							(start 0.1778 0.2794)
							(mid 0.249642 0.249642)
							(end 0.2794 0.1778)
						)
						(arc
							(start 0.2794 -0.1778)
							(mid 0.249642 -0.249642)
							(end 0.1778 -0.2794)
						)
					)
					(width 0)
					(fill yes)
				)
			)
		)
		(pad "2" smd custom
			(at 0 0.4445 180)
			(size 0.1397 0.1397)
			(layers "F.Cu" "F.Mask" "F.Paste")
			(net "BMC_SPARE_1_LS")
			(options
				(clearance outline)
				(anchor circle)
			)
			(primitives
				(gr_poly
					(pts
						(arc
							(start -0.1778 -0.2794)
							(mid -0.249642 -0.249642)
							(end -0.2794 -0.1778)
						)
						(arc
							(start -0.2794 0.1778)
							(mid -0.249642 0.249642)
							(end -0.1778 0.2794)
						)
						(arc
							(start 0.1778 0.2794)
							(mid 0.249642 0.249642)
							(end 0.2794 0.1778)
						)
						(arc
							(start 0.2794 -0.1778)
							(mid 0.249642 -0.249642)
							(end 0.1778 -0.2794)
						)
					)
					(width 0)
					(fill yes)
				)
			)
		)
	)
	(footprint ""
		(layer "F.Cu")
		(at 148.745702 -40.794432 -78)
		(property "Reference" "VIA20"
			(at 0 0 282)
			(layer "F.SilkS")
			(hide yes)
			(effects
				(font
					(size 1.27 1.27)
				)
			)
		)
		(property "Value" "100OHM-8L-1D6MM-L13-GP"
			(at 3.289333 0.050849 282)
			(unlocked yes)
			(layer "F.Fab")
			(hide yes)
			(effects
				(font
					(size 1.016 1.016)
					(thickness 0.1524)
				)
			)
		)
		(property "Device Type" "VIA-PCIE-4P-409091"
			(at 3.289456 -1.473155 282)
			(unlocked yes)
			(layer "F.Fab")
			(hide yes)
			(effects
				(font
					(size 1.016 1.016)
					(thickness 0.1524)
				)
			)
		)
		(duplicate_pad_numbers_are_jumpers no)
		(fp_poly
			(pts
				(xy -2.044719 -0.457296) (xy 2.04468 -0.457296) (xy 2.044681 0.457104) (xy -2.044719 0.457104)
			)
			(stroke
				(width 0)
				(type default)
			)
			(fill no)
			(layer "F.CrtYd")
		)
		(fp_poly
			(pts
				(xy -2.044719 -0.457296) (xy 2.04468 -0.457296) (xy 2.044681 0.457104) (xy -2.044719 0.457104)
			)
			(stroke
				(width 0)
				(type default)
			)
			(fill no)
			(layer "F.Fab")
		)
		(pad "1" thru_hole circle
			(at -1.5875 0 282)
			(size 0.508 0.508)
			(drill 0.254)
			(layers "*.Cu" "*.Mask")
			(remove_unused_layers no)
			(net "GND")
			(clearance 0.2032)
			(thermal_gap 0.2032)
		)
		(pad "2" thru_hole circle
			(at -0.5715 0.000001 282)
			(size 0.508 0.508)
			(drill 0.254)
			(layers "*.Cu" "*.Mask")
			(remove_unused_layers no)
			(net "PHY_SCC_TO_IOC_C_43_DP")
			(clearance 0.2032)
			(thermal_gap 0.2032)
		)
		(pad "3" thru_hole circle
			(at 0.5715 -0.000001 282)
			(size 0.508 0.508)
			(drill 0.254)
			(layers "*.Cu" "*.Mask")
			(remove_unused_layers no)
			(net "PHY_SCC_TO_IOC_C_43_DN")
			(clearance 0.2032)
			(thermal_gap 0.2032)
		)
		(pad "4" thru_hole circle
			(at 1.5875 0 282)
			(size 0.508 0.508)
			(drill 0.254)
			(layers "*.Cu" "*.Mask")
			(remove_unused_layers no)
			(net "GND")
			(clearance 0.2032)
			(thermal_gap 0.2032)
		)
	)
	(footprint ""
		(layer "F.Cu")
		(at 157.8737 -80.007714 -90)
		(property "Reference" "R332"
			(at 0 0 270)
			(layer "F.SilkS")
			(hide yes)
			(effects
				(font
					(size 1.27 1.27)
				)
			)
		)
		(property "Value" "4K7R2F-GP"
			(at 0.064008 -3.993896 270)
			(unlocked yes)
			(layer "F.Fab")
			(hide yes)
			(effects
				(font
					(size 1.016 1.016)
					(thickness 0.1524)
				)
			)
		)
		(property "Device Type" "R402H16"
			(at 0.064008 -5.517896 270)
			(unlocked yes)
			(layer "F.Fab")
			(hide yes)
			(effects
				(font
					(size 1.016 1.016)
					(thickness 0.1524)
				)
			)
		)
		(duplicate_pad_numbers_are_jumpers no)
		(fp_line
			(start -0.508 -0.9398)
			(end -0.508 0.9398)
			(stroke
				(width 0.1524)
				(type default)
			)
			(layer "F.SilkS")
		)
		(fp_line
			(start 0.508 -0.9398)
			(end -0.508 -0.9398)
			(stroke
				(width 0.1524)
				(type default)
			)
			(layer "F.SilkS")
		)
		(fp_rect
			(start -0.508 0.9398)
			(end 0.508 -0.9398)
			(stroke
				(width 0)
				(type default)
			)
			(fill no)
			(layer "F.CrtYd")
		)
		(fp_rect
			(start -0.508 0.9398)
			(end 0.508 -0.9398)
			(stroke
				(width 0)
				(type default)
			)
			(fill no)
			(layer "F.Fab")
		)
		(pad "1" smd custom
			(at 0 -0.4445 270)
			(size 0.1397 0.1397)
			(layers "F.Cu" "F.Mask" "F.Paste")
			(net "P3V3")
			(options
				(clearance outline)
				(anchor circle)
			)
			(primitives
				(gr_poly
					(pts
						(arc
							(start -0.1778 -0.2794)
							(mid -0.249642 -0.249642)
							(end -0.2794 -0.1778)
						)
						(arc
							(start -0.2794 0.1778)
							(mid -0.249642 0.249642)
							(end -0.1778 0.2794)
						)
						(arc
							(start 0.1778 0.2794)
							(mid 0.249642 0.249642)
							(end 0.2794 0.1778)
						)
						(arc
							(start 0.2794 -0.1778)
							(mid 0.249642 -0.249642)
							(end 0.1778 -0.2794)
						)
					)
					(width 0)
					(fill yes)
				)
			)
		)
		(pad "2" smd custom
			(at 0 0.4445 270)
			(size 0.1397 0.1397)
			(layers "F.Cu" "F.Mask" "F.Paste")
			(net "VOL_SEN2_ADDR")
			(options
				(clearance outline)
				(anchor circle)
			)
			(primitives
				(gr_poly
					(pts
						(arc
							(start -0.1778 -0.2794)
							(mid -0.249642 -0.249642)
							(end -0.2794 -0.1778)
						)
						(arc
							(start -0.2794 0.1778)
							(mid -0.249642 0.249642)
							(end -0.1778 0.2794)
						)
						(arc
							(start 0.1778 0.2794)
							(mid 0.249642 0.249642)
							(end 0.2794 0.1778)
						)
						(arc
							(start 0.2794 -0.1778)
							(mid 0.249642 -0.249642)
							(end 0.1778 -0.2794)
						)
					)
					(width 0)
					(fill yes)
				)
			)
		)
	)
	(footprint ""
		(layer "F.Cu")
		(at 142.99311 -58.3057 -90)
		(property "Reference" "C40"
			(at 0 0 270)
			(layer "F.SilkS")
			(hide yes)
			(effects
				(font
					(size 1.27 1.27)
				)
			)
		)
		(property "Value" "SCD01U16V1KX-GP"
			(at -2.8321 -1.7399 270)
			(unlocked yes)
			(layer "F.Fab")
			(hide yes)
			(effects
				(font
					(size 1.016 1.016)
					(thickness 0.1524)
				)
			)
		)
		(property "Device Type" "C0201H13"
			(at -2.8321 -3.2639 270)
			(unlocked yes)
			(layer "F.Fab")
			(hide yes)
			(effects
				(font
					(size 1.016 1.016)
					(thickness 0.1524)
				)
			)
		)
		(duplicate_pad_numbers_are_jumpers no)
		(fp_rect
			(start -0.2794 0.6477)
			(end 0.2794 -0.6477)
			(stroke
				(width 0)
				(type default)
			)
			(fill no)
			(layer "F.CrtYd")
		)
		(fp_rect
			(start -0.2794 0.6477)
			(end 0.2794 -0.6477)
			(stroke
				(width 0)
				(type default)
			)
			(fill no)
			(layer "F.Fab")
		)
		(pad "1" smd custom
			(at 0 -0.2794 270)
			(size 0.0762 0.0762)
			(layers "F.Cu" "F.Mask" "F.Paste")
			(net "PHY_IOC_TO_SCC_44_DN")
			(options
				(clearance outline)
				(anchor circle)
			)
			(primitives
				(gr_poly
					(pts
						(arc
							(start 0.1524 -0.127)
							(mid 0.137521 -0.162921)
							(end 0.1016 -0.1778)
						)
						(arc
							(start -0.1016 -0.1778)
							(mid -0.137521 -0.162921)
							(end -0.1524 -0.127)
						)
						(arc
							(start -0.1524 0.127)
							(mid -0.137521 0.162921)
							(end -0.1016 0.1778)
						)
						(arc
							(start 0.1016 0.1778)
							(mid 0.137521 0.162921)
							(end 0.1524 0.127)
						)
					)
					(width 0)
					(fill yes)
				)
			)
		)
		(pad "2" smd custom
			(at 0 0.2794 270)
			(size 0.0762 0.0762)
			(layers "F.Cu" "F.Mask" "F.Paste")
			(net "PHY_IOC_TO_SCC_C_44_DN")
			(options
				(clearance outline)
				(anchor circle)
			)
			(primitives
				(gr_poly
					(pts
						(arc
							(start 0.1524 -0.127)
							(mid 0.137521 -0.162921)
							(end 0.1016 -0.1778)
						)
						(arc
							(start -0.1016 -0.1778)
							(mid -0.137521 -0.162921)
							(end -0.1524 -0.127)
						)
						(arc
							(start -0.1524 0.127)
							(mid -0.137521 0.162921)
							(end -0.1016 0.1778)
						)
						(arc
							(start 0.1016 0.1778)
							(mid 0.137521 0.162921)
							(end 0.1524 0.127)
						)
					)
					(width 0)
					(fill yes)
				)
			)
		)
	)
	(footprint ""
		(layer "F.Cu")
		(at 130.57378 -44.717716 180)
		(property "Reference" "C43"
			(at 0 0 180)
			(layer "F.SilkS")
			(hide yes)
			(effects
				(font
					(size 1.27 1.27)
				)
			)
		)
		(property "Value" "SCD01U16V1KX-GP"
			(at -2.8321 -1.7399 180)
			(unlocked yes)
			(layer "F.Fab")
			(hide yes)
			(effects
				(font
					(size 1.016 1.016)
					(thickness 0.1524)
				)
			)
		)
		(property "Device Type" "C0201H13"
			(at -2.8321 -3.2639 180)
			(unlocked yes)
			(layer "F.Fab")
			(hide yes)
			(effects
				(font
					(size 1.016 1.016)
					(thickness 0.1524)
				)
			)
		)
		(duplicate_pad_numbers_are_jumpers no)
		(fp_rect
			(start -0.2794 0.6477)
			(end 0.2794 -0.6477)
			(stroke
				(width 0)
				(type default)
			)
			(fill no)
			(layer "F.CrtYd")
		)
		(fp_rect
			(start -0.2794 0.6477)
			(end 0.2794 -0.6477)
			(stroke
				(width 0)
				(type default)
			)
			(fill no)
			(layer "F.Fab")
		)
		(pad "1" smd custom
			(at 0 -0.2794 180)
			(size 0.0762 0.0762)
			(layers "F.Cu" "F.Mask" "F.Paste")
			(net "PHY_IOC_TO_SCC_42_DP")
			(options
				(clearance outline)
				(anchor circle)
			)
			(primitives
				(gr_poly
					(pts
						(arc
							(start 0.1524 -0.127)
							(mid 0.137521 -0.162921)
							(end 0.1016 -0.1778)
						)
						(arc
							(start -0.1016 -0.1778)
							(mid -0.137521 -0.162921)
							(end -0.1524 -0.127)
						)
						(arc
							(start -0.1524 0.127)
							(mid -0.137521 0.162921)
							(end -0.1016 0.1778)
						)
						(arc
							(start 0.1016 0.1778)
							(mid 0.137521 0.162921)
							(end 0.1524 0.127)
						)
					)
					(width 0)
					(fill yes)
				)
			)
		)
		(pad "2" smd custom
			(at 0 0.2794 180)
			(size 0.0762 0.0762)
			(layers "F.Cu" "F.Mask" "F.Paste")
			(net "PHY_IOC_TO_SCC_C_42_DP")
			(options
				(clearance outline)
				(anchor circle)
			)
			(primitives
				(gr_poly
					(pts
						(arc
							(start 0.1524 -0.127)
							(mid 0.137521 -0.162921)
							(end 0.1016 -0.1778)
						)
						(arc
							(start -0.1016 -0.1778)
							(mid -0.137521 -0.162921)
							(end -0.1524 -0.127)
						)
						(arc
							(start -0.1524 0.127)
							(mid -0.137521 0.162921)
							(end -0.1016 0.1778)
						)
						(arc
							(start 0.1016 0.1778)
							(mid 0.137521 0.162921)
							(end 0.1524 0.127)
						)
					)
					(width 0)
					(fill yes)
				)
			)
		)
	)
	(footprint ""
		(layer "F.Cu")
		(at 190.23838 -75.46848 -90)
		(property "Reference" "R371"
			(at 0 0 270)
			(layer "F.SilkS")
			(hide yes)
			(effects
				(font
					(size 1.27 1.27)
				)
			)
		)
		(property "Value" "4K7R2F-GP"
			(at 0.064008 -3.993896 270)
			(unlocked yes)
			(layer "F.Fab")
			(hide yes)
			(effects
				(font
					(size 1.016 1.016)
					(thickness 0.1524)
				)
			)
		)
		(property "Device Type" "R402H16"
			(at 0.064008 -5.517896 270)
			(unlocked yes)
			(layer "F.Fab")
			(hide yes)
			(effects
				(font
					(size 1.016 1.016)
					(thickness 0.1524)
				)
			)
		)
		(duplicate_pad_numbers_are_jumpers no)
		(fp_line
			(start -0.508 -0.9398)
			(end -0.508 0.9398)
			(stroke
				(width 0.1524)
				(type default)
			)
			(layer "F.SilkS")
		)
		(fp_line
			(start 0.508 -0.9398)
			(end -0.508 -0.9398)
			(stroke
				(width 0.1524)
				(type default)
			)
			(layer "F.SilkS")
		)
		(fp_rect
			(start -0.508 0.9398)
			(end 0.508 -0.9398)
			(stroke
				(width 0)
				(type default)
			)
			(fill no)
			(layer "F.CrtYd")
		)
		(fp_rect
			(start -0.508 0.9398)
			(end 0.508 -0.9398)
			(stroke
				(width 0)
				(type default)
			)
			(fill no)
			(layer "F.Fab")
		)
		(pad "1" smd custom
			(at 0 -0.4445 270)
			(size 0.1397 0.1397)
			(layers "F.Cu" "F.Mask" "F.Paste")
			(net "P3V3")
			(options
				(clearance outline)
				(anchor circle)
			)
			(primitives
				(gr_poly
					(pts
						(arc
							(start -0.1778 -0.2794)
							(mid -0.249642 -0.249642)
							(end -0.2794 -0.1778)
						)
						(arc
							(start -0.2794 0.1778)
							(mid -0.249642 0.249642)
							(end -0.1778 0.2794)
						)
						(arc
							(start 0.1778 0.2794)
							(mid 0.249642 0.249642)
							(end 0.2794 0.1778)
						)
						(arc
							(start 0.2794 -0.1778)
							(mid 0.249642 -0.249642)
							(end 0.1778 -0.2794)
						)
					)
					(width 0)
					(fill yes)
				)
			)
		)
		(pad "2" smd custom
			(at 0 0.4445 270)
			(size 0.1397 0.1397)
			(layers "F.Cu" "F.Mask" "F.Paste")
			(net "TEMP2_A0")
			(options
				(clearance outline)
				(anchor circle)
			)
			(primitives
				(gr_poly
					(pts
						(arc
							(start -0.1778 -0.2794)
							(mid -0.249642 -0.249642)
							(end -0.2794 -0.1778)
						)
						(arc
							(start -0.2794 0.1778)
							(mid -0.249642 0.249642)
							(end -0.1778 0.2794)
						)
						(arc
							(start 0.1778 0.2794)
							(mid 0.249642 0.249642)
							(end 0.2794 0.1778)
						)
						(arc
							(start 0.2794 -0.1778)
							(mid 0.249642 -0.249642)
							(end 0.1778 -0.2794)
						)
					)
					(width 0)
					(fill yes)
				)
			)
		)
	)
	(footprint ""
		(layer "F.Cu")
		(at 23.74773 -85.799422 -90)
		(property "Reference" "C571"
			(at 0 0 270)
			(layer "F.SilkS")
			(hide yes)
			(effects
				(font
					(size 1.27 1.27)
				)
			)
		)
		(property "Value" "SCD1U16V2KX-3GP"
			(at 1.1811 -2.7051 270)
			(unlocked yes)
			(layer "F.Fab")
			(hide yes)
			(effects
				(font
					(size 1.016 1.016)
					(thickness 0.1524)
				)
			)
		)
		(property "Device Type" "C402H22"
			(at 1.1811 -4.2291 270)
			(unlocked yes)
			(layer "F.Fab")
			(hide yes)
			(effects
				(font
					(size 1.016 1.016)
					(thickness 0.1524)
				)
			)
		)
		(duplicate_pad_numbers_are_jumpers no)
		(fp_rect
			(start -0.4318 0.9525)
			(end 0.4318 -0.9525)
			(stroke
				(width 0)
				(type default)
			)
			(fill no)
			(layer "F.CrtYd")
		)
		(fp_rect
			(start -0.4318 0.9525)
			(end 0.4318 -0.9525)
			(stroke
				(width 0)
				(type default)
			)
			(fill no)
			(layer "F.Fab")
		)
		(pad "1" smd custom
			(at 0 -0.4445 270)
			(size 0.1524 0.1524)
			(layers "F.Cu" "F.Mask" "F.Paste")
			(net "P1V8_E")
			(options
				(clearance outline)
				(anchor circle)
			)
			(primitives
				(gr_poly
					(pts
						(arc
							(start 0.3048 -0.2032)
							(mid 0.275042 -0.275042)
							(end 0.2032 -0.3048)
						)
						(arc
							(start -0.2032 -0.3048)
							(mid -0.275042 -0.275042)
							(end -0.3048 -0.2032)
						)
						(arc
							(start -0.3048 0.2032)
							(mid -0.275042 0.275042)
							(end -0.2032 0.3048)
						)
						(arc
							(start 0.2032 0.3048)
							(mid 0.275042 0.275042)
							(end 0.3048 0.2032)
						)
					)
					(width 0)
					(fill yes)
				)
			)
		)
		(pad "2" smd custom
			(at 0 0.4445 270)
			(size 0.1524 0.1524)
			(layers "F.Cu" "F.Mask" "F.Paste")
			(net "GND")
			(options
				(clearance outline)
				(anchor circle)
			)
			(primitives
				(gr_poly
					(pts
						(arc
							(start 0.3048 -0.2032)
							(mid 0.275042 -0.275042)
							(end 0.2032 -0.3048)
						)
						(arc
							(start -0.2032 -0.3048)
							(mid -0.275042 -0.275042)
							(end -0.3048 -0.2032)
						)
						(arc
							(start -0.3048 0.2032)
							(mid -0.275042 0.275042)
							(end -0.2032 0.3048)
						)
						(arc
							(start 0.2032 0.3048)
							(mid 0.275042 0.275042)
							(end 0.3048 0.2032)
						)
					)
					(width 0)
					(fill yes)
				)
			)
		)
	)
	(footprint ""
		(layer "F.Cu")
		(at 24.8031 -114.9731 90)
		(property "Reference" "C523"
			(at 0 0 90)
			(layer "F.SilkS")
			(hide yes)
			(effects
				(font
					(size 1.27 1.27)
				)
			)
		)
		(property "Value" "SCD1U16V2KX-3GP"
			(at 1.1811 -2.7051 90)
			(unlocked yes)
			(layer "F.Fab")
			(hide yes)
			(effects
				(font
					(size 1.016 1.016)
					(thickness 0.1524)
				)
			)
		)
		(property "Device Type" "C402H22"
			(at 1.1811 -4.2291 90)
			(unlocked yes)
			(layer "F.Fab")
			(hide yes)
			(effects
				(font
					(size 1.016 1.016)
					(thickness 0.1524)
				)
			)
		)
		(duplicate_pad_numbers_are_jumpers no)
		(fp_rect
			(start -0.4318 0.9525)
			(end 0.4318 -0.9525)
			(stroke
				(width 0)
				(type default)
			)
			(fill no)
			(layer "F.CrtYd")
		)
		(fp_rect
			(start -0.4318 0.9525)
			(end 0.4318 -0.9525)
			(stroke
				(width 0)
				(type default)
			)
			(fill no)
			(layer "F.Fab")
		)
		(pad "1" smd custom
			(at 0 -0.4445 90)
			(size 0.1524 0.1524)
			(layers "F.Cu" "F.Mask" "F.Paste")
			(net "P5V")
			(options
				(clearance outline)
				(anchor circle)
			)
			(primitives
				(gr_poly
					(pts
						(arc
							(start 0.3048 -0.2032)
							(mid 0.275042 -0.275042)
							(end 0.2032 -0.3048)
						)
						(arc
							(start -0.2032 -0.3048)
							(mid -0.275042 -0.275042)
							(end -0.3048 -0.2032)
						)
						(arc
							(start -0.3048 0.2032)
							(mid -0.275042 0.275042)
							(end -0.2032 0.3048)
						)
						(arc
							(start 0.2032 0.3048)
							(mid 0.275042 0.275042)
							(end 0.3048 0.2032)
						)
					)
					(width 0)
					(fill yes)
				)
			)
		)
		(pad "2" smd custom
			(at 0 0.4445 90)
			(size 0.1524 0.1524)
			(layers "F.Cu" "F.Mask" "F.Paste")
			(net "GND")
			(options
				(clearance outline)
				(anchor circle)
			)
			(primitives
				(gr_poly
					(pts
						(arc
							(start 0.3048 -0.2032)
							(mid 0.275042 -0.275042)
							(end 0.2032 -0.3048)
						)
						(arc
							(start -0.2032 -0.3048)
							(mid -0.275042 -0.275042)
							(end -0.3048 -0.2032)
						)
						(arc
							(start -0.3048 0.2032)
							(mid -0.275042 0.275042)
							(end -0.2032 0.3048)
						)
						(arc
							(start 0.2032 0.3048)
							(mid 0.275042 0.275042)
							(end 0.3048 0.2032)
						)
					)
					(width 0)
					(fill yes)
				)
			)
		)
	)
	(footprint ""
		(layer "F.Cu")
		(at 142.86484 -118.50878 180)
		(property "Reference" "D3"
			(at 0 0 180)
			(layer "F.SilkS")
			(hide yes)
			(effects
				(font
					(size 1.27 1.27)
				)
			)
		)
		(property "Value" "RB551V30-GP"
			(at 0 -6.7818 180)
			(unlocked yes)
			(layer "F.Fab")
			(hide yes)
			(effects
				(font
					(size 1.016 1.016)
					(thickness 0.1524)
				)
			)
		)
		(property "Device Type" "SOD323AKH38"
			(at 0 -8.6868 180)
			(unlocked yes)
			(layer "F.Fab")
			(hide yes)
			(effects
				(font
					(size 1.016 1.016)
					(thickness 0.1524)
				)
			)
		)
		(duplicate_pad_numbers_are_jumpers no)
		(fp_line
			(start 0.889 2.159)
			(end -0.889 2.159)
			(stroke
				(width 0.1524)
				(type default)
			)
			(layer "F.SilkS")
		)
		(fp_line
			(start 0.889 -1.9304)
			(end 0.889 2.159)
			(stroke
				(width 0.1524)
				(type default)
			)
			(layer "F.SilkS")
		)
		(fp_line
			(start 0.762 2.0574)
			(end -0.762 2.0574)
			(stroke
				(width 0.508)
				(type default)
			)
			(layer "F.SilkS")
		)
		(fp_line
			(start -0.889 2.159)
			(end -0.889 -1.9304)
			(stroke
				(width 0.1524)
				(type default)
			)
			(layer "F.SilkS")
		)
		(fp_line
			(start -0.889 -1.9304)
			(end 0.889 -1.9304)
			(stroke
				(width 0.1524)
				(type default)
			)
			(layer "F.SilkS")
		)
		(fp_rect
			(start -1.016 2.3114)
			(end 1.016 -2.0066)
			(stroke
				(width 0)
				(type default)
			)
			(fill no)
			(layer "F.CrtYd")
		)
		(fp_poly
			(pts
				(xy -1.016 -2.0066) (xy 1.016 -2.0066) (xy 1.016 2.3114) (xy -1.016 2.3114)
			)
			(stroke
				(width 0)
				(type default)
			)
			(fill no)
			(layer "F.Fab")
		)
		(pad "A" smd rect
			(at 0 -1.143 180)
			(size 0.5588 1.016)
			(layers "F.Cu" "F.Mask" "F.Paste")
			(net "P1V5_C_S")
		)
		(pad "K" smd rect
			(at 0 1.143 180)
			(size 0.5588 1.016)
			(layers "F.Cu" "F.Mask" "F.Paste")
			(net "P1V8_C_PG")
		)
	)
	(footprint ""
		(layer "F.Cu")
		(at 152.155398 -71.124318 90)
		(property "Reference" "R352"
			(at 0 0 90)
			(layer "F.SilkS")
			(hide yes)
			(effects
				(font
					(size 1.27 1.27)
				)
			)
		)
		(property "Value" "1KR2F-3-GP"
			(at 0.064008 -3.993896 90)
			(unlocked yes)
			(layer "F.Fab")
			(hide yes)
			(effects
				(font
					(size 1.016 1.016)
					(thickness 0.1524)
				)
			)
		)
		(property "Device Type" "R402H16"
			(at 0.064008 -5.517896 90)
			(unlocked yes)
			(layer "F.Fab")
			(hide yes)
			(effects
				(font
					(size 1.016 1.016)
					(thickness 0.1524)
				)
			)
		)
		(duplicate_pad_numbers_are_jumpers no)
		(fp_line
			(start 0.508 -0.9398)
			(end -0.508 -0.9398)
			(stroke
				(width 0.1524)
				(type default)
			)
			(layer "F.SilkS")
		)
		(fp_line
			(start -0.508 -0.9398)
			(end -0.508 0.9398)
			(stroke
				(width 0.1524)
				(type default)
			)
			(layer "F.SilkS")
		)
		(fp_rect
			(start -0.508 0.9398)
			(end 0.508 -0.9398)
			(stroke
				(width 0)
				(type default)
			)
			(fill no)
			(layer "F.CrtYd")
		)
		(fp_rect
			(start -0.508 0.9398)
			(end 0.508 -0.9398)
			(stroke
				(width 0)
				(type default)
			)
			(fill no)
			(layer "F.Fab")
		)
		(pad "1" smd custom
			(at 0 -0.4445 90)
			(size 0.1397 0.1397)
			(layers "F.Cu" "F.Mask" "F.Paste")
			(net "P1V8_C")
			(options
				(clearance outline)
				(anchor circle)
			)
			(primitives
				(gr_poly
					(pts
						(arc
							(start -0.1778 -0.2794)
							(mid -0.249642 -0.249642)
							(end -0.2794 -0.1778)
						)
						(arc
							(start -0.2794 0.1778)
							(mid -0.249642 0.249642)
							(end -0.1778 0.2794)
						)
						(arc
							(start 0.1778 0.2794)
							(mid 0.249642 0.249642)
							(end 0.2794 0.1778)
						)
						(arc
							(start 0.2794 -0.1778)
							(mid 0.249642 -0.249642)
							(end 0.1778 -0.2794)
						)
					)
					(width 0)
					(fill yes)
				)
			)
		)
		(pad "2" smd custom
			(at 0 0.4445 90)
			(size 0.1397 0.1397)
			(layers "F.Cu" "F.Mask" "F.Paste")
			(net "P1V8_C_SENSE")
			(options
				(clearance outline)
				(anchor circle)
			)
			(primitives
				(gr_poly
					(pts
						(arc
							(start -0.1778 -0.2794)
							(mid -0.249642 -0.249642)
							(end -0.2794 -0.1778)
						)
						(arc
							(start -0.2794 0.1778)
							(mid -0.249642 0.249642)
							(end -0.1778 0.2794)
						)
						(arc
							(start 0.1778 0.2794)
							(mid 0.249642 0.249642)
							(end 0.2794 0.1778)
						)
						(arc
							(start 0.2794 -0.1778)
							(mid 0.249642 -0.249642)
							(end 0.1778 -0.2794)
						)
					)
					(width 0)
					(fill yes)
				)
			)
		)
	)
	(footprint ""
		(layer "F.Cu")
		(at 70.485 -58.674 90)
		(property "Reference" "L15"
			(at 0 0 90)
			(layer "F.SilkS")
			(hide yes)
			(effects
				(font
					(size 1.27 1.27)
				)
			)
		)
		(property "Value" "MPZ2012S300AT-GP"
			(at 0 -4.2418 90)
			(unlocked yes)
			(layer "F.Fab")
			(hide yes)
			(effects
				(font
					(size 1.016 1.016)
					(thickness 0.1524)
				)
			)
		)
		(property "Device Type" "L805H42"
			(at 0 -5.7912 90)
			(unlocked yes)
			(layer "F.Fab")
			(hide yes)
			(effects
				(font
					(size 1.016 1.016)
					(thickness 0.1524)
				)
			)
		)
		(duplicate_pad_numbers_are_jumpers no)
		(fp_line
			(start 0.889 -1.7018)
			(end 0.889 1.7018)
			(stroke
				(width 0.1524)
				(type default)
			)
			(layer "F.SilkS")
		)
		(fp_line
			(start -0.889 -1.7018)
			(end 0.889 -1.7018)
			(stroke
				(width 0.1524)
				(type default)
			)
			(layer "F.SilkS")
		)
		(fp_line
			(start 0.889 1.7018)
			(end -0.889 1.7018)
			(stroke
				(width 0.1524)
				(type default)
			)
			(layer "F.SilkS")
		)
		(fp_line
			(start -0.889 1.7018)
			(end -0.889 -1.7018)
			(stroke
				(width 0.1524)
				(type default)
			)
			(layer "F.SilkS")
		)
		(fp_rect
			(start -0.9652 1.778)
			(end 0.9652 -1.778)
			(stroke
				(width 0)
				(type default)
			)
			(fill no)
			(layer "F.CrtYd")
		)
		(fp_rect
			(start -0.9652 1.778)
			(end 0.9652 -1.778)
			(stroke
				(width 0)
				(type default)
			)
			(fill no)
			(layer "F.Fab")
		)
		(pad "1" smd rect
			(at 0 -0.9652 90)
			(size 1.397 1.143)
			(layers "F.Cu" "F.Mask" "F.Paste")
			(net "P0V9")
		)
		(pad "2" smd rect
			(at 0 0.9652 90)
			(size 1.397 1.143)
			(layers "F.Cu" "F.Mask" "F.Paste")
			(net "GB_VDDA")
		)
	)
	(footprint ""
		(layer "F.Cu")
		(at 38.3286 -34.671 -90)
		(property "Reference" "C712"
			(at 0 0 270)
			(layer "F.SilkS")
			(hide yes)
			(effects
				(font
					(size 1.27 1.27)
				)
			)
		)
		(property "Value" "SC1U16V2KX-7-GP"
			(at 1.7526 -1.6002 270)
			(unlocked yes)
			(layer "F.Fab")
			(hide yes)
			(effects
				(font
					(size 1.016 1.016)
					(thickness 0.1524)
				)
			)
		)
		(property "Device Type" "C402-TO0D2H24"
			(at 1.7526 -3.1242 270)
			(unlocked yes)
			(layer "F.Fab")
			(hide yes)
			(effects
				(font
					(size 1.016 1.016)
					(thickness 0.1524)
				)
			)
		)
		(duplicate_pad_numbers_are_jumpers no)
		(fp_rect
			(start -0.4826 0.889)
			(end 0.4826 -0.889)
			(stroke
				(width 0)
				(type default)
			)
			(fill no)
			(layer "F.CrtYd")
		)
		(fp_rect
			(start -0.4826 0.889)
			(end 0.4826 -0.889)
			(stroke
				(width 0)
				(type default)
			)
			(fill no)
			(layer "F.Fab")
		)
		(pad "1" smd custom
			(at 0 -0.4572 270)
			(size 0.1524 0.1524)
			(layers "F.Cu" "F.Mask" "F.Paste")
			(net "P0V9_EN")
			(options
				(clearance outline)
				(anchor circle)
			)
			(primitives
				(gr_poly
					(pts
						(arc
							(start -0.254 0.3048)
							(mid -0.325842 0.275042)
							(end -0.3556 0.2032)
						)
						(arc
							(start -0.3556 -0.2032)
							(mid -0.325842 -0.275042)
							(end -0.254 -0.3048)
						)
						(arc
							(start 0.254 -0.3048)
							(mid 0.325842 -0.275042)
							(end 0.3556 -0.2032)
						)
						(arc
							(start 0.3556 0.2032)
							(mid 0.325842 0.275042)
							(end 0.254 0.3048)
						)
					)
					(width 0)
					(fill yes)
				)
			)
		)
		(pad "2" smd custom
			(at 0 0.4572 270)
			(size 0.1524 0.1524)
			(layers "F.Cu" "F.Mask" "F.Paste")
			(net "GND")
			(options
				(clearance outline)
				(anchor circle)
			)
			(primitives
				(gr_poly
					(pts
						(arc
							(start -0.254 0.3048)
							(mid -0.325842 0.275042)
							(end -0.3556 0.2032)
						)
						(arc
							(start -0.3556 -0.2032)
							(mid -0.325842 -0.275042)
							(end -0.254 -0.3048)
						)
						(arc
							(start 0.254 -0.3048)
							(mid 0.325842 -0.275042)
							(end 0.3556 -0.2032)
						)
						(arc
							(start 0.3556 0.2032)
							(mid 0.325842 0.275042)
							(end 0.254 0.3048)
						)
					)
					(width 0)
					(fill yes)
				)
			)
		)
	)
	(footprint ""
		(layer "F.Cu")
		(at 176.5554 -96.52 180)
		(property "Reference" "R490"
			(at 0 0 180)
			(layer "F.SilkS")
			(hide yes)
			(effects
				(font
					(size 1.27 1.27)
				)
			)
		)
		(property "Value" "1K21R2F-2-GP"
			(at 0.064008 -3.993896 180)
			(unlocked yes)
			(layer "F.Fab")
			(hide yes)
			(effects
				(font
					(size 1.016 1.016)
					(thickness 0.1524)
				)
			)
		)
		(property "Device Type" "R402H16"
			(at 0.064008 -5.517896 180)
			(unlocked yes)
			(layer "F.Fab")
			(hide yes)
			(effects
				(font
					(size 1.016 1.016)
					(thickness 0.1524)
				)
			)
		)
		(duplicate_pad_numbers_are_jumpers no)
		(fp_line
			(start 0.508 -0.9398)
			(end -0.508 -0.9398)
			(stroke
				(width 0.1524)
				(type default)
			)
			(layer "F.SilkS")
		)
		(fp_line
			(start -0.508 -0.9398)
			(end -0.508 0.9398)
			(stroke
				(width 0.1524)
				(type default)
			)
			(layer "F.SilkS")
		)
		(fp_rect
			(start -0.508 0.9398)
			(end 0.508 -0.9398)
			(stroke
				(width 0)
				(type default)
			)
			(fill no)
			(layer "F.CrtYd")
		)
		(fp_rect
			(start -0.508 0.9398)
			(end 0.508 -0.9398)
			(stroke
				(width 0)
				(type default)
			)
			(fill no)
			(layer "F.Fab")
		)
		(pad "1" smd custom
			(at 0 -0.4445 180)
			(size 0.1397 0.1397)
			(layers "F.Cu" "F.Mask" "F.Paste")
			(net "VT235_VFB")
			(options
				(clearance outline)
				(anchor circle)
			)
			(primitives
				(gr_poly
					(pts
						(arc
							(start -0.1778 -0.2794)
							(mid -0.249642 -0.249642)
							(end -0.2794 -0.1778)
						)
						(arc
							(start -0.2794 0.1778)
							(mid -0.249642 0.249642)
							(end -0.1778 0.2794)
						)
						(arc
							(start 0.1778 0.2794)
							(mid 0.249642 0.249642)
							(end 0.2794 0.1778)
						)
						(arc
							(start 0.2794 -0.1778)
							(mid 0.249642 -0.249642)
							(end 0.1778 -0.2794)
						)
					)
					(width 0)
					(fill yes)
				)
			)
		)
		(pad "2" smd custom
			(at 0 0.4445 180)
			(size 0.1397 0.1397)
			(layers "F.Cu" "F.Mask" "F.Paste")
			(net "VT235_VDES_RC")
			(options
				(clearance outline)
				(anchor circle)
			)
			(primitives
				(gr_poly
					(pts
						(arc
							(start -0.1778 -0.2794)
							(mid -0.249642 -0.249642)
							(end -0.2794 -0.1778)
						)
						(arc
							(start -0.2794 0.1778)
							(mid -0.249642 0.249642)
							(end -0.1778 0.2794)
						)
						(arc
							(start 0.1778 0.2794)
							(mid 0.249642 0.249642)
							(end 0.2794 0.1778)
						)
						(arc
							(start 0.2794 -0.1778)
							(mid 0.249642 -0.249642)
							(end 0.1778 -0.2794)
						)
					)
					(width 0)
					(fill yes)
				)
			)
		)
	)
	(footprint ""
		(layer "F.Cu")
		(at 130.239516 -87.244936 180)
		(property "Reference" "R100"
			(at 0 0 180)
			(layer "F.SilkS")
			(hide yes)
			(effects
				(font
					(size 1.27 1.27)
				)
			)
		)
		(property "Value" "0R2J-2-GP"
			(at 0.064008 -3.993896 180)
			(unlocked yes)
			(layer "F.Fab")
			(hide yes)
			(effects
				(font
					(size 1.016 1.016)
					(thickness 0.1524)
				)
			)
		)
		(property "Device Type" "R402H16"
			(at 0.064008 -5.517896 180)
			(unlocked yes)
			(layer "F.Fab")
			(hide yes)
			(effects
				(font
					(size 1.016 1.016)
					(thickness 0.1524)
				)
			)
		)
		(duplicate_pad_numbers_are_jumpers no)
		(fp_line
			(start 0.508 -0.9398)
			(end -0.508 -0.9398)
			(stroke
				(width 0.1524)
				(type default)
			)
			(layer "F.SilkS")
		)
		(fp_line
			(start -0.508 -0.9398)
			(end -0.508 0.9398)
			(stroke
				(width 0.1524)
				(type default)
			)
			(layer "F.SilkS")
		)
		(fp_rect
			(start -0.508 0.9398)
			(end 0.508 -0.9398)
			(stroke
				(width 0)
				(type default)
			)
			(fill no)
			(layer "F.CrtYd")
		)
		(fp_rect
			(start -0.508 0.9398)
			(end 0.508 -0.9398)
			(stroke
				(width 0)
				(type default)
			)
			(fill no)
			(layer "F.Fab")
		)
		(pad "1" smd custom
			(at 0 -0.4445 180)
			(size 0.1397 0.1397)
			(layers "F.Cu" "F.Mask" "F.Paste")
			(net "SMART_RX")
			(options
				(clearance outline)
				(anchor circle)
			)
			(primitives
				(gr_poly
					(pts
						(arc
							(start -0.1778 -0.2794)
							(mid -0.249642 -0.249642)
							(end -0.2794 -0.1778)
						)
						(arc
							(start -0.2794 0.1778)
							(mid -0.249642 0.249642)
							(end -0.1778 0.2794)
						)
						(arc
							(start 0.1778 0.2794)
							(mid 0.249642 0.249642)
							(end 0.2794 0.1778)
						)
						(arc
							(start 0.2794 -0.1778)
							(mid 0.249642 -0.249642)
							(end 0.1778 -0.2794)
						)
					)
					(width 0)
					(fill yes)
				)
			)
		)
		(pad "2" smd custom
			(at 0 0.4445 180)
			(size 0.1397 0.1397)
			(layers "F.Cu" "F.Mask" "F.Paste")
			(net "SAS_SMART_RX")
			(options
				(clearance outline)
				(anchor circle)
			)
			(primitives
				(gr_poly
					(pts
						(arc
							(start -0.1778 -0.2794)
							(mid -0.249642 -0.249642)
							(end -0.2794 -0.1778)
						)
						(arc
							(start -0.2794 0.1778)
							(mid -0.249642 0.249642)
							(end -0.1778 0.2794)
						)
						(arc
							(start 0.1778 0.2794)
							(mid 0.249642 0.249642)
							(end 0.2794 0.1778)
						)
						(arc
							(start 0.2794 -0.1778)
							(mid 0.249642 -0.249642)
							(end 0.1778 -0.2794)
						)
					)
					(width 0)
					(fill yes)
				)
			)
		)
	)
	(footprint ""
		(layer "F.Cu")
		(at 45.339 -49.784 180)
		(property "Reference" "C672"
			(at 0 0 180)
			(layer "F.SilkS")
			(hide yes)
			(effects
				(font
					(size 1.27 1.27)
				)
			)
		)
		(property "Value" "SCD1U50V3KX-GP"
			(at 0 -2.8194 180)
			(unlocked yes)
			(layer "F.Fab")
			(hide yes)
			(effects
				(font
					(size 1.016 1.016)
					(thickness 0.1524)
				)
			)
		)
		(property "Device Type" "C603H36"
			(at 0 -4.3434 180)
			(unlocked yes)
			(layer "F.Fab")
			(hide yes)
			(effects
				(font
					(size 1.016 1.016)
					(thickness 0.1524)
				)
			)
		)
		(duplicate_pad_numbers_are_jumpers no)
		(fp_line
			(start 0.508 0)
			(end -0.508 0)
			(stroke
				(width 0.2032)
				(type default)
			)
			(layer "F.SilkS")
		)
		(fp_rect
			(start -0.5842 1.3335)
			(end 0.5842 -1.3335)
			(stroke
				(width 0)
				(type default)
			)
			(fill no)
			(layer "F.CrtYd")
		)
		(fp_rect
			(start -0.5842 1.3335)
			(end 0.5842 -1.3335)
			(stroke
				(width 0)
				(type default)
			)
			(fill no)
			(layer "F.Fab")
		)
		(pad "1" smd custom
			(at 0 -0.762 180)
			(size 0.2159 0.2159)
			(layers "F.Cu" "F.Mask" "F.Paste")
			(net "P12V_STBY_VIN_Q7")
			(options
				(clearance outline)
				(anchor circle)
			)
			(primitives
				(gr_poly
					(pts
						(arc
							(start -0.3302 -0.4318)
							(mid -0.402042 -0.402042)
							(end -0.4318 -0.3302)
						)
						(arc
							(start -0.4318 0.3302)
							(mid -0.402042 0.402042)
							(end -0.3302 0.4318)
						)
						(arc
							(start 0.3302 0.4318)
							(mid 0.402042 0.402042)
							(end 0.4318 0.3302)
						)
						(arc
							(start 0.4318 -0.3302)
							(mid 0.402042 -0.402042)
							(end 0.3302 -0.4318)
						)
					)
					(width 0)
					(fill yes)
				)
			)
		)
		(pad "2" smd custom
			(at 0 0.762 180)
			(size 0.2159 0.2159)
			(layers "F.Cu" "F.Mask" "F.Paste")
			(net "GND")
			(options
				(clearance outline)
				(anchor circle)
			)
			(primitives
				(gr_poly
					(pts
						(arc
							(start -0.3302 -0.4318)
							(mid -0.402042 -0.402042)
							(end -0.4318 -0.3302)
						)
						(arc
							(start -0.4318 0.3302)
							(mid -0.402042 0.402042)
							(end -0.3302 0.4318)
						)
						(arc
							(start 0.3302 0.4318)
							(mid 0.402042 0.402042)
							(end 0.4318 0.3302)
						)
						(arc
							(start 0.4318 -0.3302)
							(mid 0.402042 -0.402042)
							(end 0.3302 -0.4318)
						)
					)
					(width 0)
					(fill yes)
				)
			)
		)
	)
	(footprint ""
		(layer "F.Cu")
		(at 81.650586 -76.63053 90)
		(property "Reference" "BLED1"
			(at 0 0 90)
			(layer "F.SilkS")
			(hide yes)
			(effects
				(font
					(size 1.27 1.27)
				)
			)
		)
		(property "Value" "LED-YG-51-GP"
			(at -2.6924 -1.4224 90)
			(unlocked yes)
			(layer "F.Fab")
			(hide yes)
			(effects
				(font
					(size 1.016 1.016)
					(thickness 0.1524)
				)
			)
		)
		(property "Device Type" "LED1608AKH40"
			(at -2.6924 -2.9464 90)
			(unlocked yes)
			(layer "F.Fab")
			(hide yes)
			(effects
				(font
					(size 1.016 1.016)
					(thickness 0.1524)
				)
			)
		)
		(duplicate_pad_numbers_are_jumpers no)
		(fp_line
			(start 0.6604 -1.3716)
			(end 0.6604 1.3716)
			(stroke
				(width 0.1524)
				(type default)
			)
			(layer "F.SilkS")
		)
		(fp_line
			(start -0.6604 -1.3716)
			(end 0.6604 -1.3716)
			(stroke
				(width 0.1524)
				(type default)
			)
			(layer "F.SilkS")
		)
		(fp_line
			(start 0.6604 1.3716)
			(end -0.6604 1.3716)
			(stroke
				(width 0.1524)
				(type default)
			)
			(layer "F.SilkS")
		)
		(fp_line
			(start -0.6604 1.3716)
			(end -0.6604 -1.3716)
			(stroke
				(width 0.1524)
				(type default)
			)
			(layer "F.SilkS")
		)
		(fp_line
			(start -0.5969 1.5494)
			(end 0.5842 1.5494)
			(stroke
				(width 0.508)
				(type default)
			)
			(layer "F.SilkS")
		)
		(fp_line
			(start 0.7493 1.651)
			(end 0.7493 1.1811)
			(stroke
				(width 0.3302)
				(type default)
			)
			(layer "F.SilkS")
		)
		(fp_line
			(start -0.7493 1.651)
			(end -0.7493 1.1811)
			(stroke
				(width 0.3302)
				(type default)
			)
			(layer "F.SilkS")
		)
		(fp_rect
			(start -0.6223 1.3335)
			(end 0.6223 -1.3335)
			(stroke
				(width 0)
				(type default)
			)
			(fill no)
			(layer "F.CrtYd")
		)
		(fp_rect
			(start -0.6223 1.3335)
			(end 0.6223 -1.3335)
			(stroke
				(width 0)
				(type default)
			)
			(fill no)
			(layer "F.Fab")
		)
		(pad "A" smd custom
			(at 0 -0.762 90)
			(size 0.2159 0.2159)
			(layers "F.Cu" "F.Mask" "F.Paste")
			(net "EXP_HW_LED_R")
			(options
				(clearance outline)
				(anchor circle)
			)
			(primitives
				(gr_poly
					(pts
						(arc
							(start -0.3302 -0.4318)
							(mid -0.402042 -0.402042)
							(end -0.4318 -0.3302)
						)
						(arc
							(start -0.4318 0.3302)
							(mid -0.402042 0.402042)
							(end -0.3302 0.4318)
						)
						(arc
							(start 0.3302 0.4318)
							(mid 0.402042 0.402042)
							(end 0.4318 0.3302)
						)
						(arc
							(start 0.4318 -0.3302)
							(mid 0.402042 -0.402042)
							(end 0.3302 -0.4318)
						)
					)
					(width 0)
					(fill yes)
				)
			)
		)
		(pad "K" smd custom
			(at 0 0.762 90)
			(size 0.2159 0.2159)
			(layers "F.Cu" "F.Mask" "F.Paste")
			(net "EXP_HW_LED_D")
			(options
				(clearance outline)
				(anchor circle)
			)
			(primitives
				(gr_poly
					(pts
						(arc
							(start -0.3302 -0.4318)
							(mid -0.402042 -0.402042)
							(end -0.4318 -0.3302)
						)
						(arc
							(start -0.4318 0.3302)
							(mid -0.402042 0.402042)
							(end -0.3302 0.4318)
						)
						(arc
							(start 0.3302 0.4318)
							(mid 0.402042 0.402042)
							(end 0.4318 0.3302)
						)
						(arc
							(start 0.4318 -0.3302)
							(mid 0.402042 -0.402042)
							(end 0.3302 -0.4318)
						)
					)
					(width 0)
					(fill yes)
				)
			)
		)
	)
	(footprint ""
		(layer "F.Cu")
		(at 196.369432 -77.457554 90)
		(property "Reference" "U30"
			(at 0 0 90)
			(layer "F.SilkS")
			(hide yes)
			(effects
				(font
					(size 1.27 1.27)
				)
			)
		)
		(property "Value" "TMP75AIDGKR-GP"
			(at -0.1143 -9.1948 90)
			(unlocked yes)
			(layer "F.Fab")
			(hide yes)
			(effects
				(font
					(size 1.016 1.016)
					(thickness 0.1524)
				)
			)
		)
		(property "Device Type" "MSOP8-1H44"
			(at -0.1143 -10.795 90)
			(unlocked yes)
			(layer "F.Fab")
			(hide yes)
			(effects
				(font
					(size 1.016 1.016)
					(thickness 0.1524)
				)
			)
		)
		(duplicate_pad_numbers_are_jumpers no)
		(fp_line
			(start 1.0795 -1.016)
			(end -1.9558 -1.016)
			(stroke
				(width 0.1524)
				(type default)
			)
			(layer "F.SilkS")
		)
		(fp_line
			(start -1.9558 -1.016)
			(end -1.9558 1.016)
			(stroke
				(width 0.1524)
				(type default)
			)
			(layer "F.SilkS")
		)
		(fp_line
			(start -1.9558 -0.5461)
			(end -1.4478 -0.0381)
			(stroke
				(width 0.1524)
				(type default)
			)
			(layer "F.SilkS")
		)
		(fp_line
			(start -1.4478 -0.0381)
			(end -1.9558 0.4699)
			(stroke
				(width 0.1524)
				(type default)
			)
			(layer "F.SilkS")
		)
		(fp_line
			(start 1.0795 1.016)
			(end 1.0795 -1.016)
			(stroke
				(width 0.1524)
				(type default)
			)
			(layer "F.SilkS")
		)
		(fp_line
			(start -1.9558 1.016)
			(end 1.0795 1.016)
			(stroke
				(width 0.1524)
				(type default)
			)
			(layer "F.SilkS")
		)
		(fp_line
			(start -1.778 1.0922)
			(end -1.778 3.048)
			(stroke
				(width 0.508)
				(type default)
			)
			(layer "F.SilkS")
		)
		(fp_poly
			(pts
				(xy -1.1557 -1.016) (xy -1.1557 1.016) (xy 1.1557 1.016) (xy 1.1557 -1.016)
			)
			(stroke
				(width 0)
				(type default)
			)
			(fill yes)
			(layer "F.SilkS")
		)
		(fp_rect
			(start -1.4986 2.4511)
			(end 1.4986 -2.4511)
			(stroke
				(width 0)
				(type default)
			)
			(fill no)
			(layer "F.CrtYd")
		)
		(fp_poly
			(pts
				(xy -2.032 3.302) (xy -2.032 -3.302) (xy 2.032 -3.302) (xy 2.032 -2.1209) (xy 1.4986 -2.1209) (xy 1.4986 -2.4511)
				(xy -1.4986 -2.4511) (xy -1.4986 2.4511) (xy 1.4986 2.4511) (xy 1.4986 -2.1082) (xy 2.032 -2.1082)
				(xy 2.032 3.302)
			)
			(stroke
				(width 0)
				(type default)
			)
			(fill no)
			(layer "F.CrtYd")
		)
		(fp_rect
			(start -2.032 3.302)
			(end 2.032 -3.302)
			(stroke
				(width 0)
				(type default)
			)
			(fill no)
			(layer "F.Fab")
		)
		(pad "1" smd rect
			(at -0.97536 2.05486 90)
			(size 0.3556 1.524)
			(layers "F.Cu" "F.Mask" "F.Paste")
			(net "TEMP2_SDA")
		)
		(pad "2" smd rect
			(at -0.32512 2.05486 90)
			(size 0.3556 1.524)
			(layers "F.Cu" "F.Mask" "F.Paste")
			(net "TEMP2_SCL")
		)
		(pad "3" smd rect
			(at 0.32512 2.05486 90)
			(size 0.3556 1.524)
			(layers "F.Cu" "F.Mask" "F.Paste")
			(net "TEMP2_ALERT")
		)
		(pad "4" smd rect
			(at 0.97536 2.05486 90)
			(size 0.3556 1.524)
			(layers "F.Cu" "F.Mask" "F.Paste")
			(net "GND")
		)
		(pad "5" smd rect
			(at 0.97536 -2.05486 90)
			(size 0.3556 1.524)
			(layers "F.Cu" "F.Mask" "F.Paste")
			(net "TEMP2_A2")
		)
		(pad "6" smd rect
			(at 0.32512 -2.05486 90)
			(size 0.3556 1.524)
			(layers "F.Cu" "F.Mask" "F.Paste")
			(net "TEMP2_A1")
		)
		(pad "7" smd rect
			(at -0.32512 -2.05486 90)
			(size 0.3556 1.524)
			(layers "F.Cu" "F.Mask" "F.Paste")
			(net "TEMP2_A0")
		)
		(pad "8" smd rect
			(at -0.97536 -2.05486 90)
			(size 0.3556 1.524)
			(layers "F.Cu" "F.Mask" "F.Paste")
			(net "P3V3")
		)
	)
	(footprint ""
		(layer "F.Cu")
		(at 179.35448 -110.80242)
		(property "Reference" "R603"
			(at 0 0 0)
			(layer "F.SilkS")
			(hide yes)
			(effects
				(font
					(size 1.27 1.27)
				)
			)
		)
		(property "Value" "0R2J-2-GP"
			(at 0.064008 -3.993896 0)
			(unlocked yes)
			(layer "F.Fab")
			(hide yes)
			(effects
				(font
					(size 1.016 1.016)
					(thickness 0.1524)
				)
			)
		)
		(property "Device Type" "R402H16"
			(at 0.064008 -5.517896 0)
			(unlocked yes)
			(layer "F.Fab")
			(hide yes)
			(effects
				(font
					(size 1.016 1.016)
					(thickness 0.1524)
				)
			)
		)
		(duplicate_pad_numbers_are_jumpers no)
		(fp_line
			(start -0.508 -0.9398)
			(end -0.508 0.9398)
			(stroke
				(width 0.1524)
				(type default)
			)
			(layer "F.SilkS")
		)
		(fp_line
			(start 0.508 -0.9398)
			(end -0.508 -0.9398)
			(stroke
				(width 0.1524)
				(type default)
			)
			(layer "F.SilkS")
		)
		(fp_rect
			(start -0.508 0.9398)
			(end 0.508 -0.9398)
			(stroke
				(width 0)
				(type default)
			)
			(fill no)
			(layer "F.CrtYd")
		)
		(fp_rect
			(start -0.508 0.9398)
			(end 0.508 -0.9398)
			(stroke
				(width 0)
				(type default)
			)
			(fill no)
			(layer "F.Fab")
		)
		(pad "1" smd custom
			(at 0 -0.4445)
			(size 0.1397 0.1397)
			(layers "F.Cu" "F.Mask" "F.Paste")
			(net "P1V8_C_PG")
			(options
				(clearance outline)
				(anchor circle)
			)
			(primitives
				(gr_poly
					(pts
						(arc
							(start -0.1778 -0.2794)
							(mid -0.249642 -0.249642)
							(end -0.2794 -0.1778)
						)
						(arc
							(start -0.2794 0.1778)
							(mid -0.249642 0.249642)
							(end -0.1778 0.2794)
						)
						(arc
							(start 0.1778 0.2794)
							(mid 0.249642 0.249642)
							(end 0.2794 0.1778)
						)
						(arc
							(start 0.2794 -0.1778)
							(mid 0.249642 -0.249642)
							(end 0.1778 -0.2794)
						)
					)
					(width 0)
					(fill yes)
				)
			)
		)
		(pad "2" smd custom
			(at 0 0.4445)
			(size 0.1397 0.1397)
			(layers "F.Cu" "F.Mask" "F.Paste")
			(net "P1V8_C_PG_R_1")
			(options
				(clearance outline)
				(anchor circle)
			)
			(primitives
				(gr_poly
					(pts
						(arc
							(start -0.1778 -0.2794)
							(mid -0.249642 -0.249642)
							(end -0.2794 -0.1778)
						)
						(arc
							(start -0.2794 0.1778)
							(mid -0.249642 0.249642)
							(end -0.1778 0.2794)
						)
						(arc
							(start 0.1778 0.2794)
							(mid 0.249642 0.249642)
							(end 0.2794 0.1778)
						)
						(arc
							(start 0.2794 -0.1778)
							(mid 0.249642 -0.249642)
							(end 0.1778 -0.2794)
						)
					)
					(width 0)
					(fill yes)
				)
			)
		)
	)
	(footprint ""
		(layer "F.Cu")
		(at 144.54378 -117.66042 180)
		(property "Reference" "C675"
			(at 0 0 180)
			(layer "F.SilkS")
			(hide yes)
			(effects
				(font
					(size 1.27 1.27)
				)
			)
		)
		(property "Value" "SCD1U50V3KX-GP"
			(at 0 -2.8194 180)
			(unlocked yes)
			(layer "F.Fab")
			(hide yes)
			(effects
				(font
					(size 1.016 1.016)
					(thickness 0.1524)
				)
			)
		)
		(property "Device Type" "C603H36"
			(at 0 -4.3434 180)
			(unlocked yes)
			(layer "F.Fab")
			(hide yes)
			(effects
				(font
					(size 1.016 1.016)
					(thickness 0.1524)
				)
			)
		)
		(duplicate_pad_numbers_are_jumpers no)
		(fp_line
			(start 0.508 0)
			(end -0.508 0)
			(stroke
				(width 0.2032)
				(type default)
			)
			(layer "F.SilkS")
		)
		(fp_rect
			(start -0.5842 1.3335)
			(end 0.5842 -1.3335)
			(stroke
				(width 0)
				(type default)
			)
			(fill no)
			(layer "F.CrtYd")
		)
		(fp_rect
			(start -0.5842 1.3335)
			(end 0.5842 -1.3335)
			(stroke
				(width 0)
				(type default)
			)
			(fill no)
			(layer "F.Fab")
		)
		(pad "1" smd custom
			(at 0 -0.762 180)
			(size 0.2159 0.2159)
			(layers "F.Cu" "F.Mask" "F.Paste")
			(net "P1V5_E_OUT")
			(options
				(clearance outline)
				(anchor circle)
			)
			(primitives
				(gr_poly
					(pts
						(arc
							(start -0.3302 -0.4318)
							(mid -0.402042 -0.402042)
							(end -0.4318 -0.3302)
						)
						(arc
							(start -0.4318 0.3302)
							(mid -0.402042 0.402042)
							(end -0.3302 0.4318)
						)
						(arc
							(start 0.3302 0.4318)
							(mid 0.402042 0.402042)
							(end 0.4318 0.3302)
						)
						(arc
							(start 0.4318 -0.3302)
							(mid 0.402042 -0.402042)
							(end 0.3302 -0.4318)
						)
					)
					(width 0)
					(fill yes)
				)
			)
		)
		(pad "2" smd custom
			(at 0 0.762 180)
			(size 0.2159 0.2159)
			(layers "F.Cu" "F.Mask" "F.Paste")
			(net "P1V5_E_LL_R")
			(options
				(clearance outline)
				(anchor circle)
			)
			(primitives
				(gr_poly
					(pts
						(arc
							(start -0.3302 -0.4318)
							(mid -0.402042 -0.402042)
							(end -0.4318 -0.3302)
						)
						(arc
							(start -0.4318 0.3302)
							(mid -0.402042 0.402042)
							(end -0.3302 0.4318)
						)
						(arc
							(start 0.3302 0.4318)
							(mid 0.402042 0.402042)
							(end 0.4318 0.3302)
						)
						(arc
							(start 0.4318 -0.3302)
							(mid 0.402042 -0.402042)
							(end 0.3302 -0.4318)
						)
					)
					(width 0)
					(fill yes)
				)
			)
		)
	)
	(footprint ""
		(layer "F.Cu")
		(at 82.2706 -63.373)
		(property "Reference" "R76"
			(at 0 0 0)
			(layer "F.SilkS")
			(hide yes)
			(effects
				(font
					(size 1.27 1.27)
				)
			)
		)
		(property "Value" "0R2J-2-GP"
			(at 0.064008 -3.993896 0)
			(unlocked yes)
			(layer "F.Fab")
			(hide yes)
			(effects
				(font
					(size 1.016 1.016)
					(thickness 0.1524)
				)
			)
		)
		(property "Device Type" "R402H16"
			(at 0.064008 -5.517896 0)
			(unlocked yes)
			(layer "F.Fab")
			(hide yes)
			(effects
				(font
					(size 1.016 1.016)
					(thickness 0.1524)
				)
			)
		)
		(duplicate_pad_numbers_are_jumpers no)
		(fp_line
			(start -0.508 -0.9398)
			(end -0.508 0.9398)
			(stroke
				(width 0.1524)
				(type default)
			)
			(layer "F.SilkS")
		)
		(fp_line
			(start 0.508 -0.9398)
			(end -0.508 -0.9398)
			(stroke
				(width 0.1524)
				(type default)
			)
			(layer "F.SilkS")
		)
		(fp_rect
			(start -0.508 0.9398)
			(end 0.508 -0.9398)
			(stroke
				(width 0)
				(type default)
			)
			(fill no)
			(layer "F.CrtYd")
		)
		(fp_rect
			(start -0.508 0.9398)
			(end 0.508 -0.9398)
			(stroke
				(width 0)
				(type default)
			)
			(fill no)
			(layer "F.Fab")
		)
		(pad "1" smd custom
			(at 0 -0.4445)
			(size 0.1397 0.1397)
			(layers "F.Cu" "F.Mask" "F.Paste")
			(net "LS_EN_U24")
			(options
				(clearance outline)
				(anchor circle)
			)
			(primitives
				(gr_poly
					(pts
						(arc
							(start -0.1778 -0.2794)
							(mid -0.249642 -0.249642)
							(end -0.2794 -0.1778)
						)
						(arc
							(start -0.2794 0.1778)
							(mid -0.249642 0.249642)
							(end -0.1778 0.2794)
						)
						(arc
							(start 0.1778 0.2794)
							(mid 0.249642 0.249642)
							(end 0.2794 0.1778)
						)
						(arc
							(start 0.2794 -0.1778)
							(mid 0.249642 -0.249642)
							(end 0.1778 -0.2794)
						)
					)
					(width 0)
					(fill yes)
				)
			)
		)
		(pad "2" smd custom
			(at 0 0.4445)
			(size 0.1397 0.1397)
			(layers "F.Cu" "F.Mask" "F.Paste")
			(net "LS_EN_N")
			(options
				(clearance outline)
				(anchor circle)
			)
			(primitives
				(gr_poly
					(pts
						(arc
							(start -0.1778 -0.2794)
							(mid -0.249642 -0.249642)
							(end -0.2794 -0.1778)
						)
						(arc
							(start -0.2794 0.1778)
							(mid -0.249642 0.249642)
							(end -0.1778 0.2794)
						)
						(arc
							(start 0.1778 0.2794)
							(mid 0.249642 0.249642)
							(end 0.2794 0.1778)
						)
						(arc
							(start 0.2794 -0.1778)
							(mid 0.249642 -0.249642)
							(end 0.1778 -0.2794)
						)
					)
					(width 0)
					(fill yes)
				)
			)
		)
	)
	(footprint ""
		(layer "F.Cu")
		(at 94.234 -70.993 -90)
		(property "Reference" "R148"
			(at 0 0 270)
			(layer "F.SilkS")
			(hide yes)
			(effects
				(font
					(size 1.27 1.27)
				)
			)
		)
		(property "Value" "4K75R2F-1-GP"
			(at 0.064008 -3.993896 270)
			(unlocked yes)
			(layer "F.Fab")
			(hide yes)
			(effects
				(font
					(size 1.016 1.016)
					(thickness 0.1524)
				)
			)
		)
		(property "Device Type" "R402H16"
			(at 0.064008 -5.517896 270)
			(unlocked yes)
			(layer "F.Fab")
			(hide yes)
			(effects
				(font
					(size 1.016 1.016)
					(thickness 0.1524)
				)
			)
		)
		(duplicate_pad_numbers_are_jumpers no)
		(fp_line
			(start -0.508 -0.9398)
			(end -0.508 0.9398)
			(stroke
				(width 0.1524)
				(type default)
			)
			(layer "F.SilkS")
		)
		(fp_line
			(start 0.508 -0.9398)
			(end -0.508 -0.9398)
			(stroke
				(width 0.1524)
				(type default)
			)
			(layer "F.SilkS")
		)
		(fp_rect
			(start -0.508 0.9398)
			(end 0.508 -0.9398)
			(stroke
				(width 0)
				(type default)
			)
			(fill no)
			(layer "F.CrtYd")
		)
		(fp_rect
			(start -0.508 0.9398)
			(end 0.508 -0.9398)
			(stroke
				(width 0)
				(type default)
			)
			(fill no)
			(layer "F.Fab")
		)
		(pad "1" smd custom
			(at 0 -0.4445 270)
			(size 0.1397 0.1397)
			(layers "F.Cu" "F.Mask" "F.Paste")
			(net "LSI_SCAN_ENABLE")
			(options
				(clearance outline)
				(anchor circle)
			)
			(primitives
				(gr_poly
					(pts
						(arc
							(start -0.1778 -0.2794)
							(mid -0.249642 -0.249642)
							(end -0.2794 -0.1778)
						)
						(arc
							(start -0.2794 0.1778)
							(mid -0.249642 0.249642)
							(end -0.1778 0.2794)
						)
						(arc
							(start 0.1778 0.2794)
							(mid 0.249642 0.249642)
							(end 0.2794 0.1778)
						)
						(arc
							(start 0.2794 -0.1778)
							(mid 0.249642 -0.249642)
							(end 0.1778 -0.2794)
						)
					)
					(width 0)
					(fill yes)
				)
			)
		)
		(pad "2" smd custom
			(at 0 0.4445 270)
			(size 0.1397 0.1397)
			(layers "F.Cu" "F.Mask" "F.Paste")
			(net "P1V8_E")
			(options
				(clearance outline)
				(anchor circle)
			)
			(primitives
				(gr_poly
					(pts
						(arc
							(start -0.1778 -0.2794)
							(mid -0.249642 -0.249642)
							(end -0.2794 -0.1778)
						)
						(arc
							(start -0.2794 0.1778)
							(mid -0.249642 0.249642)
							(end -0.1778 0.2794)
						)
						(arc
							(start 0.1778 0.2794)
							(mid 0.249642 0.249642)
							(end 0.2794 0.1778)
						)
						(arc
							(start 0.2794 -0.1778)
							(mid 0.249642 -0.249642)
							(end 0.1778 -0.2794)
						)
					)
					(width 0)
					(fill yes)
				)
			)
		)
	)
	(footprint ""
		(layer "F.Cu")
		(at 83.397852 -102.881176 -90)
		(property "Reference" "R545"
			(at 0 0 270)
			(layer "F.SilkS")
			(hide yes)
			(effects
				(font
					(size 1.27 1.27)
				)
			)
		)
		(property "Value" "0R2J-2-GP"
			(at 0.064008 -3.993896 270)
			(unlocked yes)
			(layer "F.Fab")
			(hide yes)
			(effects
				(font
					(size 1.016 1.016)
					(thickness 0.1524)
				)
			)
		)
		(property "Device Type" "R402H16"
			(at 0.064008 -5.517896 270)
			(unlocked yes)
			(layer "F.Fab")
			(hide yes)
			(effects
				(font
					(size 1.016 1.016)
					(thickness 0.1524)
				)
			)
		)
		(duplicate_pad_numbers_are_jumpers no)
		(fp_line
			(start -0.508 -0.9398)
			(end -0.508 0.9398)
			(stroke
				(width 0.1524)
				(type default)
			)
			(layer "F.SilkS")
		)
		(fp_line
			(start 0.508 -0.9398)
			(end -0.508 -0.9398)
			(stroke
				(width 0.1524)
				(type default)
			)
			(layer "F.SilkS")
		)
		(fp_rect
			(start -0.508 0.9398)
			(end 0.508 -0.9398)
			(stroke
				(width 0)
				(type default)
			)
			(fill no)
			(layer "F.CrtYd")
		)
		(fp_rect
			(start -0.508 0.9398)
			(end 0.508 -0.9398)
			(stroke
				(width 0)
				(type default)
			)
			(fill no)
			(layer "F.Fab")
		)
		(pad "1" smd custom
			(at 0 -0.4445 270)
			(size 0.1397 0.1397)
			(layers "F.Cu" "F.Mask" "F.Paste")
			(net "SCC_FULL_PWR_EN")
			(options
				(clearance outline)
				(anchor circle)
			)
			(primitives
				(gr_poly
					(pts
						(arc
							(start -0.1778 -0.2794)
							(mid -0.249642 -0.249642)
							(end -0.2794 -0.1778)
						)
						(arc
							(start -0.2794 0.1778)
							(mid -0.249642 0.249642)
							(end -0.1778 0.2794)
						)
						(arc
							(start 0.1778 0.2794)
							(mid 0.249642 0.249642)
							(end 0.2794 0.1778)
						)
						(arc
							(start 0.2794 -0.1778)
							(mid 0.249642 -0.249642)
							(end 0.1778 -0.2794)
						)
					)
					(width 0)
					(fill yes)
				)
			)
		)
		(pad "2" smd custom
			(at 0 0.4445 270)
			(size 0.1397 0.1397)
			(layers "F.Cu" "F.Mask" "F.Paste")
			(net "SCC_FULL_PWR_BUF_EN")
			(options
				(clearance outline)
				(anchor circle)
			)
			(primitives
				(gr_poly
					(pts
						(arc
							(start -0.1778 -0.2794)
							(mid -0.249642 -0.249642)
							(end -0.2794 -0.1778)
						)
						(arc
							(start -0.2794 0.1778)
							(mid -0.249642 0.249642)
							(end -0.1778 0.2794)
						)
						(arc
							(start 0.1778 0.2794)
							(mid 0.249642 0.249642)
							(end 0.2794 0.1778)
						)
						(arc
							(start 0.2794 -0.1778)
							(mid 0.249642 -0.249642)
							(end 0.1778 -0.2794)
						)
					)
					(width 0)
					(fill yes)
				)
			)
		)
	)
	(footprint ""
		(layer "F.Cu")
		(at 21.7932 -53.1876 90)
		(property "Reference" "C651"
			(at 0 0 90)
			(layer "F.SilkS")
			(hide yes)
			(effects
				(font
					(size 1.27 1.27)
				)
			)
		)
		(property "Value" "SCD1U50V3KX-GP"
			(at 0 -2.8194 90)
			(unlocked yes)
			(layer "F.Fab")
			(hide yes)
			(effects
				(font
					(size 1.016 1.016)
					(thickness 0.1524)
				)
			)
		)
		(property "Device Type" "C603H36"
			(at 0 -4.3434 90)
			(unlocked yes)
			(layer "F.Fab")
			(hide yes)
			(effects
				(font
					(size 1.016 1.016)
					(thickness 0.1524)
				)
			)
		)
		(duplicate_pad_numbers_are_jumpers no)
		(fp_line
			(start 0.508 0)
			(end -0.508 0)
			(stroke
				(width 0.2032)
				(type default)
			)
			(layer "F.SilkS")
		)
		(fp_rect
			(start -0.5842 1.3335)
			(end 0.5842 -1.3335)
			(stroke
				(width 0)
				(type default)
			)
			(fill no)
			(layer "F.CrtYd")
		)
		(fp_rect
			(start -0.5842 1.3335)
			(end 0.5842 -1.3335)
			(stroke
				(width 0)
				(type default)
			)
			(fill no)
			(layer "F.Fab")
		)
		(pad "1" smd custom
			(at 0 -0.762 90)
			(size 0.2159 0.2159)
			(layers "F.Cu" "F.Mask" "F.Paste")
			(net "MB0_ISET_R")
			(options
				(clearance outline)
				(anchor circle)
			)
			(primitives
				(gr_poly
					(pts
						(arc
							(start -0.3302 -0.4318)
							(mid -0.402042 -0.402042)
							(end -0.4318 -0.3302)
						)
						(arc
							(start -0.4318 0.3302)
							(mid -0.402042 0.402042)
							(end -0.3302 0.4318)
						)
						(arc
							(start 0.3302 0.4318)
							(mid 0.402042 0.402042)
							(end 0.4318 0.3302)
						)
						(arc
							(start 0.4318 -0.3302)
							(mid 0.402042 -0.402042)
							(end 0.3302 -0.4318)
						)
					)
					(width 0)
					(fill yes)
				)
			)
		)
		(pad "2" smd custom
			(at 0 0.762 90)
			(size 0.2159 0.2159)
			(layers "F.Cu" "F.Mask" "F.Paste")
			(net "AGND_CURRENT_MON")
			(options
				(clearance outline)
				(anchor circle)
			)
			(primitives
				(gr_poly
					(pts
						(arc
							(start -0.3302 -0.4318)
							(mid -0.402042 -0.402042)
							(end -0.4318 -0.3302)
						)
						(arc
							(start -0.4318 0.3302)
							(mid -0.402042 0.402042)
							(end -0.3302 0.4318)
						)
						(arc
							(start 0.3302 0.4318)
							(mid 0.402042 0.402042)
							(end 0.4318 0.3302)
						)
						(arc
							(start 0.4318 -0.3302)
							(mid 0.402042 -0.402042)
							(end 0.3302 -0.4318)
						)
					)
					(width 0)
					(fill yes)
				)
			)
		)
	)
	(footprint ""
		(layer "F.Cu")
		(at 154.612594 -71.60387)
		(property "Reference" "R328"
			(at 0 0 0)
			(layer "F.SilkS")
			(hide yes)
			(effects
				(font
					(size 1.27 1.27)
				)
			)
		)
		(property "Value" "0R2J-2-GP"
			(at 0.064008 -3.993896 0)
			(unlocked yes)
			(layer "F.Fab")
			(hide yes)
			(effects
				(font
					(size 1.016 1.016)
					(thickness 0.1524)
				)
			)
		)
		(property "Device Type" "R402H16"
			(at 0.064008 -5.517896 0)
			(unlocked yes)
			(layer "F.Fab")
			(hide yes)
			(effects
				(font
					(size 1.016 1.016)
					(thickness 0.1524)
				)
			)
		)
		(duplicate_pad_numbers_are_jumpers no)
		(fp_line
			(start -0.508 -0.9398)
			(end -0.508 0.9398)
			(stroke
				(width 0.1524)
				(type default)
			)
			(layer "F.SilkS")
		)
		(fp_line
			(start 0.508 -0.9398)
			(end -0.508 -0.9398)
			(stroke
				(width 0.1524)
				(type default)
			)
			(layer "F.SilkS")
		)
		(fp_rect
			(start -0.508 0.9398)
			(end 0.508 -0.9398)
			(stroke
				(width 0)
				(type default)
			)
			(fill no)
			(layer "F.CrtYd")
		)
		(fp_rect
			(start -0.508 0.9398)
			(end 0.508 -0.9398)
			(stroke
				(width 0)
				(type default)
			)
			(fill no)
			(layer "F.Fab")
		)
		(pad "1" smd custom
			(at 0 -0.4445)
			(size 0.1397 0.1397)
			(layers "F.Cu" "F.Mask" "F.Paste")
			(net "VOL_SEN2_SDA")
			(options
				(clearance outline)
				(anchor circle)
			)
			(primitives
				(gr_poly
					(pts
						(arc
							(start -0.1778 -0.2794)
							(mid -0.249642 -0.249642)
							(end -0.2794 -0.1778)
						)
						(arc
							(start -0.2794 0.1778)
							(mid -0.249642 0.249642)
							(end -0.1778 0.2794)
						)
						(arc
							(start 0.1778 0.2794)
							(mid 0.249642 0.249642)
							(end 0.2794 0.1778)
						)
						(arc
							(start 0.2794 -0.1778)
							(mid 0.249642 -0.249642)
							(end 0.1778 -0.2794)
						)
					)
					(width 0)
					(fill yes)
				)
			)
		)
		(pad "2" smd custom
			(at 0 0.4445)
			(size 0.1397 0.1397)
			(layers "F.Cu" "F.Mask" "F.Paste")
			(net "I2C_SCC_SDA2")
			(options
				(clearance outline)
				(anchor circle)
			)
			(primitives
				(gr_poly
					(pts
						(arc
							(start -0.1778 -0.2794)
							(mid -0.249642 -0.249642)
							(end -0.2794 -0.1778)
						)
						(arc
							(start -0.2794 0.1778)
							(mid -0.249642 0.249642)
							(end -0.1778 0.2794)
						)
						(arc
							(start 0.1778 0.2794)
							(mid 0.249642 0.249642)
							(end 0.2794 0.1778)
						)
						(arc
							(start 0.2794 -0.1778)
							(mid 0.249642 -0.249642)
							(end 0.1778 -0.2794)
						)
					)
					(width 0)
					(fill yes)
				)
			)
		)
	)
	(footprint ""
		(layer "F.Cu")
		(at 176.36871 -23.547832 90)
		(property "Reference" "VIA6"
			(at 0 0 90)
			(layer "F.SilkS")
			(hide yes)
			(effects
				(font
					(size 1.27 1.27)
				)
			)
		)
		(property "Value" "85OHM-8L-1D6MM-L16L18-GP"
			(at 4.064 0.6096 90)
			(unlocked yes)
			(layer "F.Fab")
			(hide yes)
			(effects
				(font
					(size 1.016 1.016)
					(thickness 0.1524)
				)
			)
		)
		(property "Device Type" "VIA-PCIE-4P-368076"
			(at 4.064 -0.9144 90)
			(unlocked yes)
			(layer "F.Fab")
			(hide yes)
			(effects
				(font
					(size 1.016 1.016)
					(thickness 0.1524)
				)
			)
		)
		(duplicate_pad_numbers_are_jumpers no)
		(fp_rect
			(start -1.8415 0.381)
			(end 1.8415 -0.381)
			(stroke
				(width 0)
				(type default)
			)
			(fill no)
			(layer "F.CrtYd")
		)
		(fp_rect
			(start -1.8415 0.381)
			(end 1.8415 -0.381)
			(stroke
				(width 0)
				(type default)
			)
			(fill no)
			(layer "F.Fab")
		)
		(pad "1" thru_hole circle
			(at -1.4605 0 90)
			(size 0.508 0.508)
			(drill 0.254)
			(layers "*.Cu" "*.Mask")
			(remove_unused_layers no)
			(net "GND")
			(clearance 0.127)
			(thermal_gap 0.127)
		)
		(pad "2" thru_hole circle
			(at -0.4445 0 90)
			(size 0.508 0.508)
			(drill 0.254)
			(layers "*.Cu" "*.Mask")
			(remove_unused_layers no)
			(net "PCIE_COMP_TO_SCC_5_DP")
			(clearance 0.127)
			(thermal_gap 0.127)
		)
		(pad "3" thru_hole circle
			(at 0.4445 0 90)
			(size 0.508 0.508)
			(drill 0.254)
			(layers "*.Cu" "*.Mask")
			(remove_unused_layers no)
			(net "PCIE_COMP_TO_SCC_5_DN")
			(clearance 0.127)
			(thermal_gap 0.127)
		)
		(pad "4" thru_hole circle
			(at 1.4605 0 90)
			(size 0.508 0.508)
			(drill 0.254)
			(layers "*.Cu" "*.Mask")
			(remove_unused_layers no)
			(net "GND")
			(clearance 0.127)
			(thermal_gap 0.127)
		)
	)
	(footprint ""
		(layer "F.Cu")
		(at 43.6372 -29.083 90)
		(property "Reference" "R398"
			(at 0 0 90)
			(layer "F.SilkS")
			(hide yes)
			(effects
				(font
					(size 1.27 1.27)
				)
			)
		)
		(property "Value" "10KR2F-2-GP"
			(at 0.064008 -3.993896 90)
			(unlocked yes)
			(layer "F.Fab")
			(hide yes)
			(effects
				(font
					(size 1.016 1.016)
					(thickness 0.1524)
				)
			)
		)
		(property "Device Type" "R402H16"
			(at 0.064008 -5.517896 90)
			(unlocked yes)
			(layer "F.Fab")
			(hide yes)
			(effects
				(font
					(size 1.016 1.016)
					(thickness 0.1524)
				)
			)
		)
		(duplicate_pad_numbers_are_jumpers no)
		(fp_line
			(start 0.508 -0.9398)
			(end -0.508 -0.9398)
			(stroke
				(width 0.1524)
				(type default)
			)
			(layer "F.SilkS")
		)
		(fp_line
			(start -0.508 -0.9398)
			(end -0.508 0.9398)
			(stroke
				(width 0.1524)
				(type default)
			)
			(layer "F.SilkS")
		)
		(fp_rect
			(start -0.508 0.9398)
			(end 0.508 -0.9398)
			(stroke
				(width 0)
				(type default)
			)
			(fill no)
			(layer "F.CrtYd")
		)
		(fp_rect
			(start -0.508 0.9398)
			(end 0.508 -0.9398)
			(stroke
				(width 0)
				(type default)
			)
			(fill no)
			(layer "F.Fab")
		)
		(pad "1" smd custom
			(at 0 -0.4445 90)
			(size 0.1397 0.1397)
			(layers "F.Cu" "F.Mask" "F.Paste")
			(net "P0V9_VREF")
			(options
				(clearance outline)
				(anchor circle)
			)
			(primitives
				(gr_poly
					(pts
						(arc
							(start -0.1778 -0.2794)
							(mid -0.249642 -0.249642)
							(end -0.2794 -0.1778)
						)
						(arc
							(start -0.2794 0.1778)
							(mid -0.249642 0.249642)
							(end -0.1778 0.2794)
						)
						(arc
							(start 0.1778 0.2794)
							(mid 0.249642 0.249642)
							(end 0.2794 0.1778)
						)
						(arc
							(start 0.2794 -0.1778)
							(mid 0.249642 -0.249642)
							(end 0.1778 -0.2794)
						)
					)
					(width 0)
					(fill yes)
				)
			)
		)
		(pad "2" smd custom
			(at 0 0.4445 90)
			(size 0.1397 0.1397)
			(layers "F.Cu" "F.Mask" "F.Paste")
			(net "P0V9_REFIN")
			(options
				(clearance outline)
				(anchor circle)
			)
			(primitives
				(gr_poly
					(pts
						(arc
							(start -0.1778 -0.2794)
							(mid -0.249642 -0.249642)
							(end -0.2794 -0.1778)
						)
						(arc
							(start -0.2794 0.1778)
							(mid -0.249642 0.249642)
							(end -0.1778 0.2794)
						)
						(arc
							(start 0.1778 0.2794)
							(mid 0.249642 0.249642)
							(end 0.2794 0.1778)
						)
						(arc
							(start 0.2794 -0.1778)
							(mid 0.249642 -0.249642)
							(end 0.1778 -0.2794)
						)
					)
					(width 0)
					(fill yes)
				)
			)
		)
	)
	(footprint ""
		(layer "F.Cu")
		(at 134.339076 -88.72601)
		(property "Reference" "R68"
			(at 0 0 0)
			(layer "F.SilkS")
			(hide yes)
			(effects
				(font
					(size 1.27 1.27)
				)
			)
		)
		(property "Value" "1KR2F-3-GP"
			(at 0.064008 -3.993896 0)
			(unlocked yes)
			(layer "F.Fab")
			(hide yes)
			(effects
				(font
					(size 1.016 1.016)
					(thickness 0.1524)
				)
			)
		)
		(property "Device Type" "R402H16"
			(at 0.064008 -5.517896 0)
			(unlocked yes)
			(layer "F.Fab")
			(hide yes)
			(effects
				(font
					(size 1.016 1.016)
					(thickness 0.1524)
				)
			)
		)
		(duplicate_pad_numbers_are_jumpers no)
		(fp_line
			(start -0.508 -0.9398)
			(end -0.508 0.9398)
			(stroke
				(width 0.1524)
				(type default)
			)
			(layer "F.SilkS")
		)
		(fp_line
			(start 0.508 -0.9398)
			(end -0.508 -0.9398)
			(stroke
				(width 0.1524)
				(type default)
			)
			(layer "F.SilkS")
		)
		(fp_rect
			(start -0.508 0.9398)
			(end 0.508 -0.9398)
			(stroke
				(width 0)
				(type default)
			)
			(fill no)
			(layer "F.CrtYd")
		)
		(fp_rect
			(start -0.508 0.9398)
			(end 0.508 -0.9398)
			(stroke
				(width 0)
				(type default)
			)
			(fill no)
			(layer "F.Fab")
		)
		(pad "1" smd custom
			(at 0 -0.4445)
			(size 0.1397 0.1397)
			(layers "F.Cu" "F.Mask" "F.Paste")
			(net "P1V8_E")
			(options
				(clearance outline)
				(anchor circle)
			)
			(primitives
				(gr_poly
					(pts
						(arc
							(start -0.1778 -0.2794)
							(mid -0.249642 -0.249642)
							(end -0.2794 -0.1778)
						)
						(arc
							(start -0.2794 0.1778)
							(mid -0.249642 0.249642)
							(end -0.1778 0.2794)
						)
						(arc
							(start 0.1778 0.2794)
							(mid 0.249642 0.249642)
							(end 0.2794 0.1778)
						)
						(arc
							(start 0.2794 -0.1778)
							(mid 0.249642 -0.249642)
							(end 0.1778 -0.2794)
						)
					)
					(width 0)
					(fill yes)
				)
			)
		)
		(pad "2" smd custom
			(at 0 0.4445)
			(size 0.1397 0.1397)
			(layers "F.Cu" "F.Mask" "F.Paste")
			(net "EXP_I2C_SCL10")
			(options
				(clearance outline)
				(anchor circle)
			)
			(primitives
				(gr_poly
					(pts
						(arc
							(start -0.1778 -0.2794)
							(mid -0.249642 -0.249642)
							(end -0.2794 -0.1778)
						)
						(arc
							(start -0.2794 0.1778)
							(mid -0.249642 0.249642)
							(end -0.1778 0.2794)
						)
						(arc
							(start 0.1778 0.2794)
							(mid 0.249642 0.249642)
							(end 0.2794 0.1778)
						)
						(arc
							(start 0.2794 -0.1778)
							(mid 0.249642 -0.249642)
							(end 0.1778 -0.2794)
						)
					)
					(width 0)
					(fill yes)
				)
			)
		)
	)
	(footprint ""
		(layer "F.Cu")
		(at 175.7934 -76.7334 90)
		(property "Reference" "C385"
			(at 0 0 90)
			(layer "F.SilkS")
			(hide yes)
			(effects
				(font
					(size 1.27 1.27)
				)
			)
		)
		(property "Value" "SC1U16V2KX-7-GP"
			(at 1.7526 -1.6002 90)
			(unlocked yes)
			(layer "F.Fab")
			(hide yes)
			(effects
				(font
					(size 1.016 1.016)
					(thickness 0.1524)
				)
			)
		)
		(property "Device Type" "C402-TO0D2H24"
			(at 1.7526 -3.1242 90)
			(unlocked yes)
			(layer "F.Fab")
			(hide yes)
			(effects
				(font
					(size 1.016 1.016)
					(thickness 0.1524)
				)
			)
		)
		(duplicate_pad_numbers_are_jumpers no)
		(fp_rect
			(start -0.4826 0.889)
			(end 0.4826 -0.889)
			(stroke
				(width 0)
				(type default)
			)
			(fill no)
			(layer "F.CrtYd")
		)
		(fp_rect
			(start -0.4826 0.889)
			(end 0.4826 -0.889)
			(stroke
				(width 0)
				(type default)
			)
			(fill no)
			(layer "F.Fab")
		)
		(pad "1" smd custom
			(at 0 -0.4572 90)
			(size 0.1524 0.1524)
			(layers "F.Cu" "F.Mask" "F.Paste")
			(net "PCE_AVDD")
			(options
				(clearance outline)
				(anchor circle)
			)
			(primitives
				(gr_poly
					(pts
						(arc
							(start -0.254 0.3048)
							(mid -0.325842 0.275042)
							(end -0.3556 0.2032)
						)
						(arc
							(start -0.3556 -0.2032)
							(mid -0.325842 -0.275042)
							(end -0.254 -0.3048)
						)
						(arc
							(start 0.254 -0.3048)
							(mid 0.325842 -0.275042)
							(end 0.3556 -0.2032)
						)
						(arc
							(start 0.3556 0.2032)
							(mid 0.325842 0.275042)
							(end 0.254 0.3048)
						)
					)
					(width 0)
					(fill yes)
				)
			)
		)
		(pad "2" smd custom
			(at 0 0.4572 90)
			(size 0.1524 0.1524)
			(layers "F.Cu" "F.Mask" "F.Paste")
			(net "GND")
			(options
				(clearance outline)
				(anchor circle)
			)
			(primitives
				(gr_poly
					(pts
						(arc
							(start -0.254 0.3048)
							(mid -0.325842 0.275042)
							(end -0.3556 0.2032)
						)
						(arc
							(start -0.3556 -0.2032)
							(mid -0.325842 -0.275042)
							(end -0.254 -0.3048)
						)
						(arc
							(start 0.254 -0.3048)
							(mid 0.325842 -0.275042)
							(end 0.3556 -0.2032)
						)
						(arc
							(start 0.3556 0.2032)
							(mid 0.325842 0.275042)
							(end 0.254 0.3048)
						)
					)
					(width 0)
					(fill yes)
				)
			)
		)
	)
	(footprint ""
		(layer "F.Cu")
		(at 21.7932 -50.6476 90)
		(property "Reference" "C652"
			(at 0 0 90)
			(layer "F.SilkS")
			(hide yes)
			(effects
				(font
					(size 1.27 1.27)
				)
			)
		)
		(property "Value" "SCD1U50V3KX-GP"
			(at 0 -2.8194 90)
			(unlocked yes)
			(layer "F.Fab")
			(hide yes)
			(effects
				(font
					(size 1.016 1.016)
					(thickness 0.1524)
				)
			)
		)
		(property "Device Type" "C603H36"
			(at 0 -4.3434 90)
			(unlocked yes)
			(layer "F.Fab")
			(hide yes)
			(effects
				(font
					(size 1.016 1.016)
					(thickness 0.1524)
				)
			)
		)
		(duplicate_pad_numbers_are_jumpers no)
		(fp_line
			(start 0.508 0)
			(end -0.508 0)
			(stroke
				(width 0.2032)
				(type default)
			)
			(layer "F.SilkS")
		)
		(fp_rect
			(start -0.5842 1.3335)
			(end 0.5842 -1.3335)
			(stroke
				(width 0)
				(type default)
			)
			(fill no)
			(layer "F.CrtYd")
		)
		(fp_rect
			(start -0.5842 1.3335)
			(end 0.5842 -1.3335)
			(stroke
				(width 0)
				(type default)
			)
			(fill no)
			(layer "F.Fab")
		)
		(pad "1" smd custom
			(at 0 -0.762 90)
			(size 0.2159 0.2159)
			(layers "F.Cu" "F.Mask" "F.Paste")
			(net "MB0_PSET_R")
			(options
				(clearance outline)
				(anchor circle)
			)
			(primitives
				(gr_poly
					(pts
						(arc
							(start -0.3302 -0.4318)
							(mid -0.402042 -0.402042)
							(end -0.4318 -0.3302)
						)
						(arc
							(start -0.4318 0.3302)
							(mid -0.402042 0.402042)
							(end -0.3302 0.4318)
						)
						(arc
							(start 0.3302 0.4318)
							(mid 0.402042 0.402042)
							(end 0.4318 0.3302)
						)
						(arc
							(start 0.4318 -0.3302)
							(mid 0.402042 -0.402042)
							(end 0.3302 -0.4318)
						)
					)
					(width 0)
					(fill yes)
				)
			)
		)
		(pad "2" smd custom
			(at 0 0.762 90)
			(size 0.2159 0.2159)
			(layers "F.Cu" "F.Mask" "F.Paste")
			(net "AGND_CURRENT_MON")
			(options
				(clearance outline)
				(anchor circle)
			)
			(primitives
				(gr_poly
					(pts
						(arc
							(start -0.3302 -0.4318)
							(mid -0.402042 -0.402042)
							(end -0.4318 -0.3302)
						)
						(arc
							(start -0.4318 0.3302)
							(mid -0.402042 0.402042)
							(end -0.3302 0.4318)
						)
						(arc
							(start 0.3302 0.4318)
							(mid 0.402042 0.402042)
							(end 0.4318 0.3302)
						)
						(arc
							(start 0.4318 -0.3302)
							(mid 0.402042 -0.402042)
							(end 0.3302 -0.4318)
						)
					)
					(width 0)
					(fill yes)
				)
			)
		)
	)
	(footprint ""
		(layer "F.Cu")
		(at 22.1742 -48.4886 90)
		(property "Reference" "R22"
			(at 0 0 90)
			(layer "F.SilkS")
			(hide yes)
			(effects
				(font
					(size 1.27 1.27)
				)
			)
		)
		(property "Value" "226KR2F-GP"
			(at 0.064008 -3.993896 90)
			(unlocked yes)
			(layer "F.Fab")
			(hide yes)
			(effects
				(font
					(size 1.016 1.016)
					(thickness 0.1524)
				)
			)
		)
		(property "Device Type" "R402H16"
			(at 0.064008 -5.517896 90)
			(unlocked yes)
			(layer "F.Fab")
			(hide yes)
			(effects
				(font
					(size 1.016 1.016)
					(thickness 0.1524)
				)
			)
		)
		(duplicate_pad_numbers_are_jumpers no)
		(fp_line
			(start 0.508 -0.9398)
			(end -0.508 -0.9398)
			(stroke
				(width 0.1524)
				(type default)
			)
			(layer "F.SilkS")
		)
		(fp_line
			(start -0.508 -0.9398)
			(end -0.508 0.9398)
			(stroke
				(width 0.1524)
				(type default)
			)
			(layer "F.SilkS")
		)
		(fp_rect
			(start -0.508 0.9398)
			(end 0.508 -0.9398)
			(stroke
				(width 0)
				(type default)
			)
			(fill no)
			(layer "F.CrtYd")
		)
		(fp_rect
			(start -0.508 0.9398)
			(end 0.508 -0.9398)
			(stroke
				(width 0)
				(type default)
			)
			(fill no)
			(layer "F.Fab")
		)
		(pad "1" smd custom
			(at 0 -0.4445 90)
			(size 0.1397 0.1397)
			(layers "F.Cu" "F.Mask" "F.Paste")
			(net "MB0_PSET_R")
			(options
				(clearance outline)
				(anchor circle)
			)
			(primitives
				(gr_poly
					(pts
						(arc
							(start -0.1778 -0.2794)
							(mid -0.249642 -0.249642)
							(end -0.2794 -0.1778)
						)
						(arc
							(start -0.2794 0.1778)
							(mid -0.249642 0.249642)
							(end -0.1778 0.2794)
						)
						(arc
							(start 0.1778 0.2794)
							(mid 0.249642 0.249642)
							(end 0.2794 0.1778)
						)
						(arc
							(start 0.2794 -0.1778)
							(mid 0.249642 -0.249642)
							(end 0.1778 -0.2794)
						)
					)
					(width 0)
					(fill yes)
				)
			)
		)
		(pad "2" smd custom
			(at 0 0.4445 90)
			(size 0.1397 0.1397)
			(layers "F.Cu" "F.Mask" "F.Paste")
			(net "AGND_CURRENT_MON")
			(options
				(clearance outline)
				(anchor circle)
			)
			(primitives
				(gr_poly
					(pts
						(arc
							(start -0.1778 -0.2794)
							(mid -0.249642 -0.249642)
							(end -0.2794 -0.1778)
						)
						(arc
							(start -0.2794 0.1778)
							(mid -0.249642 0.249642)
							(end -0.1778 0.2794)
						)
						(arc
							(start 0.1778 0.2794)
							(mid 0.249642 0.249642)
							(end 0.2794 0.1778)
						)
						(arc
							(start 0.2794 -0.1778)
							(mid 0.249642 -0.249642)
							(end 0.1778 -0.2794)
						)
					)
					(width 0)
					(fill yes)
				)
			)
		)
	)
	(footprint ""
		(layer "F.Cu")
		(at 146.4056 -32.913828 -78)
		(property "Reference" "VIA17"
			(at 0 0 282)
			(layer "F.SilkS")
			(hide yes)
			(effects
				(font
					(size 1.27 1.27)
				)
			)
		)
		(property "Value" "100OHM-8L-1D6MM-L13-GP"
			(at 3.289333 0.050849 282)
			(unlocked yes)
			(layer "F.Fab")
			(hide yes)
			(effects
				(font
					(size 1.016 1.016)
					(thickness 0.1524)
				)
			)
		)
		(property "Device Type" "VIA-PCIE-4P-409091"
			(at 3.289207 -1.473208 282)
			(unlocked yes)
			(layer "F.Fab")
			(hide yes)
			(effects
				(font
					(size 1.016 1.016)
					(thickness 0.1524)
				)
			)
		)
		(duplicate_pad_numbers_are_jumpers no)
		(fp_poly
			(pts
				(xy -2.044719 -0.457296) (xy 2.04468 -0.457296) (xy 2.044681 0.457104) (xy -2.044719 0.457104)
			)
			(stroke
				(width 0)
				(type default)
			)
			(fill no)
			(layer "F.CrtYd")
		)
		(fp_poly
			(pts
				(xy -2.044719 -0.457296) (xy 2.04468 -0.457296) (xy 2.044681 0.457104) (xy -2.044719 0.457104)
			)
			(stroke
				(width 0)
				(type default)
			)
			(fill no)
			(layer "F.Fab")
		)
		(pad "1" thru_hole circle
			(at -1.5875 0 282)
			(size 0.508 0.508)
			(drill 0.254)
			(layers "*.Cu" "*.Mask")
			(remove_unused_layers no)
			(net "GND")
			(clearance 0.2032)
			(thermal_gap 0.2032)
		)
		(pad "2" thru_hole circle
			(at -0.5715 0.000001 282)
			(size 0.508 0.508)
			(drill 0.254)
			(layers "*.Cu" "*.Mask")
			(remove_unused_layers no)
			(net "PHY_SCC_TO_IOC_C_40_DP")
			(clearance 0.2032)
			(thermal_gap 0.2032)
		)
		(pad "3" thru_hole circle
			(at 0.5715 -0.000001 282)
			(size 0.508 0.508)
			(drill 0.254)
			(layers "*.Cu" "*.Mask")
			(remove_unused_layers no)
			(net "PHY_SCC_TO_IOC_C_40_DN")
			(clearance 0.2032)
			(thermal_gap 0.2032)
		)
		(pad "4" thru_hole circle
			(at 1.5875 0 282)
			(size 0.508 0.508)
			(drill 0.254)
			(layers "*.Cu" "*.Mask")
			(remove_unused_layers no)
			(net "GND")
			(clearance 0.2032)
			(thermal_gap 0.2032)
		)
	)
	(footprint ""
		(layer "F.Cu")
		(at 12.827 -47.0408 180)
		(property "Reference" "R522"
			(at 0 0 180)
			(layer "F.SilkS")
			(hide yes)
			(effects
				(font
					(size 1.27 1.27)
				)
			)
		)
		(property "Value" "10R2F-L-GP"
			(at 0.064008 -3.993896 180)
			(unlocked yes)
			(layer "F.Fab")
			(hide yes)
			(effects
				(font
					(size 1.016 1.016)
					(thickness 0.1524)
				)
			)
		)
		(property "Device Type" "R402H14"
			(at 0.064008 -5.517896 180)
			(unlocked yes)
			(layer "F.Fab")
			(hide yes)
			(effects
				(font
					(size 1.016 1.016)
					(thickness 0.1524)
				)
			)
		)
		(duplicate_pad_numbers_are_jumpers no)
		(fp_line
			(start 0.508 -0.9398)
			(end -0.508 -0.9398)
			(stroke
				(width 0.1524)
				(type default)
			)
			(layer "F.SilkS")
		)
		(fp_line
			(start -0.508 -0.9398)
			(end -0.508 0.9398)
			(stroke
				(width 0.1524)
				(type default)
			)
			(layer "F.SilkS")
		)
		(fp_rect
			(start -0.508 0.9398)
			(end 0.508 -0.9398)
			(stroke
				(width 0)
				(type default)
			)
			(fill no)
			(layer "F.CrtYd")
		)
		(fp_rect
			(start -0.508 0.9398)
			(end 0.508 -0.9398)
			(stroke
				(width 0)
				(type default)
			)
			(fill no)
			(layer "F.Fab")
		)
		(pad "1" smd custom
			(at 0 -0.4445 180)
			(size 0.1397 0.1397)
			(layers "F.Cu" "F.Mask" "F.Paste")
			(net "MB0_CM_SENSE_R1_P")
			(options
				(clearance outline)
				(anchor circle)
			)
			(primitives
				(gr_poly
					(pts
						(arc
							(start -0.1778 -0.2794)
							(mid -0.249642 -0.249642)
							(end -0.2794 -0.1778)
						)
						(arc
							(start -0.2794 0.1778)
							(mid -0.249642 0.249642)
							(end -0.1778 0.2794)
						)
						(arc
							(start 0.1778 0.2794)
							(mid 0.249642 0.249642)
							(end 0.2794 0.1778)
						)
						(arc
							(start 0.2794 -0.1778)
							(mid 0.249642 -0.249642)
							(end 0.1778 -0.2794)
						)
					)
					(width 0)
					(fill yes)
				)
			)
		)
		(pad "2" smd custom
			(at 0 0.4445 180)
			(size 0.1397 0.1397)
			(layers "F.Cu" "F.Mask" "F.Paste")
			(net "MB0_HS_SENSE_P")
			(options
				(clearance outline)
				(anchor circle)
			)
			(primitives
				(gr_poly
					(pts
						(arc
							(start -0.1778 -0.2794)
							(mid -0.249642 -0.249642)
							(end -0.2794 -0.1778)
						)
						(arc
							(start -0.2794 0.1778)
							(mid -0.249642 0.249642)
							(end -0.1778 0.2794)
						)
						(arc
							(start 0.1778 0.2794)
							(mid 0.249642 0.249642)
							(end 0.2794 0.1778)
						)
						(arc
							(start 0.2794 -0.1778)
							(mid 0.249642 -0.249642)
							(end 0.1778 -0.2794)
						)
					)
					(width 0)
					(fill yes)
				)
			)
		)
	)
	(footprint ""
		(layer "F.Cu")
		(at 83.954874 -104.358694)
		(property "Reference" "R552"
			(at 0 0 0)
			(layer "F.SilkS")
			(hide yes)
			(effects
				(font
					(size 1.27 1.27)
				)
			)
		)
		(property "Value" "0R2J-2-GP"
			(at 0.064008 -3.993896 0)
			(unlocked yes)
			(layer "F.Fab")
			(hide yes)
			(effects
				(font
					(size 1.016 1.016)
					(thickness 0.1524)
				)
			)
		)
		(property "Device Type" "R402H16"
			(at 0.064008 -5.517896 0)
			(unlocked yes)
			(layer "F.Fab")
			(hide yes)
			(effects
				(font
					(size 1.016 1.016)
					(thickness 0.1524)
				)
			)
		)
		(duplicate_pad_numbers_are_jumpers no)
		(fp_line
			(start -0.508 -0.9398)
			(end -0.508 0.9398)
			(stroke
				(width 0.1524)
				(type default)
			)
			(layer "F.SilkS")
		)
		(fp_line
			(start 0.508 -0.9398)
			(end -0.508 -0.9398)
			(stroke
				(width 0.1524)
				(type default)
			)
			(layer "F.SilkS")
		)
		(fp_rect
			(start -0.508 0.9398)
			(end 0.508 -0.9398)
			(stroke
				(width 0)
				(type default)
			)
			(fill no)
			(layer "F.CrtYd")
		)
		(fp_rect
			(start -0.508 0.9398)
			(end 0.508 -0.9398)
			(stroke
				(width 0)
				(type default)
			)
			(fill no)
			(layer "F.Fab")
		)
		(pad "1" smd custom
			(at 0 -0.4445)
			(size 0.1397 0.1397)
			(layers "F.Cu" "F.Mask" "F.Paste")
			(net "SCC_FULL_PWR_EN_U48")
			(options
				(clearance outline)
				(anchor circle)
			)
			(primitives
				(gr_poly
					(pts
						(arc
							(start -0.1778 -0.2794)
							(mid -0.249642 -0.249642)
							(end -0.2794 -0.1778)
						)
						(arc
							(start -0.2794 0.1778)
							(mid -0.249642 0.249642)
							(end -0.1778 0.2794)
						)
						(arc
							(start 0.1778 0.2794)
							(mid 0.249642 0.249642)
							(end 0.2794 0.1778)
						)
						(arc
							(start 0.2794 -0.1778)
							(mid 0.249642 -0.249642)
							(end 0.1778 -0.2794)
						)
					)
					(width 0)
					(fill yes)
				)
			)
		)
		(pad "2" smd custom
			(at 0 0.4445)
			(size 0.1397 0.1397)
			(layers "F.Cu" "F.Mask" "F.Paste")
			(net "SCC_FULL_PWR_EN")
			(options
				(clearance outline)
				(anchor circle)
			)
			(primitives
				(gr_poly
					(pts
						(arc
							(start -0.1778 -0.2794)
							(mid -0.249642 -0.249642)
							(end -0.2794 -0.1778)
						)
						(arc
							(start -0.2794 0.1778)
							(mid -0.249642 0.249642)
							(end -0.1778 0.2794)
						)
						(arc
							(start 0.1778 0.2794)
							(mid 0.249642 0.249642)
							(end 0.2794 0.1778)
						)
						(arc
							(start 0.2794 -0.1778)
							(mid 0.249642 -0.249642)
							(end 0.1778 -0.2794)
						)
					)
					(width 0)
					(fill yes)
				)
			)
		)
	)
	(footprint ""
		(layer "F.Cu")
		(at 70.8406 -83.4136 -90)
		(property "Reference" "C599"
			(at 0 0 270)
			(layer "F.SilkS")
			(hide yes)
			(effects
				(font
					(size 1.27 1.27)
				)
			)
		)
		(property "Value" "SCD1U16V2KX-3GP"
			(at 1.1811 -2.7051 270)
			(unlocked yes)
			(layer "F.Fab")
			(hide yes)
			(effects
				(font
					(size 1.016 1.016)
					(thickness 0.1524)
				)
			)
		)
		(property "Device Type" "C402H22"
			(at 1.1811 -4.2291 270)
			(unlocked yes)
			(layer "F.Fab")
			(hide yes)
			(effects
				(font
					(size 1.016 1.016)
					(thickness 0.1524)
				)
			)
		)
		(duplicate_pad_numbers_are_jumpers no)
		(fp_rect
			(start -0.4318 0.9525)
			(end 0.4318 -0.9525)
			(stroke
				(width 0)
				(type default)
			)
			(fill no)
			(layer "F.CrtYd")
		)
		(fp_rect
			(start -0.4318 0.9525)
			(end 0.4318 -0.9525)
			(stroke
				(width 0)
				(type default)
			)
			(fill no)
			(layer "F.Fab")
		)
		(pad "1" smd custom
			(at 0 -0.4445 270)
			(size 0.1524 0.1524)
			(layers "F.Cu" "F.Mask" "F.Paste")
			(net "P1V8_E")
			(options
				(clearance outline)
				(anchor circle)
			)
			(primitives
				(gr_poly
					(pts
						(arc
							(start 0.3048 -0.2032)
							(mid 0.275042 -0.275042)
							(end 0.2032 -0.3048)
						)
						(arc
							(start -0.2032 -0.3048)
							(mid -0.275042 -0.275042)
							(end -0.3048 -0.2032)
						)
						(arc
							(start -0.3048 0.2032)
							(mid -0.275042 0.275042)
							(end -0.2032 0.3048)
						)
						(arc
							(start 0.2032 0.3048)
							(mid 0.275042 0.275042)
							(end 0.3048 0.2032)
						)
					)
					(width 0)
					(fill yes)
				)
			)
		)
		(pad "2" smd custom
			(at 0 0.4445 270)
			(size 0.1524 0.1524)
			(layers "F.Cu" "F.Mask" "F.Paste")
			(net "GND")
			(options
				(clearance outline)
				(anchor circle)
			)
			(primitives
				(gr_poly
					(pts
						(arc
							(start 0.3048 -0.2032)
							(mid 0.275042 -0.275042)
							(end 0.2032 -0.3048)
						)
						(arc
							(start -0.2032 -0.3048)
							(mid -0.275042 -0.275042)
							(end -0.3048 -0.2032)
						)
						(arc
							(start -0.3048 0.2032)
							(mid -0.275042 0.275042)
							(end -0.2032 0.3048)
						)
						(arc
							(start 0.2032 0.3048)
							(mid 0.275042 0.275042)
							(end 0.3048 0.2032)
						)
					)
					(width 0)
					(fill yes)
				)
			)
		)
	)
	(footprint ""
		(layer "F.Cu")
		(at 150.79726 -109.33176 90)
		(property "Reference" "R387"
			(at 0 0 90)
			(layer "F.SilkS")
			(hide yes)
			(effects
				(font
					(size 1.27 1.27)
				)
			)
		)
		(property "Value" "0R2J-2-GP"
			(at 0.064008 -3.993896 90)
			(unlocked yes)
			(layer "F.Fab")
			(hide yes)
			(effects
				(font
					(size 1.016 1.016)
					(thickness 0.1524)
				)
			)
		)
		(property "Device Type" "R402H16"
			(at 0.064008 -5.517896 90)
			(unlocked yes)
			(layer "F.Fab")
			(hide yes)
			(effects
				(font
					(size 1.016 1.016)
					(thickness 0.1524)
				)
			)
		)
		(duplicate_pad_numbers_are_jumpers no)
		(fp_line
			(start 0.508 -0.9398)
			(end -0.508 -0.9398)
			(stroke
				(width 0.1524)
				(type default)
			)
			(layer "F.SilkS")
		)
		(fp_line
			(start -0.508 -0.9398)
			(end -0.508 0.9398)
			(stroke
				(width 0.1524)
				(type default)
			)
			(layer "F.SilkS")
		)
		(fp_rect
			(start -0.508 0.9398)
			(end 0.508 -0.9398)
			(stroke
				(width 0)
				(type default)
			)
			(fill no)
			(layer "F.CrtYd")
		)
		(fp_rect
			(start -0.508 0.9398)
			(end 0.508 -0.9398)
			(stroke
				(width 0)
				(type default)
			)
			(fill no)
			(layer "F.Fab")
		)
		(pad "1" smd custom
			(at 0 -0.4445 90)
			(size 0.1397 0.1397)
			(layers "F.Cu" "F.Mask" "F.Paste")
			(net "P5V")
			(options
				(clearance outline)
				(anchor circle)
			)
			(primitives
				(gr_poly
					(pts
						(arc
							(start -0.1778 -0.2794)
							(mid -0.249642 -0.249642)
							(end -0.2794 -0.1778)
						)
						(arc
							(start -0.2794 0.1778)
							(mid -0.249642 0.249642)
							(end -0.1778 0.2794)
						)
						(arc
							(start 0.1778 0.2794)
							(mid 0.249642 0.249642)
							(end 0.2794 0.1778)
						)
						(arc
							(start 0.2794 -0.1778)
							(mid 0.249642 -0.249642)
							(end 0.1778 -0.2794)
						)
					)
					(width 0)
					(fill yes)
				)
			)
		)
		(pad "2" smd custom
			(at 0 0.4445 90)
			(size 0.1397 0.1397)
			(layers "F.Cu" "F.Mask" "F.Paste")
			(net "SDB_CONN_PWR_2")
			(options
				(clearance outline)
				(anchor circle)
			)
			(primitives
				(gr_poly
					(pts
						(arc
							(start -0.1778 -0.2794)
							(mid -0.249642 -0.249642)
							(end -0.2794 -0.1778)
						)
						(arc
							(start -0.2794 0.1778)
							(mid -0.249642 0.249642)
							(end -0.1778 0.2794)
						)
						(arc
							(start 0.1778 0.2794)
							(mid 0.249642 0.249642)
							(end 0.2794 0.1778)
						)
						(arc
							(start 0.2794 -0.1778)
							(mid 0.249642 -0.249642)
							(end 0.1778 -0.2794)
						)
					)
					(width 0)
					(fill yes)
				)
			)
		)
	)
	(footprint ""
		(layer "F.Cu")
		(at 66.421 -106.7562 90)
		(property "Reference" "R500"
			(at 0 0 90)
			(layer "F.SilkS")
			(hide yes)
			(effects
				(font
					(size 1.27 1.27)
				)
			)
		)
		(property "Value" "10KR2F-2-GP"
			(at 0.064008 -3.993896 90)
			(unlocked yes)
			(layer "F.Fab")
			(hide yes)
			(effects
				(font
					(size 1.016 1.016)
					(thickness 0.1524)
				)
			)
		)
		(property "Device Type" "R402H16"
			(at 0.064008 -5.517896 90)
			(unlocked yes)
			(layer "F.Fab")
			(hide yes)
			(effects
				(font
					(size 1.016 1.016)
					(thickness 0.1524)
				)
			)
		)
		(duplicate_pad_numbers_are_jumpers no)
		(fp_line
			(start 0.508 -0.9398)
			(end -0.508 -0.9398)
			(stroke
				(width 0.1524)
				(type default)
			)
			(layer "F.SilkS")
		)
		(fp_line
			(start -0.508 -0.9398)
			(end -0.508 0.9398)
			(stroke
				(width 0.1524)
				(type default)
			)
			(layer "F.SilkS")
		)
		(fp_rect
			(start -0.508 0.9398)
			(end 0.508 -0.9398)
			(stroke
				(width 0)
				(type default)
			)
			(fill no)
			(layer "F.CrtYd")
		)
		(fp_rect
			(start -0.508 0.9398)
			(end 0.508 -0.9398)
			(stroke
				(width 0)
				(type default)
			)
			(fill no)
			(layer "F.Fab")
		)
		(pad "1" smd custom
			(at 0 -0.4445 90)
			(size 0.1397 0.1397)
			(layers "F.Cu" "F.Mask" "F.Paste")
			(net "SCC_STBY_PGOOD_BUF")
			(options
				(clearance outline)
				(anchor circle)
			)
			(primitives
				(gr_poly
					(pts
						(arc
							(start -0.1778 -0.2794)
							(mid -0.249642 -0.249642)
							(end -0.2794 -0.1778)
						)
						(arc
							(start -0.2794 0.1778)
							(mid -0.249642 0.249642)
							(end -0.1778 0.2794)
						)
						(arc
							(start 0.1778 0.2794)
							(mid 0.249642 0.249642)
							(end 0.2794 0.1778)
						)
						(arc
							(start 0.2794 -0.1778)
							(mid 0.249642 -0.249642)
							(end 0.1778 -0.2794)
						)
					)
					(width 0)
					(fill yes)
				)
			)
		)
		(pad "2" smd custom
			(at 0 0.4445 90)
			(size 0.1397 0.1397)
			(layers "F.Cu" "F.Mask" "F.Paste")
			(net "P3V3_VREG")
			(options
				(clearance outline)
				(anchor circle)
			)
			(primitives
				(gr_poly
					(pts
						(arc
							(start -0.1778 -0.2794)
							(mid -0.249642 -0.249642)
							(end -0.2794 -0.1778)
						)
						(arc
							(start -0.2794 0.1778)
							(mid -0.249642 0.249642)
							(end -0.1778 0.2794)
						)
						(arc
							(start 0.1778 0.2794)
							(mid 0.249642 0.249642)
							(end 0.2794 0.1778)
						)
						(arc
							(start 0.2794 -0.1778)
							(mid 0.249642 -0.249642)
							(end 0.1778 -0.2794)
						)
					)
					(width 0)
					(fill yes)
				)
			)
		)
	)
	(footprint ""
		(layer "F.Cu")
		(at 8.6614 -93.6244)
		(property "Reference" "R414"
			(at 0 0 0)
			(layer "F.SilkS")
			(hide yes)
			(effects
				(font
					(size 1.27 1.27)
				)
			)
		)
		(property "Value" "1KR2F-3-GP"
			(at 0.064008 -3.993896 0)
			(unlocked yes)
			(layer "F.Fab")
			(hide yes)
			(effects
				(font
					(size 1.016 1.016)
					(thickness 0.1524)
				)
			)
		)
		(property "Device Type" "R402H16"
			(at 0.064008 -5.517896 0)
			(unlocked yes)
			(layer "F.Fab")
			(hide yes)
			(effects
				(font
					(size 1.016 1.016)
					(thickness 0.1524)
				)
			)
		)
		(duplicate_pad_numbers_are_jumpers no)
		(fp_line
			(start -0.508 -0.9398)
			(end -0.508 0.9398)
			(stroke
				(width 0.1524)
				(type default)
			)
			(layer "F.SilkS")
		)
		(fp_line
			(start 0.508 -0.9398)
			(end -0.508 -0.9398)
			(stroke
				(width 0.1524)
				(type default)
			)
			(layer "F.SilkS")
		)
		(fp_rect
			(start -0.508 0.9398)
			(end 0.508 -0.9398)
			(stroke
				(width 0)
				(type default)
			)
			(fill no)
			(layer "F.CrtYd")
		)
		(fp_rect
			(start -0.508 0.9398)
			(end 0.508 -0.9398)
			(stroke
				(width 0)
				(type default)
			)
			(fill no)
			(layer "F.Fab")
		)
		(pad "1" smd custom
			(at 0 -0.4445)
			(size 0.1397 0.1397)
			(layers "F.Cu" "F.Mask" "F.Paste")
			(net "P3V3")
			(options
				(clearance outline)
				(anchor circle)
			)
			(primitives
				(gr_poly
					(pts
						(arc
							(start -0.1778 -0.2794)
							(mid -0.249642 -0.249642)
							(end -0.2794 -0.1778)
						)
						(arc
							(start -0.2794 0.1778)
							(mid -0.249642 0.249642)
							(end -0.1778 0.2794)
						)
						(arc
							(start 0.1778 0.2794)
							(mid 0.249642 0.249642)
							(end 0.2794 0.1778)
						)
						(arc
							(start 0.2794 -0.1778)
							(mid 0.249642 -0.249642)
							(end 0.1778 -0.2794)
						)
					)
					(width 0)
					(fill yes)
				)
			)
		)
		(pad "2" smd custom
			(at 0 0.4445)
			(size 0.1397 0.1397)
			(layers "F.Cu" "F.Mask" "F.Paste")
			(net "I2C_SCC_SCL2")
			(options
				(clearance outline)
				(anchor circle)
			)
			(primitives
				(gr_poly
					(pts
						(arc
							(start -0.1778 -0.2794)
							(mid -0.249642 -0.249642)
							(end -0.2794 -0.1778)
						)
						(arc
							(start -0.2794 0.1778)
							(mid -0.249642 0.249642)
							(end -0.1778 0.2794)
						)
						(arc
							(start 0.1778 0.2794)
							(mid 0.249642 0.249642)
							(end 0.2794 0.1778)
						)
						(arc
							(start 0.2794 -0.1778)
							(mid 0.249642 -0.249642)
							(end 0.1778 -0.2794)
						)
					)
					(width 0)
					(fill yes)
				)
			)
		)
	)
	(footprint ""
		(layer "F.Cu")
		(at 51.308 -77.9272 90)
		(property "Reference" "R472"
			(at 0 0 90)
			(layer "F.SilkS")
			(hide yes)
			(effects
				(font
					(size 1.27 1.27)
				)
			)
		)
		(property "Value" "1KR2F-3-GP"
			(at 0.064008 -3.993896 90)
			(unlocked yes)
			(layer "F.Fab")
			(hide yes)
			(effects
				(font
					(size 1.016 1.016)
					(thickness 0.1524)
				)
			)
		)
		(property "Device Type" "R402H16"
			(at 0.064008 -5.517896 90)
			(unlocked yes)
			(layer "F.Fab")
			(hide yes)
			(effects
				(font
					(size 1.016 1.016)
					(thickness 0.1524)
				)
			)
		)
		(duplicate_pad_numbers_are_jumpers no)
		(fp_line
			(start 0.508 -0.9398)
			(end -0.508 -0.9398)
			(stroke
				(width 0.1524)
				(type default)
			)
			(layer "F.SilkS")
		)
		(fp_line
			(start -0.508 -0.9398)
			(end -0.508 0.9398)
			(stroke
				(width 0.1524)
				(type default)
			)
			(layer "F.SilkS")
		)
		(fp_rect
			(start -0.508 0.9398)
			(end 0.508 -0.9398)
			(stroke
				(width 0)
				(type default)
			)
			(fill no)
			(layer "F.CrtYd")
		)
		(fp_rect
			(start -0.508 0.9398)
			(end 0.508 -0.9398)
			(stroke
				(width 0)
				(type default)
			)
			(fill no)
			(layer "F.Fab")
		)
		(pad "1" smd custom
			(at 0 -0.4445 90)
			(size 0.1397 0.1397)
			(layers "F.Cu" "F.Mask" "F.Paste")
			(net "P3V3")
			(options
				(clearance outline)
				(anchor circle)
			)
			(primitives
				(gr_poly
					(pts
						(arc
							(start -0.1778 -0.2794)
							(mid -0.249642 -0.249642)
							(end -0.2794 -0.1778)
						)
						(arc
							(start -0.2794 0.1778)
							(mid -0.249642 0.249642)
							(end -0.1778 0.2794)
						)
						(arc
							(start 0.1778 0.2794)
							(mid 0.249642 0.249642)
							(end 0.2794 0.1778)
						)
						(arc
							(start 0.2794 -0.1778)
							(mid 0.249642 -0.249642)
							(end 0.1778 -0.2794)
						)
					)
					(width 0)
					(fill yes)
				)
			)
		)
		(pad "2" smd custom
			(at 0 0.4445 90)
			(size 0.1397 0.1397)
			(layers "F.Cu" "F.Mask" "F.Paste")
			(net "I2C_CLIP_SCL7")
			(options
				(clearance outline)
				(anchor circle)
			)
			(primitives
				(gr_poly
					(pts
						(arc
							(start -0.1778 -0.2794)
							(mid -0.249642 -0.249642)
							(end -0.2794 -0.1778)
						)
						(arc
							(start -0.2794 0.1778)
							(mid -0.249642 0.249642)
							(end -0.1778 0.2794)
						)
						(arc
							(start 0.1778 0.2794)
							(mid 0.249642 0.249642)
							(end 0.2794 0.1778)
						)
						(arc
							(start 0.2794 -0.1778)
							(mid 0.249642 -0.249642)
							(end 0.1778 -0.2794)
						)
					)
					(width 0)
					(fill yes)
				)
			)
		)
	)
	(footprint ""
		(layer "F.Cu")
		(at 156.43098 -110.92942)
		(property "Reference" "C697"
			(at 0 0 0)
			(layer "F.SilkS")
			(hide yes)
			(effects
				(font
					(size 1.27 1.27)
				)
			)
		)
		(property "Value" "SCD1U50V3KX-GP"
			(at 0 -2.8194 0)
			(unlocked yes)
			(layer "F.Fab")
			(hide yes)
			(effects
				(font
					(size 1.016 1.016)
					(thickness 0.1524)
				)
			)
		)
		(property "Device Type" "C603H36"
			(at 0 -4.3434 0)
			(unlocked yes)
			(layer "F.Fab")
			(hide yes)
			(effects
				(font
					(size 1.016 1.016)
					(thickness 0.1524)
				)
			)
		)
		(duplicate_pad_numbers_are_jumpers no)
		(fp_line
			(start 0.508 0)
			(end -0.508 0)
			(stroke
				(width 0.2032)
				(type default)
			)
			(layer "F.SilkS")
		)
		(fp_rect
			(start -0.5842 1.3335)
			(end 0.5842 -1.3335)
			(stroke
				(width 0)
				(type default)
			)
			(fill no)
			(layer "F.CrtYd")
		)
		(fp_rect
			(start -0.5842 1.3335)
			(end 0.5842 -1.3335)
			(stroke
				(width 0)
				(type default)
			)
			(fill no)
			(layer "F.Fab")
		)
		(pad "1" smd custom
			(at 0 -0.762)
			(size 0.2159 0.2159)
			(layers "F.Cu" "F.Mask" "F.Paste")
			(net "P12V_STBY_VIN_U11")
			(options
				(clearance outline)
				(anchor circle)
			)
			(primitives
				(gr_poly
					(pts
						(arc
							(start -0.3302 -0.4318)
							(mid -0.402042 -0.402042)
							(end -0.4318 -0.3302)
						)
						(arc
							(start -0.4318 0.3302)
							(mid -0.402042 0.402042)
							(end -0.3302 0.4318)
						)
						(arc
							(start 0.3302 0.4318)
							(mid 0.402042 0.402042)
							(end 0.4318 0.3302)
						)
						(arc
							(start 0.4318 -0.3302)
							(mid 0.402042 -0.402042)
							(end 0.3302 -0.4318)
						)
					)
					(width 0)
					(fill yes)
				)
			)
		)
		(pad "2" smd custom
			(at 0 0.762)
			(size 0.2159 0.2159)
			(layers "F.Cu" "F.Mask" "F.Paste")
			(net "GND")
			(options
				(clearance outline)
				(anchor circle)
			)
			(primitives
				(gr_poly
					(pts
						(arc
							(start -0.3302 -0.4318)
							(mid -0.402042 -0.402042)
							(end -0.4318 -0.3302)
						)
						(arc
							(start -0.4318 0.3302)
							(mid -0.402042 0.402042)
							(end -0.3302 0.4318)
						)
						(arc
							(start 0.3302 0.4318)
							(mid 0.402042 0.402042)
							(end 0.4318 0.3302)
						)
						(arc
							(start 0.4318 -0.3302)
							(mid 0.402042 -0.402042)
							(end 0.3302 -0.4318)
						)
					)
					(width 0)
					(fill yes)
				)
			)
		)
	)
	(footprint ""
		(layer "F.Cu")
		(at 157.8737 -89.7636 -90)
		(property "Reference" "R330"
			(at 0 0 270)
			(layer "F.SilkS")
			(hide yes)
			(effects
				(font
					(size 1.27 1.27)
				)
			)
		)
		(property "Value" "4K7R2F-GP"
			(at 0.064008 -3.993896 270)
			(unlocked yes)
			(layer "F.Fab")
			(hide yes)
			(effects
				(font
					(size 1.016 1.016)
					(thickness 0.1524)
				)
			)
		)
		(property "Device Type" "R402H16"
			(at 0.064008 -5.517896 270)
			(unlocked yes)
			(layer "F.Fab")
			(hide yes)
			(effects
				(font
					(size 1.016 1.016)
					(thickness 0.1524)
				)
			)
		)
		(duplicate_pad_numbers_are_jumpers no)
		(fp_line
			(start -0.508 -0.9398)
			(end -0.508 0.9398)
			(stroke
				(width 0.1524)
				(type default)
			)
			(layer "F.SilkS")
		)
		(fp_line
			(start 0.508 -0.9398)
			(end -0.508 -0.9398)
			(stroke
				(width 0.1524)
				(type default)
			)
			(layer "F.SilkS")
		)
		(fp_rect
			(start -0.508 0.9398)
			(end 0.508 -0.9398)
			(stroke
				(width 0)
				(type default)
			)
			(fill no)
			(layer "F.CrtYd")
		)
		(fp_rect
			(start -0.508 0.9398)
			(end 0.508 -0.9398)
			(stroke
				(width 0)
				(type default)
			)
			(fill no)
			(layer "F.Fab")
		)
		(pad "1" smd custom
			(at 0 -0.4445 270)
			(size 0.1397 0.1397)
			(layers "F.Cu" "F.Mask" "F.Paste")
			(net "P3V3")
			(options
				(clearance outline)
				(anchor circle)
			)
			(primitives
				(gr_poly
					(pts
						(arc
							(start -0.1778 -0.2794)
							(mid -0.249642 -0.249642)
							(end -0.2794 -0.1778)
						)
						(arc
							(start -0.2794 0.1778)
							(mid -0.249642 0.249642)
							(end -0.1778 0.2794)
						)
						(arc
							(start 0.1778 0.2794)
							(mid 0.249642 0.249642)
							(end 0.2794 0.1778)
						)
						(arc
							(start 0.2794 -0.1778)
							(mid 0.249642 -0.249642)
							(end 0.1778 -0.2794)
						)
					)
					(width 0)
					(fill yes)
				)
			)
		)
		(pad "2" smd custom
			(at 0 0.4445 270)
			(size 0.1397 0.1397)
			(layers "F.Cu" "F.Mask" "F.Paste")
			(net "VOL_SEN1_ADDR")
			(options
				(clearance outline)
				(anchor circle)
			)
			(primitives
				(gr_poly
					(pts
						(arc
							(start -0.1778 -0.2794)
							(mid -0.249642 -0.249642)
							(end -0.2794 -0.1778)
						)
						(arc
							(start -0.2794 0.1778)
							(mid -0.249642 0.249642)
							(end -0.1778 0.2794)
						)
						(arc
							(start 0.1778 0.2794)
							(mid 0.249642 0.249642)
							(end 0.2794 0.1778)
						)
						(arc
							(start 0.2794 -0.1778)
							(mid 0.249642 -0.249642)
							(end 0.1778 -0.2794)
						)
					)
					(width 0)
					(fill yes)
				)
			)
		)
	)
	(footprint ""
		(layer "F.Cu")
		(at 10.652252 -59.360816 180)
		(property "Reference" "R12"
			(at 0 0 180)
			(layer "F.SilkS")
			(hide yes)
			(effects
				(font
					(size 1.27 1.27)
				)
			)
		)
		(property "Value" "0R2J-2-GP"
			(at 0.064008 -3.993896 180)
			(unlocked yes)
			(layer "F.Fab")
			(hide yes)
			(effects
				(font
					(size 1.016 1.016)
					(thickness 0.1524)
				)
			)
		)
		(property "Device Type" "R402H16"
			(at 0.064008 -5.517896 180)
			(unlocked yes)
			(layer "F.Fab")
			(hide yes)
			(effects
				(font
					(size 1.016 1.016)
					(thickness 0.1524)
				)
			)
		)
		(duplicate_pad_numbers_are_jumpers no)
		(fp_line
			(start 0.508 -0.9398)
			(end -0.508 -0.9398)
			(stroke
				(width 0.1524)
				(type default)
			)
			(layer "F.SilkS")
		)
		(fp_line
			(start -0.508 -0.9398)
			(end -0.508 0.9398)
			(stroke
				(width 0.1524)
				(type default)
			)
			(layer "F.SilkS")
		)
		(fp_rect
			(start -0.508 0.9398)
			(end 0.508 -0.9398)
			(stroke
				(width 0)
				(type default)
			)
			(fill no)
			(layer "F.CrtYd")
		)
		(fp_rect
			(start -0.508 0.9398)
			(end 0.508 -0.9398)
			(stroke
				(width 0)
				(type default)
			)
			(fill no)
			(layer "F.Fab")
		)
		(pad "1" smd custom
			(at 0 -0.4445 180)
			(size 0.1397 0.1397)
			(layers "F.Cu" "F.Mask" "F.Paste")
			(net "HSW_SCL_2")
			(options
				(clearance outline)
				(anchor circle)
			)
			(primitives
				(gr_poly
					(pts
						(arc
							(start -0.1778 -0.2794)
							(mid -0.249642 -0.249642)
							(end -0.2794 -0.1778)
						)
						(arc
							(start -0.2794 0.1778)
							(mid -0.249642 0.249642)
							(end -0.1778 0.2794)
						)
						(arc
							(start 0.1778 0.2794)
							(mid 0.249642 0.249642)
							(end 0.2794 0.1778)
						)
						(arc
							(start 0.2794 -0.1778)
							(mid 0.249642 -0.249642)
							(end 0.1778 -0.2794)
						)
					)
					(width 0)
					(fill yes)
				)
			)
		)
		(pad "2" smd custom
			(at 0 0.4445 180)
			(size 0.1397 0.1397)
			(layers "F.Cu" "F.Mask" "F.Paste")
			(net "I2C_SCC_SCL2")
			(options
				(clearance outline)
				(anchor circle)
			)
			(primitives
				(gr_poly
					(pts
						(arc
							(start -0.1778 -0.2794)
							(mid -0.249642 -0.249642)
							(end -0.2794 -0.1778)
						)
						(arc
							(start -0.2794 0.1778)
							(mid -0.249642 0.249642)
							(end -0.1778 0.2794)
						)
						(arc
							(start 0.1778 0.2794)
							(mid 0.249642 0.249642)
							(end 0.2794 0.1778)
						)
						(arc
							(start 0.2794 -0.1778)
							(mid 0.249642 -0.249642)
							(end 0.1778 -0.2794)
						)
					)
					(width 0)
					(fill yes)
				)
			)
		)
	)
	(footprint ""
		(layer "F.Cu")
		(at 51.089306 -29.56433 180)
		(property "Reference" "R478"
			(at 0 0 180)
			(layer "F.SilkS")
			(hide yes)
			(effects
				(font
					(size 1.27 1.27)
				)
			)
		)
		(property "Value" "0R2F-1-GP"
			(at 0.064008 -3.993896 180)
			(unlocked yes)
			(layer "F.Fab")
			(hide yes)
			(effects
				(font
					(size 1.016 1.016)
					(thickness 0.1524)
				)
			)
		)
		(property "Device Type" "R402H16"
			(at 0.064008 -5.517896 180)
			(unlocked yes)
			(layer "F.Fab")
			(hide yes)
			(effects
				(font
					(size 1.016 1.016)
					(thickness 0.1524)
				)
			)
		)
		(duplicate_pad_numbers_are_jumpers no)
		(fp_line
			(start 0.508 -0.9398)
			(end -0.508 -0.9398)
			(stroke
				(width 0.1524)
				(type default)
			)
			(layer "F.SilkS")
		)
		(fp_line
			(start -0.508 -0.9398)
			(end -0.508 0.9398)
			(stroke
				(width 0.1524)
				(type default)
			)
			(layer "F.SilkS")
		)
		(fp_rect
			(start -0.508 0.9398)
			(end 0.508 -0.9398)
			(stroke
				(width 0)
				(type default)
			)
			(fill no)
			(layer "F.CrtYd")
		)
		(fp_rect
			(start -0.508 0.9398)
			(end 0.508 -0.9398)
			(stroke
				(width 0)
				(type default)
			)
			(fill no)
			(layer "F.Fab")
		)
		(pad "1" smd custom
			(at 0 -0.4445 180)
			(size 0.1397 0.1397)
			(layers "F.Cu" "F.Mask" "F.Paste")
			(net "P0V9_VFB")
			(options
				(clearance outline)
				(anchor circle)
			)
			(primitives
				(gr_poly
					(pts
						(arc
							(start -0.1778 -0.2794)
							(mid -0.249642 -0.249642)
							(end -0.2794 -0.1778)
						)
						(arc
							(start -0.2794 0.1778)
							(mid -0.249642 0.249642)
							(end -0.1778 0.2794)
						)
						(arc
							(start 0.1778 0.2794)
							(mid 0.249642 0.249642)
							(end 0.2794 0.1778)
						)
						(arc
							(start 0.2794 -0.1778)
							(mid 0.249642 -0.249642)
							(end 0.1778 -0.2794)
						)
					)
					(width 0)
					(fill yes)
				)
			)
		)
		(pad "2" smd custom
			(at 0 0.4445 180)
			(size 0.1397 0.1397)
			(layers "F.Cu" "F.Mask" "F.Paste")
			(net "P0V9")
			(options
				(clearance outline)
				(anchor circle)
			)
			(primitives
				(gr_poly
					(pts
						(arc
							(start -0.1778 -0.2794)
							(mid -0.249642 -0.249642)
							(end -0.2794 -0.1778)
						)
						(arc
							(start -0.2794 0.1778)
							(mid -0.249642 0.249642)
							(end -0.1778 0.2794)
						)
						(arc
							(start 0.1778 0.2794)
							(mid 0.249642 0.249642)
							(end 0.2794 0.1778)
						)
						(arc
							(start 0.2794 -0.1778)
							(mid 0.249642 -0.249642)
							(end 0.1778 -0.2794)
						)
					)
					(width 0)
					(fill yes)
				)
			)
		)
	)
	(footprint ""
		(layer "F.Cu")
		(at 168.159938 -23.568406 90)
		(property "Reference" "VIA2"
			(at 0 0 90)
			(layer "F.SilkS")
			(hide yes)
			(effects
				(font
					(size 1.27 1.27)
				)
			)
		)
		(property "Value" "85OHM-8L-1D6MM-L16L18-GP"
			(at 4.064 0.6096 90)
			(unlocked yes)
			(layer "F.Fab")
			(hide yes)
			(effects
				(font
					(size 1.016 1.016)
					(thickness 0.1524)
				)
			)
		)
		(property "Device Type" "VIA-PCIE-4P-368076"
			(at 4.064 -0.9144 90)
			(unlocked yes)
			(layer "F.Fab")
			(hide yes)
			(effects
				(font
					(size 1.016 1.016)
					(thickness 0.1524)
				)
			)
		)
		(duplicate_pad_numbers_are_jumpers no)
		(fp_rect
			(start -1.8415 0.381)
			(end 1.8415 -0.381)
			(stroke
				(width 0)
				(type default)
			)
			(fill no)
			(layer "F.CrtYd")
		)
		(fp_rect
			(start -1.8415 0.381)
			(end 1.8415 -0.381)
			(stroke
				(width 0)
				(type default)
			)
			(fill no)
			(layer "F.Fab")
		)
		(pad "1" thru_hole circle
			(at -1.4605 0 90)
			(size 0.508 0.508)
			(drill 0.254)
			(layers "*.Cu" "*.Mask")
			(remove_unused_layers no)
			(net "GND")
			(clearance 0.127)
			(thermal_gap 0.127)
		)
		(pad "2" thru_hole circle
			(at -0.4445 0 90)
			(size 0.508 0.508)
			(drill 0.254)
			(layers "*.Cu" "*.Mask")
			(remove_unused_layers no)
			(net "PCIE_COMP_TO_SCC_1_DP")
			(clearance 0.127)
			(thermal_gap 0.127)
		)
		(pad "3" thru_hole circle
			(at 0.4445 0 90)
			(size 0.508 0.508)
			(drill 0.254)
			(layers "*.Cu" "*.Mask")
			(remove_unused_layers no)
			(net "PCIE_COMP_TO_SCC_1_DN")
			(clearance 0.127)
			(thermal_gap 0.127)
		)
		(pad "4" thru_hole circle
			(at 1.4605 0 90)
			(size 0.508 0.508)
			(drill 0.254)
			(layers "*.Cu" "*.Mask")
			(remove_unused_layers no)
			(net "GND")
			(clearance 0.127)
			(thermal_gap 0.127)
		)
	)
	(footprint ""
		(layer "F.Cu")
		(at 16.637 -59.1312 180)
		(property "Reference" "R524"
			(at 0 0 180)
			(layer "F.SilkS")
			(hide yes)
			(effects
				(font
					(size 1.27 1.27)
				)
			)
		)
		(property "Value" "0R2J-2-GP"
			(at 0.064008 -3.993896 180)
			(unlocked yes)
			(layer "F.Fab")
			(hide yes)
			(effects
				(font
					(size 1.016 1.016)
					(thickness 0.1524)
				)
			)
		)
		(property "Device Type" "R402H16"
			(at 0.064008 -5.517896 180)
			(unlocked yes)
			(layer "F.Fab")
			(hide yes)
			(effects
				(font
					(size 1.016 1.016)
					(thickness 0.1524)
				)
			)
		)
		(duplicate_pad_numbers_are_jumpers no)
		(fp_line
			(start 0.508 -0.9398)
			(end -0.508 -0.9398)
			(stroke
				(width 0.1524)
				(type default)
			)
			(layer "F.SilkS")
		)
		(fp_line
			(start -0.508 -0.9398)
			(end -0.508 0.9398)
			(stroke
				(width 0.1524)
				(type default)
			)
			(layer "F.SilkS")
		)
		(fp_rect
			(start -0.508 0.9398)
			(end 0.508 -0.9398)
			(stroke
				(width 0)
				(type default)
			)
			(fill no)
			(layer "F.CrtYd")
		)
		(fp_rect
			(start -0.508 0.9398)
			(end 0.508 -0.9398)
			(stroke
				(width 0)
				(type default)
			)
			(fill no)
			(layer "F.Fab")
		)
		(pad "1" smd custom
			(at 0 -0.4445 180)
			(size 0.1397 0.1397)
			(layers "F.Cu" "F.Mask" "F.Paste")
			(net "MB0_SPISS_PD")
			(options
				(clearance outline)
				(anchor circle)
			)
			(primitives
				(gr_poly
					(pts
						(arc
							(start -0.1778 -0.2794)
							(mid -0.249642 -0.249642)
							(end -0.2794 -0.1778)
						)
						(arc
							(start -0.2794 0.1778)
							(mid -0.249642 0.249642)
							(end -0.1778 0.2794)
						)
						(arc
							(start 0.1778 0.2794)
							(mid 0.249642 0.249642)
							(end 0.2794 0.1778)
						)
						(arc
							(start 0.2794 -0.1778)
							(mid 0.249642 -0.249642)
							(end 0.1778 -0.2794)
						)
					)
					(width 0)
					(fill yes)
				)
			)
		)
		(pad "2" smd custom
			(at 0 0.4445 180)
			(size 0.1397 0.1397)
			(layers "F.Cu" "F.Mask" "F.Paste")
			(net "AGND_CURRENT_MON")
			(options
				(clearance outline)
				(anchor circle)
			)
			(primitives
				(gr_poly
					(pts
						(arc
							(start -0.1778 -0.2794)
							(mid -0.249642 -0.249642)
							(end -0.2794 -0.1778)
						)
						(arc
							(start -0.2794 0.1778)
							(mid -0.249642 0.249642)
							(end -0.1778 0.2794)
						)
						(arc
							(start 0.1778 0.2794)
							(mid 0.249642 0.249642)
							(end 0.2794 0.1778)
						)
						(arc
							(start 0.2794 -0.1778)
							(mid 0.249642 -0.249642)
							(end 0.1778 -0.2794)
						)
					)
					(width 0)
					(fill yes)
				)
			)
		)
	)
	(footprint ""
		(layer "F.Cu")
		(at 73.533 -36.068)
		(property "Reference" "C255"
			(at 0 0 0)
			(layer "F.SilkS")
			(hide yes)
			(effects
				(font
					(size 1.27 1.27)
				)
			)
		)
		(property "Value" "SC100U6D3V6MX-GP"
			(at -0.0762 -5.1308 0)
			(unlocked yes)
			(layer "F.Fab")
			(hide yes)
			(effects
				(font
					(size 1.016 1.016)
					(thickness 0.1524)
				)
			)
		)
		(property "Device Type" "C1206H71"
			(at -0.127 -6.6548 0)
			(unlocked yes)
			(layer "F.Fab")
			(hide yes)
			(effects
				(font
					(size 1.016 1.016)
					(thickness 0.1524)
				)
			)
		)
		(duplicate_pad_numbers_are_jumpers no)
		(fp_line
			(start -1.016 -2.2352)
			(end 1.016 -2.2352)
			(stroke
				(width 0.1524)
				(type default)
			)
			(layer "F.SilkS")
		)
		(fp_line
			(start -1.016 -0.8382)
			(end -1.016 -2.2352)
			(stroke
				(width 0.1524)
				(type default)
			)
			(layer "F.SilkS")
		)
		(fp_line
			(start -1.016 2.2352)
			(end -1.016 0.8382)
			(stroke
				(width 0.1524)
				(type default)
			)
			(layer "F.SilkS")
		)
		(fp_line
			(start 1.016 -2.2352)
			(end 1.016 -0.8382)
			(stroke
				(width 0.1524)
				(type default)
			)
			(layer "F.SilkS")
		)
		(fp_line
			(start 1.016 0.8382)
			(end 1.016 2.2352)
			(stroke
				(width 0.1524)
				(type default)
			)
			(layer "F.SilkS")
		)
		(fp_line
			(start 1.016 2.2352)
			(end -1.016 2.2352)
			(stroke
				(width 0.1524)
				(type default)
			)
			(layer "F.SilkS")
		)
		(fp_rect
			(start -1.0922 2.3114)
			(end 1.0922 -2.3114)
			(stroke
				(width 0)
				(type default)
			)
			(fill no)
			(layer "F.CrtYd")
		)
		(fp_poly
			(pts
				(xy 1.0922 -2.3114) (xy 1.0922 2.3114) (xy -1.0922 2.3114) (xy -1.0922 -2.3114)
			)
			(stroke
				(width 0)
				(type default)
			)
			(fill no)
			(layer "F.Fab")
		)
		(pad "1" smd rect
			(at 0 -1.397)
			(size 1.651 1.27)
			(layers "F.Cu" "F.Mask" "F.Paste")
			(net "GB_VDDA")
		)
		(pad "2" smd rect
			(at 0 1.397)
			(size 1.651 1.27)
			(layers "F.Cu" "F.Mask" "F.Paste")
			(net "GND")
		)
	)
	(footprint ""
		(layer "F.Cu")
		(at 57.5564 -72.6948 180)
		(property "Reference" "R422"
			(at 0 0 180)
			(layer "F.SilkS")
			(hide yes)
			(effects
				(font
					(size 1.27 1.27)
				)
			)
		)
		(property "Value" "1KR2F-3-GP"
			(at 0.064008 -3.993896 180)
			(unlocked yes)
			(layer "F.Fab")
			(hide yes)
			(effects
				(font
					(size 1.016 1.016)
					(thickness 0.1524)
				)
			)
		)
		(property "Device Type" "R402H16"
			(at 0.064008 -5.517896 180)
			(unlocked yes)
			(layer "F.Fab")
			(hide yes)
			(effects
				(font
					(size 1.016 1.016)
					(thickness 0.1524)
				)
			)
		)
		(duplicate_pad_numbers_are_jumpers no)
		(fp_line
			(start 0.508 -0.9398)
			(end -0.508 -0.9398)
			(stroke
				(width 0.1524)
				(type default)
			)
			(layer "F.SilkS")
		)
		(fp_line
			(start -0.508 -0.9398)
			(end -0.508 0.9398)
			(stroke
				(width 0.1524)
				(type default)
			)
			(layer "F.SilkS")
		)
		(fp_rect
			(start -0.508 0.9398)
			(end 0.508 -0.9398)
			(stroke
				(width 0)
				(type default)
			)
			(fill no)
			(layer "F.CrtYd")
		)
		(fp_rect
			(start -0.508 0.9398)
			(end 0.508 -0.9398)
			(stroke
				(width 0)
				(type default)
			)
			(fill no)
			(layer "F.Fab")
		)
		(pad "1" smd custom
			(at 0 -0.4445 180)
			(size 0.1397 0.1397)
			(layers "F.Cu" "F.Mask" "F.Paste")
			(net "P3V3")
			(options
				(clearance outline)
				(anchor circle)
			)
			(primitives
				(gr_poly
					(pts
						(arc
							(start -0.1778 -0.2794)
							(mid -0.249642 -0.249642)
							(end -0.2794 -0.1778)
						)
						(arc
							(start -0.2794 0.1778)
							(mid -0.249642 0.249642)
							(end -0.1778 0.2794)
						)
						(arc
							(start 0.1778 0.2794)
							(mid 0.249642 0.249642)
							(end 0.2794 0.1778)
						)
						(arc
							(start 0.2794 -0.1778)
							(mid 0.249642 -0.249642)
							(end 0.1778 -0.2794)
						)
					)
					(width 0)
					(fill yes)
				)
			)
		)
		(pad "2" smd custom
			(at 0 0.4445 180)
			(size 0.1397 0.1397)
			(layers "F.Cu" "F.Mask" "F.Paste")
			(net "I2C_DRIVE_PWR_SCL4")
			(options
				(clearance outline)
				(anchor circle)
			)
			(primitives
				(gr_poly
					(pts
						(arc
							(start -0.1778 -0.2794)
							(mid -0.249642 -0.249642)
							(end -0.2794 -0.1778)
						)
						(arc
							(start -0.2794 0.1778)
							(mid -0.249642 0.249642)
							(end -0.1778 0.2794)
						)
						(arc
							(start 0.1778 0.2794)
							(mid 0.249642 0.249642)
							(end 0.2794 0.1778)
						)
						(arc
							(start 0.2794 -0.1778)
							(mid 0.249642 -0.249642)
							(end 0.1778 -0.2794)
						)
					)
					(width 0)
					(fill yes)
				)
			)
		)
	)
	(footprint ""
		(layer "F.Cu")
		(at 49.584102 -30.110176 -90)
		(property "Reference" "C615"
			(at 0 0 270)
			(layer "F.SilkS")
			(hide yes)
			(effects
				(font
					(size 1.27 1.27)
				)
			)
		)
		(property "Value" "SC1KP50V2KX-1GP"
			(at 1.1811 -2.7051 270)
			(unlocked yes)
			(layer "F.Fab")
			(hide yes)
			(effects
				(font
					(size 1.016 1.016)
					(thickness 0.1524)
				)
			)
		)
		(property "Device Type" "C402H22"
			(at 1.1811 -4.2291 270)
			(unlocked yes)
			(layer "F.Fab")
			(hide yes)
			(effects
				(font
					(size 1.016 1.016)
					(thickness 0.1524)
				)
			)
		)
		(duplicate_pad_numbers_are_jumpers no)
		(fp_rect
			(start -0.4318 0.9525)
			(end 0.4318 -0.9525)
			(stroke
				(width 0)
				(type default)
			)
			(fill no)
			(layer "F.CrtYd")
		)
		(fp_rect
			(start -0.4318 0.9525)
			(end 0.4318 -0.9525)
			(stroke
				(width 0)
				(type default)
			)
			(fill no)
			(layer "F.Fab")
		)
		(pad "1" smd custom
			(at 0 -0.4445 270)
			(size 0.1524 0.1524)
			(layers "F.Cu" "F.Mask" "F.Paste")
			(net "GND")
			(options
				(clearance outline)
				(anchor circle)
			)
			(primitives
				(gr_poly
					(pts
						(arc
							(start 0.3048 -0.2032)
							(mid 0.275042 -0.275042)
							(end 0.2032 -0.3048)
						)
						(arc
							(start -0.2032 -0.3048)
							(mid -0.275042 -0.275042)
							(end -0.3048 -0.2032)
						)
						(arc
							(start -0.3048 0.2032)
							(mid -0.275042 0.275042)
							(end -0.2032 0.3048)
						)
						(arc
							(start 0.2032 0.3048)
							(mid 0.275042 0.275042)
							(end 0.3048 0.2032)
						)
					)
					(width 0)
					(fill yes)
				)
			)
		)
		(pad "2" smd custom
			(at 0 0.4445 270)
			(size 0.1524 0.1524)
			(layers "F.Cu" "F.Mask" "F.Paste")
			(net "P0V9_VSNS")
			(options
				(clearance outline)
				(anchor circle)
			)
			(primitives
				(gr_poly
					(pts
						(arc
							(start 0.3048 -0.2032)
							(mid 0.275042 -0.275042)
							(end 0.2032 -0.3048)
						)
						(arc
							(start -0.2032 -0.3048)
							(mid -0.275042 -0.275042)
							(end -0.3048 -0.2032)
						)
						(arc
							(start -0.3048 0.2032)
							(mid -0.275042 0.275042)
							(end -0.2032 0.3048)
						)
						(arc
							(start 0.2032 0.3048)
							(mid 0.275042 0.275042)
							(end 0.3048 0.2032)
						)
					)
					(width 0)
					(fill yes)
				)
			)
		)
	)
	(footprint ""
		(layer "F.Cu")
		(at 48.110902 -29.551376 180)
		(property "Reference" "C613"
			(at 0 0 180)
			(layer "F.SilkS")
			(hide yes)
			(effects
				(font
					(size 1.27 1.27)
				)
			)
		)
		(property "Value" "SCD01U25V2KX-3GP"
			(at 1.1811 -2.7051 180)
			(unlocked yes)
			(layer "F.Fab")
			(hide yes)
			(effects
				(font
					(size 1.016 1.016)
					(thickness 0.1524)
				)
			)
		)
		(property "Device Type" "C402H22"
			(at 1.1811 -4.2291 180)
			(unlocked yes)
			(layer "F.Fab")
			(hide yes)
			(effects
				(font
					(size 1.016 1.016)
					(thickness 0.1524)
				)
			)
		)
		(duplicate_pad_numbers_are_jumpers no)
		(fp_rect
			(start -0.4318 0.9525)
			(end 0.4318 -0.9525)
			(stroke
				(width 0)
				(type default)
			)
			(fill no)
			(layer "F.CrtYd")
		)
		(fp_rect
			(start -0.4318 0.9525)
			(end 0.4318 -0.9525)
			(stroke
				(width 0)
				(type default)
			)
			(fill no)
			(layer "F.Fab")
		)
		(pad "1" smd custom
			(at 0 -0.4445 180)
			(size 0.1524 0.1524)
			(layers "F.Cu" "F.Mask" "F.Paste")
			(net "P0V9_VSNS")
			(options
				(clearance outline)
				(anchor circle)
			)
			(primitives
				(gr_poly
					(pts
						(arc
							(start 0.3048 -0.2032)
							(mid 0.275042 -0.275042)
							(end 0.2032 -0.3048)
						)
						(arc
							(start -0.2032 -0.3048)
							(mid -0.275042 -0.275042)
							(end -0.3048 -0.2032)
						)
						(arc
							(start -0.3048 0.2032)
							(mid -0.275042 0.275042)
							(end -0.2032 0.3048)
						)
						(arc
							(start 0.2032 0.3048)
							(mid 0.275042 0.275042)
							(end 0.3048 0.2032)
						)
					)
					(width 0)
					(fill yes)
				)
			)
		)
		(pad "2" smd custom
			(at 0 0.4445 180)
			(size 0.1524 0.1524)
			(layers "F.Cu" "F.Mask" "F.Paste")
			(net "P0V9_COMP")
			(options
				(clearance outline)
				(anchor circle)
			)
			(primitives
				(gr_poly
					(pts
						(arc
							(start 0.3048 -0.2032)
							(mid 0.275042 -0.275042)
							(end 0.2032 -0.3048)
						)
						(arc
							(start -0.2032 -0.3048)
							(mid -0.275042 -0.275042)
							(end -0.3048 -0.2032)
						)
						(arc
							(start -0.3048 0.2032)
							(mid -0.275042 0.275042)
							(end -0.2032 0.3048)
						)
						(arc
							(start 0.2032 0.3048)
							(mid 0.275042 0.275042)
							(end 0.3048 0.2032)
						)
					)
					(width 0)
					(fill yes)
				)
			)
		)
	)
	(footprint ""
		(layer "F.Cu")
		(at 177.8508 -99.822)
		(property "Reference" "R491"
			(at 0 0 0)
			(layer "F.SilkS")
			(hide yes)
			(effects
				(font
					(size 1.27 1.27)
				)
			)
		)
		(property "Value" "221R2F-2-GP"
			(at 0.064008 -3.993896 0)
			(unlocked yes)
			(layer "F.Fab")
			(hide yes)
			(effects
				(font
					(size 1.016 1.016)
					(thickness 0.1524)
				)
			)
		)
		(property "Device Type" "R402H16"
			(at 0.064008 -5.517896 0)
			(unlocked yes)
			(layer "F.Fab")
			(hide yes)
			(effects
				(font
					(size 1.016 1.016)
					(thickness 0.1524)
				)
			)
		)
		(duplicate_pad_numbers_are_jumpers no)
		(fp_line
			(start -0.508 -0.9398)
			(end -0.508 0.9398)
			(stroke
				(width 0.1524)
				(type default)
			)
			(layer "F.SilkS")
		)
		(fp_line
			(start 0.508 -0.9398)
			(end -0.508 -0.9398)
			(stroke
				(width 0.1524)
				(type default)
			)
			(layer "F.SilkS")
		)
		(fp_rect
			(start -0.508 0.9398)
			(end 0.508 -0.9398)
			(stroke
				(width 0)
				(type default)
			)
			(fill no)
			(layer "F.CrtYd")
		)
		(fp_rect
			(start -0.508 0.9398)
			(end 0.508 -0.9398)
			(stroke
				(width 0)
				(type default)
			)
			(fill no)
			(layer "F.Fab")
		)
		(pad "1" smd custom
			(at 0 -0.4445)
			(size 0.1397 0.1397)
			(layers "F.Cu" "F.Mask" "F.Paste")
			(net "VT235_VDES_RCC")
			(options
				(clearance outline)
				(anchor circle)
			)
			(primitives
				(gr_poly
					(pts
						(arc
							(start -0.1778 -0.2794)
							(mid -0.249642 -0.249642)
							(end -0.2794 -0.1778)
						)
						(arc
							(start -0.2794 0.1778)
							(mid -0.249642 0.249642)
							(end -0.1778 0.2794)
						)
						(arc
							(start 0.1778 0.2794)
							(mid 0.249642 0.249642)
							(end 0.2794 0.1778)
						)
						(arc
							(start 0.2794 -0.1778)
							(mid 0.249642 -0.249642)
							(end 0.1778 -0.2794)
						)
					)
					(width 0)
					(fill yes)
				)
			)
		)
		(pad "2" smd custom
			(at 0 0.4445)
			(size 0.1397 0.1397)
			(layers "F.Cu" "F.Mask" "F.Paste")
			(net "GND_SENSE")
			(options
				(clearance outline)
				(anchor circle)
			)
			(primitives
				(gr_poly
					(pts
						(arc
							(start -0.1778 -0.2794)
							(mid -0.249642 -0.249642)
							(end -0.2794 -0.1778)
						)
						(arc
							(start -0.2794 0.1778)
							(mid -0.249642 0.249642)
							(end -0.1778 0.2794)
						)
						(arc
							(start 0.1778 0.2794)
							(mid 0.249642 0.249642)
							(end 0.2794 0.1778)
						)
						(arc
							(start 0.2794 -0.1778)
							(mid 0.249642 -0.249642)
							(end 0.1778 -0.2794)
						)
					)
					(width 0)
					(fill yes)
				)
			)
		)
	)
	(footprint ""
		(layer "F.Cu")
		(at 63.34125 -77.487018 180)
		(property "Reference" "U38"
			(at 0 0 180)
			(layer "F.SilkS")
			(hide yes)
			(effects
				(font
					(size 1.27 1.27)
				)
			)
		)
		(property "Value" "PCA9306DCTR-GP"
			(at 0 -11.6332 180)
			(unlocked yes)
			(layer "F.Fab")
			(hide yes)
			(effects
				(font
					(size 1.016 1.016)
					(thickness 0.1524)
				)
			)
		)
		(property "Device Type" "SSOIC8H52"
			(at 0 -13.1572 180)
			(unlocked yes)
			(layer "F.Fab")
			(hide yes)
			(effects
				(font
					(size 1.016 1.016)
					(thickness 0.1524)
				)
			)
		)
		(duplicate_pad_numbers_are_jumpers no)
		(fp_line
			(start 1.0668 0.5842)
			(end -1.524 0.5842)
			(stroke
				(width 0.1524)
				(type default)
			)
			(layer "F.SilkS")
		)
		(fp_line
			(start 1.0668 -0.5842)
			(end 1.0668 0.5842)
			(stroke
				(width 0.1524)
				(type default)
			)
			(layer "F.SilkS")
		)
		(fp_line
			(start -1.397 0)
			(end -1.7018 0.3048)
			(stroke
				(width 0.1524)
				(type default)
			)
			(layer "F.SilkS")
		)
		(fp_line
			(start -1.397 0)
			(end -1.7018 -0.3048)
			(stroke
				(width 0.1524)
				(type default)
			)
			(layer "F.SilkS")
		)
		(fp_line
			(start -1.524 0.5842)
			(end -1.524 2.286)
			(stroke
				(width 0.508)
				(type default)
			)
			(layer "F.SilkS")
		)
		(fp_line
			(start -1.7018 -0.5842)
			(end 1.0668 -0.5842)
			(stroke
				(width 0.1524)
				(type default)
			)
			(layer "F.SilkS")
		)
		(fp_line
			(start -1.7018 -0.5842)
			(end -1.7018 2.286)
			(stroke
				(width 0.1524)
				(type default)
			)
			(layer "F.SilkS")
		)
		(fp_poly
			(pts
				(xy -1.1684 -0.5842) (xy 1.0668 -0.5842) (xy 1.0668 0.5842) (xy -1.1684 0.5842)
			)
			(stroke
				(width 0)
				(type default)
			)
			(fill yes)
			(layer "F.SilkS")
		)
		(fp_poly
			(pts
				(xy -1.778 2.54) (xy 1.778 2.54) (xy 1.778 -2.54) (xy -1.778 -2.54)
			)
			(stroke
				(width 0)
				(type default)
			)
			(fill no)
			(layer "F.CrtYd")
		)
		(fp_poly
			(pts
				(xy -1.778 -2.54) (xy 1.778 -2.54) (xy 1.778 2.54) (xy -1.778 2.54)
			)
			(stroke
				(width 0)
				(type default)
			)
			(fill no)
			(layer "F.Fab")
		)
		(pad "1" smd rect
			(at -0.97536 1.6256 180)
			(size 0.3556 1.524)
			(layers "F.Cu" "F.Mask" "F.Paste")
			(net "GND")
		)
		(pad "2" smd rect
			(at -0.32512 1.6256 180)
			(size 0.3556 1.524)
			(layers "F.Cu" "F.Mask" "F.Paste")
			(net "P1V8_E")
		)
		(pad "3" smd rect
			(at 0.32512 1.6256 180)
			(size 0.3556 1.524)
			(layers "F.Cu" "F.Mask" "F.Paste")
			(net "I2C_DRIVE_INS_SCL5_LS")
		)
		(pad "4" smd rect
			(at 0.97536 1.6256 180)
			(size 0.3556 1.524)
			(layers "F.Cu" "F.Mask" "F.Paste")
			(net "I2C_DRIVE_INS_SDA5_LS")
		)
		(pad "5" smd rect
			(at 0.97536 -1.6256 180)
			(size 0.3556 1.524)
			(layers "F.Cu" "F.Mask" "F.Paste")
			(net "I2C_DRIVE_INS_SDA5")
		)
		(pad "6" smd rect
			(at 0.32512 -1.6256 180)
			(size 0.3556 1.524)
			(layers "F.Cu" "F.Mask" "F.Paste")
			(net "I2C_DRIVE_INS_SCL5")
		)
		(pad "7" smd rect
			(at -0.32512 -1.6256 180)
			(size 0.3556 1.524)
			(layers "F.Cu" "F.Mask" "F.Paste")
			(net "VREF5")
		)
		(pad "8" smd rect
			(at -0.97536 -1.6256 180)
			(size 0.3556 1.524)
			(layers "F.Cu" "F.Mask" "F.Paste")
			(net "LS_EN_U38")
		)
	)
	(footprint ""
		(layer "F.Cu")
		(at 55.7276 -72.5678 180)
		(property "Reference" "R421"
			(at 0 0 180)
			(layer "F.SilkS")
			(hide yes)
			(effects
				(font
					(size 1.27 1.27)
				)
			)
		)
		(property "Value" "1KR2F-3-GP"
			(at 0.064008 -3.993896 180)
			(unlocked yes)
			(layer "F.Fab")
			(hide yes)
			(effects
				(font
					(size 1.016 1.016)
					(thickness 0.1524)
				)
			)
		)
		(property "Device Type" "R402H16"
			(at 0.064008 -5.517896 180)
			(unlocked yes)
			(layer "F.Fab")
			(hide yes)
			(effects
				(font
					(size 1.016 1.016)
					(thickness 0.1524)
				)
			)
		)
		(duplicate_pad_numbers_are_jumpers no)
		(fp_line
			(start 0.508 -0.9398)
			(end -0.508 -0.9398)
			(stroke
				(width 0.1524)
				(type default)
			)
			(layer "F.SilkS")
		)
		(fp_line
			(start -0.508 -0.9398)
			(end -0.508 0.9398)
			(stroke
				(width 0.1524)
				(type default)
			)
			(layer "F.SilkS")
		)
		(fp_rect
			(start -0.508 0.9398)
			(end 0.508 -0.9398)
			(stroke
				(width 0)
				(type default)
			)
			(fill no)
			(layer "F.CrtYd")
		)
		(fp_rect
			(start -0.508 0.9398)
			(end 0.508 -0.9398)
			(stroke
				(width 0)
				(type default)
			)
			(fill no)
			(layer "F.Fab")
		)
		(pad "1" smd custom
			(at 0 -0.4445 180)
			(size 0.1397 0.1397)
			(layers "F.Cu" "F.Mask" "F.Paste")
			(net "P3V3")
			(options
				(clearance outline)
				(anchor circle)
			)
			(primitives
				(gr_poly
					(pts
						(arc
							(start -0.1778 -0.2794)
							(mid -0.249642 -0.249642)
							(end -0.2794 -0.1778)
						)
						(arc
							(start -0.2794 0.1778)
							(mid -0.249642 0.249642)
							(end -0.1778 0.2794)
						)
						(arc
							(start 0.1778 0.2794)
							(mid 0.249642 0.249642)
							(end 0.2794 0.1778)
						)
						(arc
							(start 0.2794 -0.1778)
							(mid 0.249642 -0.249642)
							(end 0.1778 -0.2794)
						)
					)
					(width 0)
					(fill yes)
				)
			)
		)
		(pad "2" smd custom
			(at 0 0.4445 180)
			(size 0.1397 0.1397)
			(layers "F.Cu" "F.Mask" "F.Paste")
			(net "I2C_DRIVE_PWR_SDA4")
			(options
				(clearance outline)
				(anchor circle)
			)
			(primitives
				(gr_poly
					(pts
						(arc
							(start -0.1778 -0.2794)
							(mid -0.249642 -0.249642)
							(end -0.2794 -0.1778)
						)
						(arc
							(start -0.2794 0.1778)
							(mid -0.249642 0.249642)
							(end -0.1778 0.2794)
						)
						(arc
							(start 0.1778 0.2794)
							(mid 0.249642 0.249642)
							(end 0.2794 0.1778)
						)
						(arc
							(start 0.2794 -0.1778)
							(mid 0.249642 -0.249642)
							(end 0.1778 -0.2794)
						)
					)
					(width 0)
					(fill yes)
				)
			)
		)
	)
	(footprint ""
		(layer "F.Cu")
		(at 22.8092 -47.0154 180)
		(property "Reference" "R551"
			(at 0 0 180)
			(layer "F.SilkS")
			(hide yes)
			(effects
				(font
					(size 1.27 1.27)
				)
			)
		)
		(property "Value" "49K9R2F-L-GP"
			(at 0.064008 -3.993896 180)
			(unlocked yes)
			(layer "F.Fab")
			(hide yes)
			(effects
				(font
					(size 1.016 1.016)
					(thickness 0.1524)
				)
			)
		)
		(property "Device Type" "R402H16"
			(at 0.064008 -5.517896 180)
			(unlocked yes)
			(layer "F.Fab")
			(hide yes)
			(effects
				(font
					(size 1.016 1.016)
					(thickness 0.1524)
				)
			)
		)
		(duplicate_pad_numbers_are_jumpers no)
		(fp_line
			(start 0.508 -0.9398)
			(end -0.508 -0.9398)
			(stroke
				(width 0.1524)
				(type default)
			)
			(layer "F.SilkS")
		)
		(fp_line
			(start -0.508 -0.9398)
			(end -0.508 0.9398)
			(stroke
				(width 0.1524)
				(type default)
			)
			(layer "F.SilkS")
		)
		(fp_rect
			(start -0.508 0.9398)
			(end 0.508 -0.9398)
			(stroke
				(width 0)
				(type default)
			)
			(fill no)
			(layer "F.CrtYd")
		)
		(fp_rect
			(start -0.508 0.9398)
			(end 0.508 -0.9398)
			(stroke
				(width 0)
				(type default)
			)
			(fill no)
			(layer "F.Fab")
		)
		(pad "1" smd custom
			(at 0 -0.4445 180)
			(size 0.1397 0.1397)
			(layers "F.Cu" "F.Mask" "F.Paste")
			(net "P12V_MAIN")
			(options
				(clearance outline)
				(anchor circle)
			)
			(primitives
				(gr_poly
					(pts
						(arc
							(start -0.1778 -0.2794)
							(mid -0.249642 -0.249642)
							(end -0.2794 -0.1778)
						)
						(arc
							(start -0.2794 0.1778)
							(mid -0.249642 0.249642)
							(end -0.1778 0.2794)
						)
						(arc
							(start 0.1778 0.2794)
							(mid 0.249642 0.249642)
							(end 0.2794 0.1778)
						)
						(arc
							(start 0.2794 -0.1778)
							(mid 0.249642 -0.249642)
							(end 0.1778 -0.2794)
						)
					)
					(width 0)
					(fill yes)
				)
			)
		)
		(pad "2" smd custom
			(at 0 0.4445 180)
			(size 0.1397 0.1397)
			(layers "F.Cu" "F.Mask" "F.Paste")
			(net "MB0_CM_OV_R")
			(options
				(clearance outline)
				(anchor circle)
			)
			(primitives
				(gr_poly
					(pts
						(arc
							(start -0.1778 -0.2794)
							(mid -0.249642 -0.249642)
							(end -0.2794 -0.1778)
						)
						(arc
							(start -0.2794 0.1778)
							(mid -0.249642 0.249642)
							(end -0.1778 0.2794)
						)
						(arc
							(start 0.1778 0.2794)
							(mid 0.249642 0.249642)
							(end 0.2794 0.1778)
						)
						(arc
							(start 0.2794 -0.1778)
							(mid 0.249642 -0.249642)
							(end 0.1778 -0.2794)
						)
					)
					(width 0)
					(fill yes)
				)
			)
		)
	)
	(footprint ""
		(layer "F.Cu")
		(at 6.6294 -94.831408 180)
		(property "Reference" "C548"
			(at 0 0 180)
			(layer "F.SilkS")
			(hide yes)
			(effects
				(font
					(size 1.27 1.27)
				)
			)
		)
		(property "Value" "SCD1U16V2KX-3GP"
			(at 1.1811 -2.7051 180)
			(unlocked yes)
			(layer "F.Fab")
			(hide yes)
			(effects
				(font
					(size 1.016 1.016)
					(thickness 0.1524)
				)
			)
		)
		(property "Device Type" "C402H22"
			(at 1.1811 -4.2291 180)
			(unlocked yes)
			(layer "F.Fab")
			(hide yes)
			(effects
				(font
					(size 1.016 1.016)
					(thickness 0.1524)
				)
			)
		)
		(duplicate_pad_numbers_are_jumpers no)
		(fp_rect
			(start -0.4318 0.9525)
			(end 0.4318 -0.9525)
			(stroke
				(width 0)
				(type default)
			)
			(fill no)
			(layer "F.CrtYd")
		)
		(fp_rect
			(start -0.4318 0.9525)
			(end 0.4318 -0.9525)
			(stroke
				(width 0)
				(type default)
			)
			(fill no)
			(layer "F.Fab")
		)
		(pad "1" smd custom
			(at 0 -0.4445 180)
			(size 0.1524 0.1524)
			(layers "F.Cu" "F.Mask" "F.Paste")
			(net "VREF2")
			(options
				(clearance outline)
				(anchor circle)
			)
			(primitives
				(gr_poly
					(pts
						(arc
							(start 0.3048 -0.2032)
							(mid 0.275042 -0.275042)
							(end 0.2032 -0.3048)
						)
						(arc
							(start -0.2032 -0.3048)
							(mid -0.275042 -0.275042)
							(end -0.3048 -0.2032)
						)
						(arc
							(start -0.3048 0.2032)
							(mid -0.275042 0.275042)
							(end -0.2032 0.3048)
						)
						(arc
							(start 0.2032 0.3048)
							(mid 0.275042 0.275042)
							(end 0.3048 0.2032)
						)
					)
					(width 0)
					(fill yes)
				)
			)
		)
		(pad "2" smd custom
			(at 0 0.4445 180)
			(size 0.1524 0.1524)
			(layers "F.Cu" "F.Mask" "F.Paste")
			(net "GND")
			(options
				(clearance outline)
				(anchor circle)
			)
			(primitives
				(gr_poly
					(pts
						(arc
							(start 0.3048 -0.2032)
							(mid 0.275042 -0.275042)
							(end 0.2032 -0.3048)
						)
						(arc
							(start -0.2032 -0.3048)
							(mid -0.275042 -0.275042)
							(end -0.3048 -0.2032)
						)
						(arc
							(start -0.3048 0.2032)
							(mid -0.275042 0.275042)
							(end -0.2032 0.3048)
						)
						(arc
							(start 0.2032 0.3048)
							(mid 0.275042 0.275042)
							(end 0.3048 0.2032)
						)
					)
					(width 0)
					(fill yes)
				)
			)
		)
	)
	(footprint ""
		(layer "F.Cu")
		(at 8.20547 -89.054178)
		(property "Reference" "U36"
			(at 0 0 0)
			(layer "F.SilkS")
			(hide yes)
			(effects
				(font
					(size 1.27 1.27)
				)
			)
		)
		(property "Value" "PCA9306DCTR-GP"
			(at 0 -11.6332 0)
			(unlocked yes)
			(layer "F.Fab")
			(hide yes)
			(effects
				(font
					(size 1.016 1.016)
					(thickness 0.1524)
				)
			)
		)
		(property "Device Type" "SSOIC8H52"
			(at 0 -13.1572 0)
			(unlocked yes)
			(layer "F.Fab")
			(hide yes)
			(effects
				(font
					(size 1.016 1.016)
					(thickness 0.1524)
				)
			)
		)
		(duplicate_pad_numbers_are_jumpers no)
		(fp_line
			(start -1.7018 -0.5842)
			(end -1.7018 2.286)
			(stroke
				(width 0.1524)
				(type default)
			)
			(layer "F.SilkS")
		)
		(fp_line
			(start -1.7018 -0.5842)
			(end 1.0668 -0.5842)
			(stroke
				(width 0.1524)
				(type default)
			)
			(layer "F.SilkS")
		)
		(fp_line
			(start -1.524 0.5842)
			(end -1.524 2.286)
			(stroke
				(width 0.508)
				(type default)
			)
			(layer "F.SilkS")
		)
		(fp_line
			(start -1.397 0)
			(end -1.7018 -0.3048)
			(stroke
				(width 0.1524)
				(type default)
			)
			(layer "F.SilkS")
		)
		(fp_line
			(start -1.397 0)
			(end -1.7018 0.3048)
			(stroke
				(width 0.1524)
				(type default)
			)
			(layer "F.SilkS")
		)
		(fp_line
			(start 1.0668 -0.5842)
			(end 1.0668 0.5842)
			(stroke
				(width 0.1524)
				(type default)
			)
			(layer "F.SilkS")
		)
		(fp_line
			(start 1.0668 0.5842)
			(end -1.524 0.5842)
			(stroke
				(width 0.1524)
				(type default)
			)
			(layer "F.SilkS")
		)
		(fp_poly
			(pts
				(xy -1.1684 -0.5842) (xy 1.0668 -0.5842) (xy 1.0668 0.5842) (xy -1.1684 0.5842)
			)
			(stroke
				(width 0)
				(type default)
			)
			(fill yes)
			(layer "F.SilkS")
		)
		(fp_poly
			(pts
				(xy -1.778 2.54) (xy 1.778 2.54) (xy 1.778 -2.54) (xy -1.778 -2.54)
			)
			(stroke
				(width 0)
				(type default)
			)
			(fill no)
			(layer "F.CrtYd")
		)
		(fp_poly
			(pts
				(xy -1.778 -2.54) (xy 1.778 -2.54) (xy 1.778 2.54) (xy -1.778 2.54)
			)
			(stroke
				(width 0)
				(type default)
			)
			(fill no)
			(layer "F.Fab")
		)
		(pad "1" smd rect
			(at -0.97536 1.6256)
			(size 0.3556 1.524)
			(layers "F.Cu" "F.Mask" "F.Paste")
			(net "GND")
		)
		(pad "2" smd rect
			(at -0.32512 1.6256)
			(size 0.3556 1.524)
			(layers "F.Cu" "F.Mask" "F.Paste")
			(net "P1V8_E")
		)
		(pad "3" smd rect
			(at 0.32512 1.6256)
			(size 0.3556 1.524)
			(layers "F.Cu" "F.Mask" "F.Paste")
			(net "I2C_SCC_SCL2_LS")
		)
		(pad "4" smd rect
			(at 0.97536 1.6256)
			(size 0.3556 1.524)
			(layers "F.Cu" "F.Mask" "F.Paste")
			(net "I2C_SCC_SDA2_LS")
		)
		(pad "5" smd rect
			(at 0.97536 -1.6256)
			(size 0.3556 1.524)
			(layers "F.Cu" "F.Mask" "F.Paste")
			(net "I2C_SCC_SDA2")
		)
		(pad "6" smd rect
			(at 0.32512 -1.6256)
			(size 0.3556 1.524)
			(layers "F.Cu" "F.Mask" "F.Paste")
			(net "I2C_SCC_SCL2")
		)
		(pad "7" smd rect
			(at -0.32512 -1.6256)
			(size 0.3556 1.524)
			(layers "F.Cu" "F.Mask" "F.Paste")
			(net "VREF2")
		)
		(pad "8" smd rect
			(at -0.97536 -1.6256)
			(size 0.3556 1.524)
			(layers "F.Cu" "F.Mask" "F.Paste")
			(net "LS_EN_U36")
		)
	)
	(footprint ""
		(layer "F.Cu")
		(at 147.317206 -51.039268 102)
		(property "Reference" "C341"
			(at 0 0 102)
			(layer "F.SilkS")
			(hide yes)
			(effects
				(font
					(size 1.27 1.27)
				)
			)
		)
		(property "Value" "SCD01U16V1KX-GP"
			(at -2.831995 -1.740026 102)
			(unlocked yes)
			(layer "F.Fab")
			(hide yes)
			(effects
				(font
					(size 1.016 1.016)
					(thickness 0.1524)
				)
			)
		)
		(property "Device Type" "C0201H13"
			(at -2.831872 -3.264029 102)
			(unlocked yes)
			(layer "F.Fab")
			(hide yes)
			(effects
				(font
					(size 1.016 1.016)
					(thickness 0.1524)
				)
			)
		)
		(duplicate_pad_numbers_are_jumpers no)
		(fp_poly
			(pts
				(xy -0.279454 -0.647706) (xy 0.279346 -0.647706) (xy 0.279346 0.647694) (xy -0.279454 0.647694)
			)
			(stroke
				(width 0)
				(type default)
			)
			(fill no)
			(layer "F.CrtYd")
		)
		(fp_poly
			(pts
				(xy -0.279454 -0.647706) (xy 0.279346 -0.647706) (xy 0.279346 0.647694) (xy -0.279454 0.647694)
			)
			(stroke
				(width 0)
				(type default)
			)
			(fill no)
			(layer "F.Fab")
		)
		(pad "1" smd custom
			(at -0.000001 -0.2794 102)
			(size 0.0762 0.0762)
			(layers "F.Cu" "F.Mask" "F.Paste")
			(net "PHY_SCC_TO_IOC_46_DP")
			(options
				(clearance outline)
				(anchor circle)
			)
			(primitives
				(gr_poly
					(pts
						(arc
							(start 0.1524 -0.127)
							(mid 0.137521 -0.162921)
							(end 0.1016 -0.1778)
						)
						(arc
							(start -0.1016 -0.1778)
							(mid -0.137521 -0.162921)
							(end -0.1524 -0.127)
						)
						(arc
							(start -0.1524 0.127)
							(mid -0.137521 0.162921)
							(end -0.1016 0.1778)
						)
						(arc
							(start 0.1016 0.1778)
							(mid 0.137521 0.162921)
							(end 0.1524 0.127)
						)
					)
					(width 0)
					(fill yes)
				)
			)
		)
		(pad "2" smd custom
			(at 0.000001 0.2794 102)
			(size 0.0762 0.0762)
			(layers "F.Cu" "F.Mask" "F.Paste")
			(net "PHY_SCC_TO_IOC_C_46_DP")
			(options
				(clearance outline)
				(anchor circle)
			)
			(primitives
				(gr_poly
					(pts
						(arc
							(start 0.1524 -0.127)
							(mid 0.137521 -0.162921)
							(end 0.1016 -0.1778)
						)
						(arc
							(start -0.1016 -0.1778)
							(mid -0.137521 -0.162921)
							(end -0.1524 -0.127)
						)
						(arc
							(start -0.1524 0.127)
							(mid -0.137521 0.162921)
							(end -0.1016 0.1778)
						)
						(arc
							(start 0.1016 0.1778)
							(mid 0.137521 0.162921)
							(end 0.1524 0.127)
						)
					)
					(width 0)
					(fill yes)
				)
			)
		)
	)
	(footprint ""
		(layer "F.Cu")
		(at 136.181592 -77.272134 90)
		(property "Reference" "C680"
			(at 0 0 90)
			(layer "F.SilkS")
			(hide yes)
			(effects
				(font
					(size 1.27 1.27)
				)
			)
		)
		(property "Value" "SCD01U16V1KX-GP"
			(at -2.8321 -1.7399 90)
			(unlocked yes)
			(layer "F.Fab")
			(hide yes)
			(effects
				(font
					(size 1.016 1.016)
					(thickness 0.1524)
				)
			)
		)
		(property "Device Type" "C0201H13"
			(at -2.8321 -3.2639 90)
			(unlocked yes)
			(layer "F.Fab")
			(hide yes)
			(effects
				(font
					(size 1.016 1.016)
					(thickness 0.1524)
				)
			)
		)
		(duplicate_pad_numbers_are_jumpers no)
		(fp_rect
			(start -0.2794 0.6477)
			(end 0.2794 -0.6477)
			(stroke
				(width 0)
				(type default)
			)
			(fill no)
			(layer "F.CrtYd")
		)
		(fp_rect
			(start -0.2794 0.6477)
			(end 0.2794 -0.6477)
			(stroke
				(width 0)
				(type default)
			)
			(fill no)
			(layer "F.Fab")
		)
		(pad "1" smd custom
			(at 0 -0.2794 90)
			(size 0.0762 0.0762)
			(layers "F.Cu" "F.Mask" "F.Paste")
			(net "PHY_EXP_TO_CONN_C_9_DP")
			(options
				(clearance outline)
				(anchor circle)
			)
			(primitives
				(gr_poly
					(pts
						(arc
							(start 0.1524 -0.127)
							(mid 0.137521 -0.162921)
							(end 0.1016 -0.1778)
						)
						(arc
							(start -0.1016 -0.1778)
							(mid -0.137521 -0.162921)
							(end -0.1524 -0.127)
						)
						(arc
							(start -0.1524 0.127)
							(mid -0.137521 0.162921)
							(end -0.1016 0.1778)
						)
						(arc
							(start 0.1016 0.1778)
							(mid 0.137521 0.162921)
							(end 0.1524 0.127)
						)
					)
					(width 0)
					(fill yes)
				)
			)
		)
		(pad "2" smd custom
			(at 0 0.2794 90)
			(size 0.0762 0.0762)
			(layers "F.Cu" "F.Mask" "F.Paste")
			(net "PHY_EXP_TO_CONN_9_DP")
			(options
				(clearance outline)
				(anchor circle)
			)
			(primitives
				(gr_poly
					(pts
						(arc
							(start 0.1524 -0.127)
							(mid 0.137521 -0.162921)
							(end 0.1016 -0.1778)
						)
						(arc
							(start -0.1016 -0.1778)
							(mid -0.137521 -0.162921)
							(end -0.1524 -0.127)
						)
						(arc
							(start -0.1524 0.127)
							(mid -0.137521 0.162921)
							(end -0.1016 0.1778)
						)
						(arc
							(start 0.1016 0.1778)
							(mid 0.137521 0.162921)
							(end 0.1524 0.127)
						)
					)
					(width 0)
					(fill yes)
				)
			)
		)
	)
	(footprint ""
		(layer "F.Cu")
		(at 142.778226 -64.375284 -90)
		(property "Reference" "C34"
			(at 0 0 270)
			(layer "F.SilkS")
			(hide yes)
			(effects
				(font
					(size 1.27 1.27)
				)
			)
		)
		(property "Value" "SCD01U16V1KX-GP"
			(at -2.8321 -1.7399 270)
			(unlocked yes)
			(layer "F.Fab")
			(hide yes)
			(effects
				(font
					(size 1.016 1.016)
					(thickness 0.1524)
				)
			)
		)
		(property "Device Type" "C0201H13"
			(at -2.8321 -3.2639 270)
			(unlocked yes)
			(layer "F.Fab")
			(hide yes)
			(effects
				(font
					(size 1.016 1.016)
					(thickness 0.1524)
				)
			)
		)
		(duplicate_pad_numbers_are_jumpers no)
		(fp_rect
			(start -0.2794 0.6477)
			(end 0.2794 -0.6477)
			(stroke
				(width 0)
				(type default)
			)
			(fill no)
			(layer "F.CrtYd")
		)
		(fp_rect
			(start -0.2794 0.6477)
			(end 0.2794 -0.6477)
			(stroke
				(width 0)
				(type default)
			)
			(fill no)
			(layer "F.Fab")
		)
		(pad "1" smd custom
			(at 0 -0.2794 270)
			(size 0.0762 0.0762)
			(layers "F.Cu" "F.Mask" "F.Paste")
			(net "PHY_IOC_TO_SCC_47_DN")
			(options
				(clearance outline)
				(anchor circle)
			)
			(primitives
				(gr_poly
					(pts
						(arc
							(start 0.1524 -0.127)
							(mid 0.137521 -0.162921)
							(end 0.1016 -0.1778)
						)
						(arc
							(start -0.1016 -0.1778)
							(mid -0.137521 -0.162921)
							(end -0.1524 -0.127)
						)
						(arc
							(start -0.1524 0.127)
							(mid -0.137521 0.162921)
							(end -0.1016 0.1778)
						)
						(arc
							(start 0.1016 0.1778)
							(mid 0.137521 0.162921)
							(end 0.1524 0.127)
						)
					)
					(width 0)
					(fill yes)
				)
			)
		)
		(pad "2" smd custom
			(at 0 0.2794 270)
			(size 0.0762 0.0762)
			(layers "F.Cu" "F.Mask" "F.Paste")
			(net "PHY_IOC_TO_SCC_C_47_DN")
			(options
				(clearance outline)
				(anchor circle)
			)
			(primitives
				(gr_poly
					(pts
						(arc
							(start 0.1524 -0.127)
							(mid 0.137521 -0.162921)
							(end 0.1016 -0.1778)
						)
						(arc
							(start -0.1016 -0.1778)
							(mid -0.137521 -0.162921)
							(end -0.1524 -0.127)
						)
						(arc
							(start -0.1524 0.127)
							(mid -0.137521 0.162921)
							(end -0.1016 0.1778)
						)
						(arc
							(start 0.1016 0.1778)
							(mid 0.137521 0.162921)
							(end 0.1524 0.127)
						)
					)
					(width 0)
					(fill yes)
				)
			)
		)
	)
	(footprint ""
		(layer "F.Cu")
		(at 176.406048 -116.146834)
		(property "Reference" "U4"
			(at 0 0 0)
			(layer "F.SilkS")
			(hide yes)
			(effects
				(font
					(size 1.27 1.27)
				)
			)
		)
		(property "Value" "TPS74801RGW-GP"
			(at -4.7244 -6.223 0)
			(unlocked yes)
			(layer "F.Fab")
			(hide yes)
			(effects
				(font
					(size 1.016 1.016)
					(thickness 0.1524)
				)
			)
		)
		(property "Device Type" "QFN20-1G3D15H40"
			(at -4.7244 -7.747 0)
			(unlocked yes)
			(layer "F.Fab")
			(hide yes)
			(effects
				(font
					(size 1.016 1.016)
					(thickness 0.1524)
				)
			)
		)
		(duplicate_pad_numbers_are_jumpers no)
		(fp_line
			(start -3.5179 -3.5179)
			(end -3.5179 -2.2479)
			(stroke
				(width 0.1524)
				(type default)
			)
			(layer "F.SilkS")
		)
		(fp_line
			(start -3.5179 2.2479)
			(end -3.5179 3.5179)
			(stroke
				(width 0.1524)
				(type default)
			)
			(layer "F.SilkS")
		)
		(fp_line
			(start -3.5179 3.5179)
			(end -2.2479 3.5179)
			(stroke
				(width 0.1524)
				(type default)
			)
			(layer "F.SilkS")
		)
		(fp_line
			(start -3.160522 1.299972)
			(end -3.922522 1.299972)
			(stroke
				(width 0.1524)
				(type default)
			)
			(layer "F.SilkS")
		)
		(fp_line
			(start -2.2479 -3.5179)
			(end -3.5179 -3.5179)
			(stroke
				(width 0.1524)
				(type default)
			)
			(layer "F.SilkS")
		)
		(fp_line
			(start -1.299972 -3.160522)
			(end -1.299972 -3.668522)
			(stroke
				(width 0.1524)
				(type default)
			)
			(layer "F.SilkS")
		)
		(fp_line
			(start 1.299972 3.160522)
			(end 1.299972 3.668522)
			(stroke
				(width 0.1524)
				(type default)
			)
			(layer "F.SilkS")
		)
		(fp_line
			(start 2.2479 3.5179)
			(end 3.5179 3.5179)
			(stroke
				(width 0.1524)
				(type default)
			)
			(layer "F.SilkS")
		)
		(fp_line
			(start 3.160522 -1.299972)
			(end 3.922522 -1.299972)
			(stroke
				(width 0.1524)
				(type default)
			)
			(layer "F.SilkS")
		)
		(fp_line
			(start 3.5179 3.5179)
			(end 3.5179 2.2479)
			(stroke
				(width 0.1524)
				(type default)
			)
			(layer "F.SilkS")
		)
		(fp_poly
			(pts
				(xy 3.5179 -3.5179) (xy 2.2479 -3.5179) (xy 3.5179 -2.2479)
			)
			(stroke
				(width 0)
				(type default)
			)
			(fill yes)
			(layer "F.SilkS")
		)
		(fp_rect
			(start -2.5019 2.5019)
			(end 2.5019 -2.5019)
			(stroke
				(width 0)
				(type default)
			)
			(fill no)
			(layer "F.CrtYd")
		)
		(fp_poly
			(pts
				(xy -3.5179 3.5179) (xy -3.5179 -3.5179) (xy 3.5179 -3.5179) (xy 3.5179 -2.5019) (xy -2.5019 -2.5019)
				(xy -2.5019 2.5019) (xy 2.5019 2.5019) (xy 2.5019 -2.49682) (xy 3.5179 -2.49682) (xy 3.5179 3.5179)
			)
			(stroke
				(width 0)
				(type default)
			)
			(fill no)
			(layer "F.CrtYd")
		)
		(fp_rect
			(start -3.5179 3.5179)
			(end 3.5179 -3.5179)
			(stroke
				(width 0)
				(type default)
			)
			(fill no)
			(layer "F.Fab")
		)
		(pad "1" smd rect
			(at 1.299972 -2.474722)
			(size 0.3556 1.0668)
			(layers "F.Cu" "F.Mask" "F.Paste")
			(net "P1V8_E_OUT")
		)
		(pad "2" smd rect
			(at 0.649986 -2.474722)
			(size 0.3556 1.0668)
			(layers "F.Cu" "F.Mask" "F.Paste")
			(net "GND")
		)
		(pad "3" smd rect
			(at 0 -2.474722)
			(size 0.3556 1.0668)
			(layers "F.Cu" "F.Mask" "F.Paste")
			(net "GND")
		)
		(pad "4" smd rect
			(at -0.649986 -2.474722)
			(size 0.3556 1.0668)
			(layers "F.Cu" "F.Mask" "F.Paste")
			(net "GND")
		)
		(pad "5" smd rect
			(at -1.299972 -2.474722)
			(size 0.3556 1.0668)
			(layers "F.Cu" "F.Mask" "F.Paste")
			(net "P3V3")
		)
		(pad "6" smd rect
			(at -2.474722 -1.299972)
			(size 1.0668 0.3556)
			(layers "F.Cu" "F.Mask" "F.Paste")
			(net "P3V3")
		)
		(pad "7" smd rect
			(at -2.474722 -0.649986)
			(size 1.0668 0.3556)
			(layers "F.Cu" "F.Mask" "F.Paste")
			(net "P3V3")
		)
		(pad "8" smd rect
			(at -2.474722 0)
			(size 1.0668 0.3556)
			(layers "F.Cu" "F.Mask" "F.Paste")
			(net "P3V3")
		)
		(pad "9" smd rect
			(at -2.474722 0.649986)
			(size 1.0668 0.3556)
			(layers "F.Cu" "F.Mask" "F.Paste")
			(net "P1V8_E_PG")
		)
		(pad "10" smd rect
			(at -2.474722 1.299972)
			(size 1.0668 0.3556)
			(layers "F.Cu" "F.Mask" "F.Paste")
			(net "P1V8_E_BIAS")
		)
		(pad "11" smd rect
			(at -1.299972 2.474722)
			(size 0.3556 1.0668)
			(layers "F.Cu" "F.Mask" "F.Paste")
			(net "P1V8_E_EN")
		)
		(pad "12" smd rect
			(at -0.649986 2.474722)
			(size 0.3556 1.0668)
			(layers "F.Cu" "F.Mask" "F.Paste")
			(net "GND")
		)
		(pad "13" smd rect
			(at 0 2.474722)
			(size 0.3556 1.0668)
			(layers "F.Cu" "F.Mask" "F.Paste")
			(net "GND")
		)
		(pad "14" smd rect
			(at 0.649986 2.474722)
			(size 0.3556 1.0668)
			(layers "F.Cu" "F.Mask" "F.Paste")
			(net "GND")
		)
		(pad "15" smd rect
			(at 1.299972 2.474722)
			(size 0.3556 1.0668)
			(layers "F.Cu" "F.Mask" "F.Paste")
			(net "P1V8_E_SS")
		)
		(pad "16" smd rect
			(at 2.474722 1.299972)
			(size 1.0668 0.3556)
			(layers "F.Cu" "F.Mask" "F.Paste")
			(net "P1V8_E_FB")
		)
		(pad "17" smd rect
			(at 2.474722 0.649986)
			(size 1.0668 0.3556)
			(layers "F.Cu" "F.Mask" "F.Paste")
			(net "GND")
		)
		(pad "18" smd rect
			(at 2.474722 0)
			(size 1.0668 0.3556)
			(layers "F.Cu" "F.Mask" "F.Paste")
			(net "P1V8_E_OUT")
		)
		(pad "19" smd rect
			(at 2.474722 -0.649986)
			(size 1.0668 0.3556)
			(layers "F.Cu" "F.Mask" "F.Paste")
			(net "P1V8_E_OUT")
		)
		(pad "20" smd rect
			(at 2.474722 -1.299972)
			(size 1.0668 0.3556)
			(layers "F.Cu" "F.Mask" "F.Paste")
			(net "P1V8_E_OUT")
		)
		(pad "21" smd rect
			(at 0 0)
			(size 3.2512 3.2512)
			(layers "F.Cu" "F.Mask" "F.Paste")
			(net "GND")
		)
	)
	(footprint ""
		(layer "F.Cu")
		(at 163.878768 -23.935944 -90)
		(property "Reference" "R173"
			(at 0 0 270)
			(layer "F.SilkS")
			(hide yes)
			(effects
				(font
					(size 1.27 1.27)
				)
			)
		)
		(property "Value" "51R2F-2-GP"
			(at 0.064008 -3.993896 270)
			(unlocked yes)
			(layer "F.Fab")
			(hide yes)
			(effects
				(font
					(size 1.016 1.016)
					(thickness 0.1524)
				)
			)
		)
		(property "Device Type" "R402H16"
			(at 0.064008 -5.517896 270)
			(unlocked yes)
			(layer "F.Fab")
			(hide yes)
			(effects
				(font
					(size 1.016 1.016)
					(thickness 0.1524)
				)
			)
		)
		(duplicate_pad_numbers_are_jumpers no)
		(fp_line
			(start -0.508 -0.9398)
			(end -0.508 0.9398)
			(stroke
				(width 0.1524)
				(type default)
			)
			(layer "F.SilkS")
		)
		(fp_line
			(start 0.508 -0.9398)
			(end -0.508 -0.9398)
			(stroke
				(width 0.1524)
				(type default)
			)
			(layer "F.SilkS")
		)
		(fp_rect
			(start -0.508 0.9398)
			(end 0.508 -0.9398)
			(stroke
				(width 0)
				(type default)
			)
			(fill no)
			(layer "F.CrtYd")
		)
		(fp_rect
			(start -0.508 0.9398)
			(end 0.508 -0.9398)
			(stroke
				(width 0)
				(type default)
			)
			(fill no)
			(layer "F.Fab")
		)
		(pad "1" smd custom
			(at 0 -0.4445 270)
			(size 0.1397 0.1397)
			(layers "F.Cu" "F.Mask" "F.Paste")
			(net "GND")
			(options
				(clearance outline)
				(anchor circle)
			)
			(primitives
				(gr_poly
					(pts
						(arc
							(start -0.1778 -0.2794)
							(mid -0.249642 -0.249642)
							(end -0.2794 -0.1778)
						)
						(arc
							(start -0.2794 0.1778)
							(mid -0.249642 0.249642)
							(end -0.1778 0.2794)
						)
						(arc
							(start 0.1778 0.2794)
							(mid 0.249642 0.249642)
							(end 0.2794 0.1778)
						)
						(arc
							(start 0.2794 -0.1778)
							(mid 0.249642 -0.249642)
							(end 0.1778 -0.2794)
						)
					)
					(width 0)
					(fill yes)
				)
			)
		)
		(pad "2" smd custom
			(at 0 0.4445 270)
			(size 0.1397 0.1397)
			(layers "F.Cu" "F.Mask" "F.Paste")
			(net "PCIE_CLK_R_N")
			(options
				(clearance outline)
				(anchor circle)
			)
			(primitives
				(gr_poly
					(pts
						(arc
							(start -0.1778 -0.2794)
							(mid -0.249642 -0.249642)
							(end -0.2794 -0.1778)
						)
						(arc
							(start -0.2794 0.1778)
							(mid -0.249642 0.249642)
							(end -0.1778 0.2794)
						)
						(arc
							(start 0.1778 0.2794)
							(mid 0.249642 0.249642)
							(end 0.2794 0.1778)
						)
						(arc
							(start 0.2794 -0.1778)
							(mid 0.249642 -0.249642)
							(end 0.1778 -0.2794)
						)
					)
					(width 0)
					(fill yes)
				)
			)
		)
	)
	(footprint ""
		(layer "F.Cu")
		(at 151.930608 -92.593414 180)
		(property "Reference" "C503"
			(at 0 0 180)
			(layer "F.SilkS")
			(hide yes)
			(effects
				(font
					(size 1.27 1.27)
				)
			)
		)
		(property "Value" "SCD1U16V2KX-3GP"
			(at 1.1811 -2.7051 180)
			(unlocked yes)
			(layer "F.Fab")
			(hide yes)
			(effects
				(font
					(size 1.016 1.016)
					(thickness 0.1524)
				)
			)
		)
		(property "Device Type" "C402H22"
			(at 1.1811 -4.2291 180)
			(unlocked yes)
			(layer "F.Fab")
			(hide yes)
			(effects
				(font
					(size 1.016 1.016)
					(thickness 0.1524)
				)
			)
		)
		(duplicate_pad_numbers_are_jumpers no)
		(fp_rect
			(start -0.4318 0.9525)
			(end 0.4318 -0.9525)
			(stroke
				(width 0)
				(type default)
			)
			(fill no)
			(layer "F.CrtYd")
		)
		(fp_rect
			(start -0.4318 0.9525)
			(end 0.4318 -0.9525)
			(stroke
				(width 0)
				(type default)
			)
			(fill no)
			(layer "F.Fab")
		)
		(pad "1" smd custom
			(at 0 -0.4445 180)
			(size 0.1524 0.1524)
			(layers "F.Cu" "F.Mask" "F.Paste")
			(net "P1V8_E")
			(options
				(clearance outline)
				(anchor circle)
			)
			(primitives
				(gr_poly
					(pts
						(arc
							(start 0.3048 -0.2032)
							(mid 0.275042 -0.275042)
							(end 0.2032 -0.3048)
						)
						(arc
							(start -0.2032 -0.3048)
							(mid -0.275042 -0.275042)
							(end -0.3048 -0.2032)
						)
						(arc
							(start -0.3048 0.2032)
							(mid -0.275042 0.275042)
							(end -0.2032 0.3048)
						)
						(arc
							(start 0.2032 0.3048)
							(mid 0.275042 0.275042)
							(end 0.3048 0.2032)
						)
					)
					(width 0)
					(fill yes)
				)
			)
		)
		(pad "2" smd custom
			(at 0 0.4445 180)
			(size 0.1524 0.1524)
			(layers "F.Cu" "F.Mask" "F.Paste")
			(net "GND")
			(options
				(clearance outline)
				(anchor circle)
			)
			(primitives
				(gr_poly
					(pts
						(arc
							(start 0.3048 -0.2032)
							(mid 0.275042 -0.275042)
							(end 0.2032 -0.3048)
						)
						(arc
							(start -0.2032 -0.3048)
							(mid -0.275042 -0.275042)
							(end -0.3048 -0.2032)
						)
						(arc
							(start -0.3048 0.2032)
							(mid -0.275042 0.275042)
							(end -0.2032 0.3048)
						)
						(arc
							(start 0.2032 0.3048)
							(mid 0.275042 0.275042)
							(end 0.3048 0.2032)
						)
					)
					(width 0)
					(fill yes)
				)
			)
		)
	)
	(footprint ""
		(layer "F.Cu")
		(at 152.253442 -90.609166 -90)
		(property "Reference" "R290"
			(at 0 0 270)
			(layer "F.SilkS")
			(hide yes)
			(effects
				(font
					(size 1.27 1.27)
				)
			)
		)
		(property "Value" "0R2J-2-GP"
			(at 0.064008 -3.993896 270)
			(unlocked yes)
			(layer "F.Fab")
			(hide yes)
			(effects
				(font
					(size 1.016 1.016)
					(thickness 0.1524)
				)
			)
		)
		(property "Device Type" "R402H16"
			(at 0.064008 -5.517896 270)
			(unlocked yes)
			(layer "F.Fab")
			(hide yes)
			(effects
				(font
					(size 1.016 1.016)
					(thickness 0.1524)
				)
			)
		)
		(duplicate_pad_numbers_are_jumpers no)
		(fp_line
			(start -0.508 -0.9398)
			(end -0.508 0.9398)
			(stroke
				(width 0.1524)
				(type default)
			)
			(layer "F.SilkS")
		)
		(fp_line
			(start 0.508 -0.9398)
			(end -0.508 -0.9398)
			(stroke
				(width 0.1524)
				(type default)
			)
			(layer "F.SilkS")
		)
		(fp_rect
			(start -0.508 0.9398)
			(end 0.508 -0.9398)
			(stroke
				(width 0)
				(type default)
			)
			(fill no)
			(layer "F.CrtYd")
		)
		(fp_rect
			(start -0.508 0.9398)
			(end 0.508 -0.9398)
			(stroke
				(width 0)
				(type default)
			)
			(fill no)
			(layer "F.Fab")
		)
		(pad "1" smd custom
			(at 0 -0.4445 270)
			(size 0.1397 0.1397)
			(layers "F.Cu" "F.Mask" "F.Paste")
			(net "SAS_SMART_R_RX")
			(options
				(clearance outline)
				(anchor circle)
			)
			(primitives
				(gr_poly
					(pts
						(arc
							(start -0.1778 -0.2794)
							(mid -0.249642 -0.249642)
							(end -0.2794 -0.1778)
						)
						(arc
							(start -0.2794 0.1778)
							(mid -0.249642 0.249642)
							(end -0.1778 0.2794)
						)
						(arc
							(start 0.1778 0.2794)
							(mid 0.249642 0.249642)
							(end 0.2794 0.1778)
						)
						(arc
							(start 0.2794 -0.1778)
							(mid 0.249642 -0.249642)
							(end 0.1778 -0.2794)
						)
					)
					(width 0)
					(fill yes)
				)
			)
		)
		(pad "2" smd custom
			(at 0 0.4445 270)
			(size 0.1397 0.1397)
			(layers "F.Cu" "F.Mask" "F.Paste")
			(net "SAS_SMART_RX")
			(options
				(clearance outline)
				(anchor circle)
			)
			(primitives
				(gr_poly
					(pts
						(arc
							(start -0.1778 -0.2794)
							(mid -0.249642 -0.249642)
							(end -0.2794 -0.1778)
						)
						(arc
							(start -0.2794 0.1778)
							(mid -0.249642 0.249642)
							(end -0.1778 0.2794)
						)
						(arc
							(start 0.1778 0.2794)
							(mid 0.249642 0.249642)
							(end 0.2794 0.1778)
						)
						(arc
							(start 0.2794 -0.1778)
							(mid 0.249642 -0.249642)
							(end 0.1778 -0.2794)
						)
					)
					(width 0)
					(fill yes)
				)
			)
		)
	)
	(footprint ""
		(layer "F.Cu")
		(at 145.68678 -117.34292 180)
		(property "Reference" "R378"
			(at 0 0 180)
			(layer "F.SilkS")
			(hide yes)
			(effects
				(font
					(size 1.27 1.27)
				)
			)
		)
		(property "Value" "1K5R2F-2-GP"
			(at 0.064008 -3.993896 180)
			(unlocked yes)
			(layer "F.Fab")
			(hide yes)
			(effects
				(font
					(size 1.016 1.016)
					(thickness 0.1524)
				)
			)
		)
		(property "Device Type" "R402H16"
			(at 0.064008 -5.517896 180)
			(unlocked yes)
			(layer "F.Fab")
			(hide yes)
			(effects
				(font
					(size 1.016 1.016)
					(thickness 0.1524)
				)
			)
		)
		(duplicate_pad_numbers_are_jumpers no)
		(fp_line
			(start 0.508 -0.9398)
			(end -0.508 -0.9398)
			(stroke
				(width 0.1524)
				(type default)
			)
			(layer "F.SilkS")
		)
		(fp_line
			(start -0.508 -0.9398)
			(end -0.508 0.9398)
			(stroke
				(width 0.1524)
				(type default)
			)
			(layer "F.SilkS")
		)
		(fp_rect
			(start -0.508 0.9398)
			(end 0.508 -0.9398)
			(stroke
				(width 0)
				(type default)
			)
			(fill no)
			(layer "F.CrtYd")
		)
		(fp_rect
			(start -0.508 0.9398)
			(end 0.508 -0.9398)
			(stroke
				(width 0)
				(type default)
			)
			(fill no)
			(layer "F.Fab")
		)
		(pad "1" smd custom
			(at 0 -0.4445 180)
			(size 0.1397 0.1397)
			(layers "F.Cu" "F.Mask" "F.Paste")
			(net "P1V5_E_LL")
			(options
				(clearance outline)
				(anchor circle)
			)
			(primitives
				(gr_poly
					(pts
						(arc
							(start -0.1778 -0.2794)
							(mid -0.249642 -0.249642)
							(end -0.2794 -0.1778)
						)
						(arc
							(start -0.2794 0.1778)
							(mid -0.249642 0.249642)
							(end -0.1778 0.2794)
						)
						(arc
							(start 0.1778 0.2794)
							(mid 0.249642 0.249642)
							(end 0.2794 0.1778)
						)
						(arc
							(start 0.2794 -0.1778)
							(mid 0.249642 -0.249642)
							(end 0.1778 -0.2794)
						)
					)
					(width 0)
					(fill yes)
				)
			)
		)
		(pad "2" smd custom
			(at 0 0.4445 180)
			(size 0.1397 0.1397)
			(layers "F.Cu" "F.Mask" "F.Paste")
			(net "P1V5_E_LL_R")
			(options
				(clearance outline)
				(anchor circle)
			)
			(primitives
				(gr_poly
					(pts
						(arc
							(start -0.1778 -0.2794)
							(mid -0.249642 -0.249642)
							(end -0.2794 -0.1778)
						)
						(arc
							(start -0.2794 0.1778)
							(mid -0.249642 0.249642)
							(end -0.1778 0.2794)
						)
						(arc
							(start 0.1778 0.2794)
							(mid 0.249642 0.249642)
							(end 0.2794 0.1778)
						)
						(arc
							(start 0.2794 -0.1778)
							(mid 0.249642 -0.249642)
							(end 0.1778 -0.2794)
						)
					)
					(width 0)
					(fill yes)
				)
			)
		)
	)
	(footprint ""
		(layer "F.Cu")
		(at 89.803224 -65.314322)
		(property "Reference" "TP164"
			(at 0 0 0)
			(layer "F.SilkS")
			(hide yes)
			(effects
				(font
					(size 1.27 1.27)
				)
			)
		)
		(property "Value" "TPAD28-2-GP"
			(at -0.0127 -1.6637 0)
			(unlocked yes)
			(layer "F.Fab")
			(hide yes)
			(effects
				(font
					(size 1.016 1.016)
					(thickness 0.1524)
				)
			)
		)
		(property "Device Type" "TPAD28"
			(at -0.0127 -3.1877 0)
			(unlocked yes)
			(layer "F.Fab")
			(hide yes)
			(effects
				(font
					(size 1.016 1.016)
					(thickness 0.1524)
				)
			)
		)
		(duplicate_pad_numbers_are_jumpers no)
		(fp_poly
			(pts
				(arc
					(start 0.3556 0)
					(mid -0.3556 0)
					(end 0.3556 0)
				)
			)
			(stroke
				(width 0)
				(type default)
			)
			(fill no)
			(layer "F.CrtYd")
		)
		(fp_poly
			(pts
				(arc
					(start 0.6096 0)
					(mid -0.6096 0)
					(end 0.6096 0)
				)
			)
			(stroke
				(width 0)
				(type default)
			)
			(fill no)
			(layer "F.Fab")
		)
		(pad "1" smd circle
			(at 0 0)
			(size 0.7112 0.7112)
			(layers "F.Cu" "F.Mask" "F.Paste")
			(net "LED47")
		)
	)
	(footprint ""
		(layer "F.Cu")
		(at 149.250908 -35.666934 -78)
		(property "Reference" "VIA18"
			(at 0 0 282)
			(layer "F.SilkS")
			(hide yes)
			(effects
				(font
					(size 1.27 1.27)
				)
			)
		)
		(property "Value" "100OHM-8L-1D6MM-L13-GP"
			(at 3.289333 0.050849 282)
			(unlocked yes)
			(layer "F.Fab")
			(hide yes)
			(effects
				(font
					(size 1.016 1.016)
					(thickness 0.1524)
				)
			)
		)
		(property "Device Type" "VIA-PCIE-4P-409091"
			(at 3.289207 -1.473208 282)
			(unlocked yes)
			(layer "F.Fab")
			(hide yes)
			(effects
				(font
					(size 1.016 1.016)
					(thickness 0.1524)
				)
			)
		)
		(duplicate_pad_numbers_are_jumpers no)
		(fp_poly
			(pts
				(xy -2.044719 -0.457296) (xy 2.04468 -0.457296) (xy 2.044681 0.457104) (xy -2.044719 0.457104)
			)
			(stroke
				(width 0)
				(type default)
			)
			(fill no)
			(layer "F.CrtYd")
		)
		(fp_poly
			(pts
				(xy -2.044719 -0.457296) (xy 2.04468 -0.457296) (xy 2.044681 0.457104) (xy -2.044719 0.457104)
			)
			(stroke
				(width 0)
				(type default)
			)
			(fill no)
			(layer "F.Fab")
		)
		(pad "1" thru_hole circle
			(at -1.5875 0 282)
			(size 0.508 0.508)
			(drill 0.254)
			(layers "*.Cu" "*.Mask")
			(remove_unused_layers no)
			(net "GND")
			(clearance 0.2032)
			(thermal_gap 0.2032)
		)
		(pad "2" thru_hole circle
			(at -0.5715 0.000001 282)
			(size 0.508 0.508)
			(drill 0.254)
			(layers "*.Cu" "*.Mask")
			(remove_unused_layers no)
			(net "PHY_SCC_TO_IOC_C_41_DP")
			(clearance 0.2032)
			(thermal_gap 0.2032)
		)
		(pad "3" thru_hole circle
			(at 0.5715 -0.000001 282)
			(size 0.508 0.508)
			(drill 0.254)
			(layers "*.Cu" "*.Mask")
			(remove_unused_layers no)
			(net "PHY_SCC_TO_IOC_C_41_DN")
			(clearance 0.2032)
			(thermal_gap 0.2032)
		)
		(pad "4" thru_hole circle
			(at 1.5875 0 282)
			(size 0.508 0.508)
			(drill 0.254)
			(layers "*.Cu" "*.Mask")
			(remove_unused_layers no)
			(net "GND")
			(clearance 0.2032)
			(thermal_gap 0.2032)
		)
	)
	(footprint ""
		(layer "F.Cu")
		(at 179.999894 -3.800094)
		(property "Reference" "CN6"
			(at 0 0 0)
			(layer "F.SilkS")
			(hide yes)
			(effects
				(font
					(size 1.27 1.27)
				)
			)
		)
		(property "Value" "AMP-CONN76-8R-7-GP"
			(at -11.755374 -18.361152 0)
			(unlocked yes)
			(layer "F.Fab")
			(hide yes)
			(effects
				(font
					(size 1.016 1.016)
					(thickness 0.1524)
				)
			)
		)
		(property "Device Type" "PREFIT-76P-144260H400"
			(at -11.755374 -19.885152 0)
			(unlocked yes)
			(layer "F.Fab")
			(hide yes)
			(effects
				(font
					(size 1.016 1.016)
					(thickness 0.1524)
				)
			)
		)
		(duplicate_pad_numbers_are_jumpers no)
		(fp_line
			(start -0.9398 -12.3444)
			(end 13.9446 -12.3444)
			(stroke
				(width 0.1524)
				(type default)
			)
			(layer "F.SilkS")
		)
		(fp_line
			(start -0.9398 3.800094)
			(end -0.9398 -12.3444)
			(stroke
				(width 0.1524)
				(type default)
			)
			(layer "F.SilkS")
		)
		(fp_line
			(start 13.9446 -12.3444)
			(end 13.9446 3.800094)
			(stroke
				(width 0.1524)
				(type default)
			)
			(layer "F.SilkS")
		)
		(fp_line
			(start 13.9446 3.800094)
			(end -0.9398 3.800094)
			(stroke
				(width 0.1524)
				(type default)
			)
			(layer "F.SilkS")
		)
		(fp_poly
			(pts
				(xy -0.9398 3.800094) (xy -0.9398 -12.3444) (xy 13.9446 -12.3444) (xy 13.9446 3.800094) (xy 13.234924 3.800094)
				(xy 13.234924 -10.335006) (xy 11.7348 -10.335006) (xy 11.7348 -11.7856) (xy 1.2192 -11.7856) (xy 1.2192 -10.335006)
				(xy -0.635 -10.335006) (xy -0.635 3.800094)
			)
			(stroke
				(width 0)
				(type default)
			)
			(fill yes)
			(layer "F.SilkS")
		)
		(fp_poly
			(pts
				(arc
					(start 0.1905 3.1369)
					(mid 0 2.9464)
					(end -0.1905 3.1369)
				)
				(arc
					(start -0.1905 3.5179)
					(mid 0 3.7084)
					(end 0.1905 3.5179)
				)
			)
			(stroke
				(width 0)
				(type default)
			)
			(fill yes)
			(layer "F.SilkS")
		)
		(fp_poly
			(pts
				(arc
					(start 1.990598 -10.0203)
					(mid 1.800098 -10.2108)
					(end 1.609598 -10.0203)
				)
				(arc
					(start 1.609598 -9.6393)
					(mid 1.800098 -9.4488)
					(end 1.990598 -9.6393)
				)
			)
			(stroke
				(width 0)
				(type default)
			)
			(fill yes)
			(layer "F.SilkS")
		)
		(fp_poly
			(pts
				(arc
					(start 3.790696 3.1369)
					(mid 3.600196 2.9464)
					(end 3.409696 3.1369)
				)
				(arc
					(start 3.409696 3.5179)
					(mid 3.600196 3.7084)
					(end 3.790696 3.5179)
				)
			)
			(stroke
				(width 0)
				(type default)
			)
			(fill yes)
			(layer "F.SilkS")
		)
		(fp_poly
			(pts
				(arc
					(start 5.590794 -10.0203)
					(mid 5.400294 -10.2108)
					(end 5.209794 -10.0203)
				)
				(arc
					(start 5.209794 -9.6393)
					(mid 5.400294 -9.4488)
					(end 5.590794 -9.6393)
				)
			)
			(stroke
				(width 0)
				(type default)
			)
			(fill yes)
			(layer "F.SilkS")
		)
		(fp_poly
			(pts
				(arc
					(start 7.390892 3.1369)
					(mid 7.200392 2.9464)
					(end 7.009892 3.1369)
				)
				(arc
					(start 7.009892 3.5179)
					(mid 7.200392 3.7084)
					(end 7.390892 3.5179)
				)
			)
			(stroke
				(width 0)
				(type default)
			)
			(fill yes)
			(layer "F.SilkS")
		)
		(fp_poly
			(pts
				(arc
					(start 9.19099 -10.0203)
					(mid 9.00049 -10.2108)
					(end 8.80999 -10.0203)
				)
				(arc
					(start 8.80999 -9.6393)
					(mid 9.00049 -9.4488)
					(end 9.19099 -9.6393)
				)
			)
			(stroke
				(width 0)
				(type default)
			)
			(fill yes)
			(layer "F.SilkS")
		)
		(fp_poly
			(pts
				(arc
					(start 10.991088 3.1369)
					(mid 10.800588 2.9464)
					(end 10.610088 3.1369)
				)
				(arc
					(start 10.610088 3.5179)
					(mid 10.800588 3.7084)
					(end 10.991088 3.5179)
				)
			)
			(stroke
				(width 0)
				(type default)
			)
			(fill yes)
			(layer "F.SilkS")
		)
		(fp_poly
			(pts
				(arc
					(start 12.791186 -10.0203)
					(mid 12.600686 -10.2108)
					(end 12.410186 -10.0203)
				)
				(arc
					(start 12.410186 -9.6393)
					(mid 12.600686 -9.4488)
					(end 12.791186 -9.6393)
				)
			)
			(stroke
				(width 0)
				(type default)
			)
			(fill yes)
			(layer "F.SilkS")
		)
		(fp_rect
			(start -5.3848 7.6962)
			(end 17.9832 -15.0876)
			(stroke
				(width 0)
				(type default)
			)
			(fill no)
			(layer "B.CrtYd")
		)
		(fp_rect
			(start -0.6858 13.8938)
			(end 13.6906 -12.0904)
			(stroke
				(width 0)
				(type default)
			)
			(fill no)
			(layer "F.CrtYd")
		)
		(fp_poly
			(pts
				(xy -5.6896 18.8976) (xy -5.6896 -17.0942) (xy 18.6944 -17.0942) (xy 18.6944 -0.00635) (xy 14.1986 -0.00635)
				(xy 14.1986 -12.5984) (xy -1.1938 -12.5984) (xy -1.1938 14.4018) (xy 14.1986 14.4018) (xy 14.1986 0.00635)
				(xy 18.6944 0.00635) (xy 18.6944 18.8976)
			)
			(stroke
				(width 0)
				(type default)
			)
			(fill no)
			(layer "F.CrtYd")
		)
		(fp_poly
			(pts
				(xy -1.1938 14.4018) (xy -1.1938 -12.5984) (xy 14.1986 -12.5984) (xy 14.1986 -0.00635) (xy 13.6906 -0.00635)
				(xy 13.6906 -12.0904) (xy -0.6858 -12.0904) (xy -0.6858 13.8938) (xy 13.6906 13.8938) (xy 13.6906 0.00635)
				(xy 14.1986 0.00635) (xy 14.1986 14.4018)
			)
			(stroke
				(width 0)
				(type default)
			)
			(fill no)
			(layer "F.CrtYd")
		)
		(fp_rect
			(start -10.3886 12.7)
			(end 22.987 -20.0914)
			(stroke
				(width 0)
				(type default)
			)
			(fill no)
			(layer "B.Fab")
		)
		(fp_rect
			(start -5.3848 7.6962)
			(end 17.9832 -15.0876)
			(stroke
				(width 0)
				(type default)
			)
			(fill no)
			(layer "B.Fab")
		)
		(fp_rect
			(start -10.6934 23.9014)
			(end 23.6982 -22.098)
			(stroke
				(width 0)
				(type default)
			)
			(fill no)
			(layer "F.Fab")
		)
		(fp_rect
			(start -5.6896 18.8976)
			(end 18.6944 -17.0942)
			(stroke
				(width 0)
				(type default)
			)
			(fill no)
			(layer "F.Fab")
		)
		(fp_rect
			(start -1.1938 14.4018)
			(end 14.1986 -12.5984)
			(stroke
				(width 0)
				(type default)
			)
			(fill no)
			(layer "F.Fab")
		)
		(fp_text user "Press Fit"
			(at 1.332484 -10.928604 0)
			(unlocked yes)
			(layer "F.SilkS")
			(effects
				(font
					(size 1.016 1.016)
					(thickness 0.1524)
				)
				(justify left)
			)
		)
		(fp_text user "Slit"
			(at 6.81736 5.89407 0)
			(unlocked yes)
			(layer "F.SilkS")
			(effects
				(font
					(size 1.016 1.016)
					(thickness 0.1524)
				)
				(justify left)
			)
		)
		(fp_text user "Can not place BGA,CSP,Wave Solder Component"
			(at -18.213578 10.752074 0)
			(unlocked yes)
			(layer "B.Fab")
			(effects
				(font
					(size 1.016 1.016)
					(thickness 0.1524)
				)
				(justify left)
			)
		)
		(fp_text user "Can not place BGA,CSP,Wave Solder Component"
			(at -16.541242 21.622512 0)
			(unlocked yes)
			(layer "F.Fab")
			(effects
				(font
					(size 1.016 1.016)
					(thickness 0.1524)
				)
				(justify left)
			)
		)
		(fp_text user "High Limit 2mm"
			(at -1.445768 16.781526 0)
			(unlocked yes)
			(layer "F.Fab")
			(effects
				(font
					(size 1.016 1.016)
					(thickness 0.1524)
				)
				(justify left)
			)
		)
		(pad "A1" thru_hole circle
			(at 0 0)
			(size 0.762 0.762)
			(drill 0.359918)
			(layers "*.Cu" "*.Mask")
			(remove_unused_layers no)
			(net "PCIE_COMP_TO_SCC_0_DP")
			(clearance 0.1651)
			(thermal_gap 0.1651)
		)
		(pad "A2" thru_hole circle
			(at 1.800098 1.199896)
			(size 0.762 0.762)
			(drill 0.359918)
			(layers "*.Cu" "*.Mask")
			(remove_unused_layers no)
			(net "PCIE_COMP_TO_SCC_1_DP")
			(clearance 0.1651)
			(thermal_gap 0.1651)
		)
		(pad "A3" thru_hole circle
			(at 3.599942 0)
			(size 0.762 0.762)
			(drill 0.359918)
			(layers "*.Cu" "*.Mask")
			(remove_unused_layers no)
			(net "PCIE_COMP_TO_SCC_2_DP")
			(clearance 0.1651)
			(thermal_gap 0.1651)
		)
		(pad "A4" thru_hole circle
			(at 5.40004 1.199896)
			(size 0.762 0.762)
			(drill 0.359918)
			(layers "*.Cu" "*.Mask")
			(remove_unused_layers no)
			(net "PCIE_COMP_TO_SCC_3_DP")
			(clearance 0.1651)
			(thermal_gap 0.1651)
		)
		(pad "A5" thru_hole circle
			(at 7.199884 0)
			(size 0.762 0.762)
			(drill 0.359918)
			(layers "*.Cu" "*.Mask")
			(remove_unused_layers no)
			(net "PCIE_COMP_TO_SCC_4_DP")
			(clearance 0.1651)
			(thermal_gap 0.1651)
		)
		(pad "A6" thru_hole circle
			(at 8.999982 1.199896)
			(size 0.762 0.762)
			(drill 0.359918)
			(layers "*.Cu" "*.Mask")
			(remove_unused_layers no)
			(net "PCIE_COMP_TO_SCC_5_DP")
			(clearance 0.1651)
			(thermal_gap 0.1651)
		)
		(pad "A7" thru_hole circle
			(at 10.80008 0)
			(size 0.762 0.762)
			(drill 0.359918)
			(layers "*.Cu" "*.Mask")
			(remove_unused_layers no)
			(net "PCIE_COMP_TO_SCC_6_DP")
			(clearance 0.1651)
			(thermal_gap 0.1651)
		)
		(pad "A8" thru_hole circle
			(at 12.599924 1.199896)
			(size 0.762 0.762)
			(drill 0.359918)
			(layers "*.Cu" "*.Mask")
			(remove_unused_layers no)
			(net "PCIE_COMP_TO_SCC_7_DP")
			(clearance 0.1651)
			(thermal_gap 0.1651)
		)
		(pad "B1" thru_hole circle
			(at 0 -1.400048)
			(size 0.762 0.762)
			(drill 0.359918)
			(layers "*.Cu" "*.Mask")
			(remove_unused_layers no)
			(net "PCIE_COMP_TO_SCC_0_DN")
			(clearance 0.1651)
			(thermal_gap 0.1651)
		)
		(pad "B2" thru_hole circle
			(at 1.800098 -0.199898)
			(size 0.762 0.762)
			(drill 0.359918)
			(layers "*.Cu" "*.Mask")
			(remove_unused_layers no)
			(net "PCIE_COMP_TO_SCC_1_DN")
			(clearance 0.1651)
			(thermal_gap 0.1651)
		)
		(pad "B3" thru_hole circle
			(at 3.599942 -1.400048)
			(size 0.762 0.762)
			(drill 0.359918)
			(layers "*.Cu" "*.Mask")
			(remove_unused_layers no)
			(net "PCIE_COMP_TO_SCC_2_DN")
			(clearance 0.1651)
			(thermal_gap 0.1651)
		)
		(pad "B4" thru_hole circle
			(at 5.40004 -0.199898)
			(size 0.762 0.762)
			(drill 0.359918)
			(layers "*.Cu" "*.Mask")
			(remove_unused_layers no)
			(net "PCIE_COMP_TO_SCC_3_DN")
			(clearance 0.1651)
			(thermal_gap 0.1651)
		)
		(pad "B5" thru_hole circle
			(at 7.199884 -1.400048)
			(size 0.762 0.762)
			(drill 0.359918)
			(layers "*.Cu" "*.Mask")
			(remove_unused_layers no)
			(net "PCIE_COMP_TO_SCC_4_DN")
			(clearance 0.1651)
			(thermal_gap 0.1651)
		)
		(pad "B6" thru_hole circle
			(at 8.999982 -0.199898)
			(size 0.762 0.762)
			(drill 0.359918)
			(layers "*.Cu" "*.Mask")
			(remove_unused_layers no)
			(net "PCIE_COMP_TO_SCC_5_DN")
			(clearance 0.1651)
			(thermal_gap 0.1651)
		)
		(pad "B7" thru_hole circle
			(at 10.80008 -1.400048)
			(size 0.762 0.762)
			(drill 0.359918)
			(layers "*.Cu" "*.Mask")
			(remove_unused_layers no)
			(net "PCIE_COMP_TO_SCC_6_DN")
			(clearance 0.1651)
			(thermal_gap 0.1651)
		)
		(pad "B8" thru_hole circle
			(at 12.599924 -0.199898)
			(size 0.762 0.762)
			(drill 0.359918)
			(layers "*.Cu" "*.Mask")
			(remove_unused_layers no)
			(net "PCIE_COMP_TO_SCC_7_DN")
			(clearance 0.1651)
			(thermal_gap 0.1651)
		)
		(pad "C1" thru_hole circle
			(at 0 -3.599942)
			(size 0.762 0.762)
			(drill 0.359918)
			(layers "*.Cu" "*.Mask")
			(remove_unused_layers no)
			(net "PCIE_COMP_TO_SCC_CLK_0_DP")
			(clearance 0.1651)
			(thermal_gap 0.1651)
		)
		(pad "C2" thru_hole circle
			(at 1.800098 -2.400046)
			(size 0.762 0.762)
			(drill 0.359918)
			(layers "*.Cu" "*.Mask")
			(remove_unused_layers no)
			(net "I2C_BMC_RMT_SCL1")
			(clearance 0.1651)
			(thermal_gap 0.1651)
		)
		(pad "C3" thru_hole circle
			(at 3.599942 -3.599942)
			(size 0.762 0.762)
			(drill 0.359918)
			(layers "*.Cu" "*.Mask")
			(remove_unused_layers no)
			(net "I2C_SCC_SCL2")
			(clearance 0.1651)
			(thermal_gap 0.1651)
		)
		(pad "C4" thru_hole circle
			(at 5.40004 -2.400046)
			(size 0.762 0.762)
			(drill 0.359918)
			(layers "*.Cu" "*.Mask")
			(remove_unused_layers no)
			(net "COMP_SPARE_0")
			(clearance 0.1651)
			(thermal_gap 0.1651)
		)
		(pad "C5" thru_hole circle
			(at 7.199884 -3.599942)
			(size 0.762 0.762)
			(drill 0.359918)
			(layers "*.Cu" "*.Mask")
			(remove_unused_layers no)
			(net "UART_IOC_TX")
			(clearance 0.1651)
			(thermal_gap 0.1651)
		)
		(pad "C6" thru_hole circle
			(at 8.999982 -2.400046)
			(size 0.762 0.762)
			(drill 0.359918)
			(layers "*.Cu" "*.Mask")
			(remove_unused_layers no)
			(net "BMC_SPARE_0")
			(clearance 0.1651)
			(thermal_gap 0.1651)
		)
		(pad "C7" thru_hole circle
			(at 10.80008 -3.599942)
			(size 0.762 0.762)
			(drill 0.359918)
			(layers "*.Cu" "*.Mask")
			(remove_unused_layers no)
			(net "PCIE_COMP_TO_SCC_RST_0")
			(clearance 0.1651)
			(thermal_gap 0.1651)
		)
		(pad "C8" thru_hole circle
			(at 12.599924 -2.400046)
			(size 0.762 0.762)
			(drill 0.359918)
			(layers "*.Cu" "*.Mask")
			(remove_unused_layers no)
			(net "I2C_BMC_LOC_SCL0")
			(clearance 0.1651)
			(thermal_gap 0.1651)
		)
		(pad "D1" thru_hole circle
			(at 0 -4.99999)
			(size 0.762 0.762)
			(drill 0.359918)
			(layers "*.Cu" "*.Mask")
			(remove_unused_layers no)
			(net "PCIE_COMP_TO_SCC_CLK_0_DN")
			(clearance 0.1651)
			(thermal_gap 0.1651)
		)
		(pad "D2" thru_hole circle
			(at 1.800098 -3.800094)
			(size 0.762 0.762)
			(drill 0.359918)
			(layers "*.Cu" "*.Mask")
			(remove_unused_layers no)
			(net "I2C_BMC_RMT_SDA1")
			(clearance 0.1651)
			(thermal_gap 0.1651)
		)
		(pad "D3" thru_hole circle
			(at 3.599942 -4.99999)
			(size 0.762 0.762)
			(drill 0.359918)
			(layers "*.Cu" "*.Mask")
			(remove_unused_layers no)
			(net "I2C_SCC_SDA2")
			(clearance 0.1651)
			(thermal_gap 0.1651)
		)
		(pad "D4" thru_hole circle
			(at 5.40004 -3.800094)
			(size 0.762 0.762)
			(drill 0.359918)
			(layers "*.Cu" "*.Mask")
			(remove_unused_layers no)
			(net "Net_4")
			(clearance 0.1651)
			(thermal_gap 0.1651)
		)
		(pad "D5" thru_hole circle
			(at 7.199884 -4.99999)
			(size 0.762 0.762)
			(drill 0.359918)
			(layers "*.Cu" "*.Mask")
			(remove_unused_layers no)
			(net "UART_IOC_RX")
			(clearance 0.1651)
			(thermal_gap 0.1651)
		)
		(pad "D6" thru_hole circle
			(at 8.999982 -3.800094)
			(size 0.762 0.762)
			(drill 0.359918)
			(layers "*.Cu" "*.Mask")
			(remove_unused_layers no)
			(net "BMC_SPARE_1")
			(clearance 0.1651)
			(thermal_gap 0.1651)
		)
		(pad "D7" thru_hole circle
			(at 10.80008 -4.99999)
			(size 0.762 0.762)
			(drill 0.359918)
			(layers "*.Cu" "*.Mask")
			(remove_unused_layers no)
			(net "BMC_RMT_HEARTBEAT")
			(clearance 0.1651)
			(thermal_gap 0.1651)
		)
		(pad "D8" thru_hole circle
			(at 12.599924 -3.800094)
			(size 0.762 0.762)
			(drill 0.359918)
			(layers "*.Cu" "*.Mask")
			(remove_unused_layers no)
			(net "I2C_BMC_LOC_SDA0")
			(clearance 0.1651)
			(thermal_gap 0.1651)
		)
		(pad "E1" thru_hole circle
			(at 0 -7.199884)
			(size 0.762 0.762)
			(drill 0.359918)
			(layers "*.Cu" "*.Mask")
			(remove_unused_layers no)
			(net "PCIE_SCC_TO_COMP_0_DP")
			(clearance 0.1651)
			(thermal_gap 0.1651)
		)
		(pad "E2" thru_hole circle
			(at 1.800098 -5.999988)
			(size 0.762 0.762)
			(drill 0.359918)
			(layers "*.Cu" "*.Mask")
			(remove_unused_layers no)
			(net "PCIE_SCC_TO_COMP_1_DP")
			(clearance 0.1651)
			(thermal_gap 0.1651)
		)
		(pad "E3" thru_hole circle
			(at 3.599942 -7.199884)
			(size 0.762 0.762)
			(drill 0.359918)
			(layers "*.Cu" "*.Mask")
			(remove_unused_layers no)
			(net "PCIE_SCC_TO_COMP_2_DP")
			(clearance 0.1651)
			(thermal_gap 0.1651)
		)
		(pad "E4" thru_hole circle
			(at 5.40004 -5.999988)
			(size 0.762 0.762)
			(drill 0.359918)
			(layers "*.Cu" "*.Mask")
			(remove_unused_layers no)
			(net "PCIE_SCC_TO_COMP_3_DP")
			(clearance 0.1651)
			(thermal_gap 0.1651)
		)
		(pad "E5" thru_hole circle
			(at 7.199884 -7.199884)
			(size 0.762 0.762)
			(drill 0.359918)
			(layers "*.Cu" "*.Mask")
			(remove_unused_layers no)
			(net "PCIE_SCC_TO_COMP_4_DP")
			(clearance 0.1651)
			(thermal_gap 0.1651)
		)
		(pad "E6" thru_hole circle
			(at 8.999982 -5.999988)
			(size 0.762 0.762)
			(drill 0.359918)
			(layers "*.Cu" "*.Mask")
			(remove_unused_layers no)
			(net "PCIE_SCC_TO_COMP_5_DP")
			(clearance 0.1651)
			(thermal_gap 0.1651)
		)
		(pad "E7" thru_hole circle
			(at 10.80008 -7.199884)
			(size 0.762 0.762)
			(drill 0.359918)
			(layers "*.Cu" "*.Mask")
			(remove_unused_layers no)
			(net "PCIE_SCC_TO_COMP_6_DP")
			(clearance 0.1651)
			(thermal_gap 0.1651)
		)
		(pad "E8" thru_hole circle
			(at 12.599924 -5.999988)
			(size 0.762 0.762)
			(drill 0.359918)
			(layers "*.Cu" "*.Mask")
			(remove_unused_layers no)
			(net "PCIE_SCC_TO_COMP_7_DP")
			(clearance 0.1651)
			(thermal_gap 0.1651)
		)
		(pad "F1" thru_hole circle
			(at 0 -8.599932)
			(size 0.762 0.762)
			(drill 0.359918)
			(layers "*.Cu" "*.Mask")
			(remove_unused_layers no)
			(net "PCIE_SCC_TO_COMP_0_DN")
			(clearance 0.1651)
			(thermal_gap 0.1651)
		)
		(pad "F2" thru_hole circle
			(at 1.800098 -7.400036)
			(size 0.762 0.762)
			(drill 0.359918)
			(layers "*.Cu" "*.Mask")
			(remove_unused_layers no)
			(net "PCIE_SCC_TO_COMP_1_DN")
			(clearance 0.1651)
			(thermal_gap 0.1651)
		)
		(pad "F3" thru_hole circle
			(at 3.599942 -8.599932)
			(size 0.762 0.762)
			(drill 0.359918)
			(layers "*.Cu" "*.Mask")
			(remove_unused_layers no)
			(net "PCIE_SCC_TO_COMP_2_DN")
			(clearance 0.1651)
			(thermal_gap 0.1651)
		)
		(pad "F4" thru_hole circle
			(at 5.40004 -7.400036)
			(size 0.762 0.762)
			(drill 0.359918)
			(layers "*.Cu" "*.Mask")
			(remove_unused_layers no)
			(net "PCIE_SCC_TO_COMP_3_DN")
			(clearance 0.1651)
			(thermal_gap 0.1651)
		)
		(pad "F5" thru_hole circle
			(at 7.199884 -8.599932)
			(size 0.762 0.762)
			(drill 0.359918)
			(layers "*.Cu" "*.Mask")
			(remove_unused_layers no)
			(net "PCIE_SCC_TO_COMP_4_DN")
			(clearance 0.1651)
			(thermal_gap 0.1651)
		)
		(pad "F6" thru_hole circle
			(at 8.999982 -7.400036)
			(size 0.762 0.762)
			(drill 0.359918)
			(layers "*.Cu" "*.Mask")
			(remove_unused_layers no)
			(net "PCIE_SCC_TO_COMP_5_DN")
			(clearance 0.1651)
			(thermal_gap 0.1651)
		)
		(pad "F7" thru_hole circle
			(at 10.80008 -8.599932)
			(size 0.762 0.762)
			(drill 0.359918)
			(layers "*.Cu" "*.Mask")
			(remove_unused_layers no)
			(net "PCIE_SCC_TO_COMP_6_DN")
			(clearance 0.1651)
			(thermal_gap 0.1651)
		)
		(pad "F8" thru_hole circle
			(at 12.599924 -7.400036)
			(size 0.762 0.762)
			(drill 0.359918)
			(layers "*.Cu" "*.Mask")
			(remove_unused_layers no)
			(net "PCIE_SCC_TO_COMP_7_DN")
			(clearance 0.1651)
			(thermal_gap 0.1651)
		)
		(pad "GND1" thru_hole circle
			(at 0 -2.500122)
			(size 0.762 0.762)
			(drill 0.359918)
			(layers "*.Cu" "*.Mask")
			(remove_unused_layers no)
			(net "GND")
			(clearance 0.1651)
			(thermal_gap 0.1651)
		)
		(pad "GND2" thru_hole circle
			(at 0 -6.100064)
			(size 0.762 0.762)
			(drill 0.359918)
			(layers "*.Cu" "*.Mask")
			(remove_unused_layers no)
			(net "GND")
			(clearance 0.1651)
			(thermal_gap 0.1651)
		)
		(pad "GND3" thru_hole circle
			(at 0 -9.700006)
			(size 0.762 0.762)
			(drill 0.359918)
			(layers "*.Cu" "*.Mask")
			(remove_unused_layers no)
			(net "GND")
			(clearance 0.1651)
			(thermal_gap 0.1651)
		)
		(pad "GND4" thru_hole circle
			(at 1.800098 2.29997)
			(size 0.762 0.762)
			(drill 0.359918)
			(layers "*.Cu" "*.Mask")
			(remove_unused_layers no)
			(net "GND")
			(clearance 0.1651)
			(thermal_gap 0.1651)
		)
		(pad "GND5" thru_hole circle
			(at 1.800098 -1.299972)
			(size 0.762 0.762)
			(drill 0.359918)
			(layers "*.Cu" "*.Mask")
			(remove_unused_layers no)
			(net "GND")
			(clearance 0.1651)
			(thermal_gap 0.1651)
		)
		(pad "GND6" thru_hole circle
			(at 1.800098 -4.899914)
			(size 0.762 0.762)
			(drill 0.359918)
			(layers "*.Cu" "*.Mask")
			(remove_unused_layers no)
			(net "GND")
			(clearance 0.1651)
			(thermal_gap 0.1651)
		)
		(pad "GND7" thru_hole circle
			(at 1.800098 -8.50011)
			(size 0.762 0.762)
			(drill 0.359918)
			(layers "*.Cu" "*.Mask")
			(remove_unused_layers no)
			(net "GND")
			(clearance 0.1651)
			(thermal_gap 0.1651)
		)
		(pad "GND8" thru_hole circle
			(at 3.599942 -2.500122)
			(size 0.762 0.762)
			(drill 0.359918)
			(layers "*.Cu" "*.Mask")
			(remove_unused_layers no)
			(net "GND")
			(clearance 0.1651)
			(thermal_gap 0.1651)
		)
		(pad "GND9" thru_hole circle
			(at 3.599942 -6.100064)
			(size 0.762 0.762)
			(drill 0.359918)
			(layers "*.Cu" "*.Mask")
			(remove_unused_layers no)
			(net "GND")
			(clearance 0.1651)
			(thermal_gap 0.1651)
		)
		(pad "GND10" thru_hole circle
			(at 3.599942 -9.700006)
			(size 0.762 0.762)
			(drill 0.359918)
			(layers "*.Cu" "*.Mask")
			(remove_unused_layers no)
			(net "GND")
			(clearance 0.1651)
			(thermal_gap 0.1651)
		)
		(pad "GND11" thru_hole circle
			(at 5.40004 2.29997)
			(size 0.762 0.762)
			(drill 0.359918)
			(layers "*.Cu" "*.Mask")
			(remove_unused_layers no)
			(net "GND")
			(clearance 0.1651)
			(thermal_gap 0.1651)
		)
		(pad "GND12" thru_hole circle
			(at 5.40004 -1.299972)
			(size 0.762 0.762)
			(drill 0.359918)
			(layers "*.Cu" "*.Mask")
			(remove_unused_layers no)
			(net "GND")
			(clearance 0.1651)
			(thermal_gap 0.1651)
		)
		(pad "GND13" thru_hole circle
			(at 5.40004 -4.899914)
			(size 0.762 0.762)
			(drill 0.359918)
			(layers "*.Cu" "*.Mask")
			(remove_unused_layers no)
			(net "GND")
			(clearance 0.1651)
			(thermal_gap 0.1651)
		)
		(pad "GND14" thru_hole circle
			(at 5.40004 -8.50011)
			(size 0.762 0.762)
			(drill 0.359918)
			(layers "*.Cu" "*.Mask")
			(remove_unused_layers no)
			(net "GND")
			(clearance 0.1651)
			(thermal_gap 0.1651)
		)
		(pad "GND15" thru_hole circle
			(at 7.199884 -2.500122)
			(size 0.762 0.762)
			(drill 0.359918)
			(layers "*.Cu" "*.Mask")
			(remove_unused_layers no)
			(net "GND")
			(clearance 0.1651)
			(thermal_gap 0.1651)
		)
		(pad "GND16" thru_hole circle
			(at 7.199884 -6.100064)
			(size 0.762 0.762)
			(drill 0.359918)
			(layers "*.Cu" "*.Mask")
			(remove_unused_layers no)
			(net "GND")
			(clearance 0.1651)
			(thermal_gap 0.1651)
		)
		(pad "GND17" thru_hole circle
			(at 7.199884 -9.700006)
			(size 0.762 0.762)
			(drill 0.359918)
			(layers "*.Cu" "*.Mask")
			(remove_unused_layers no)
			(net "GND")
			(clearance 0.1651)
			(thermal_gap 0.1651)
		)
		(pad "GND18" thru_hole circle
			(at 8.999982 2.29997)
			(size 0.762 0.762)
			(drill 0.359918)
			(layers "*.Cu" "*.Mask")
			(remove_unused_layers no)
			(net "GND")
			(clearance 0.1651)
			(thermal_gap 0.1651)
		)
		(pad "GND19" thru_hole circle
			(at 8.999982 -1.299972)
			(size 0.762 0.762)
			(drill 0.359918)
			(layers "*.Cu" "*.Mask")
			(remove_unused_layers no)
			(net "GND")
			(clearance 0.1651)
			(thermal_gap 0.1651)
		)
		(pad "GND20" thru_hole circle
			(at 8.999982 -4.899914)
			(size 0.762 0.762)
			(drill 0.359918)
			(layers "*.Cu" "*.Mask")
			(remove_unused_layers no)
			(net "GND")
			(clearance 0.1651)
			(thermal_gap 0.1651)
		)
		(pad "GND21" thru_hole circle
			(at 8.999982 -8.50011)
			(size 0.762 0.762)
			(drill 0.359918)
			(layers "*.Cu" "*.Mask")
			(remove_unused_layers no)
			(net "GND")
			(clearance 0.1651)
			(thermal_gap 0.1651)
		)
		(pad "GND22" thru_hole circle
			(at 10.80008 -2.500122)
			(size 0.762 0.762)
			(drill 0.359918)
			(layers "*.Cu" "*.Mask")
			(remove_unused_layers no)
			(net "GND")
			(clearance 0.1651)
			(thermal_gap 0.1651)
		)
		(pad "GND23" thru_hole circle
			(at 10.80008 -6.100064)
			(size 0.762 0.762)
			(drill 0.359918)
			(layers "*.Cu" "*.Mask")
			(remove_unused_layers no)
			(net "GND")
			(clearance 0.1651)
			(thermal_gap 0.1651)
		)
		(pad "GND24" thru_hole circle
			(at 10.80008 -9.700006)
			(size 0.762 0.762)
			(drill 0.359918)
			(layers "*.Cu" "*.Mask")
			(remove_unused_layers no)
			(net "GND")
			(clearance 0.1651)
			(thermal_gap 0.1651)
		)
		(pad "GND25" thru_hole circle
			(at 12.599924 2.29997)
			(size 0.762 0.762)
			(drill 0.359918)
			(layers "*.Cu" "*.Mask")
			(remove_unused_layers no)
			(net "GND")
			(clearance 0.1651)
			(thermal_gap 0.1651)
		)
		(pad "GND26" thru_hole circle
			(at 12.599924 -1.299972)
			(size 0.762 0.762)
			(drill 0.359918)
			(layers "*.Cu" "*.Mask")
			(remove_unused_layers no)
			(net "GND")
			(clearance 0.1651)
			(thermal_gap 0.1651)
		)
		(pad "GND27" thru_hole circle
			(at 12.599924 -4.899914)
			(size 0.762 0.762)
			(drill 0.359918)
			(layers "*.Cu" "*.Mask")
			(remove_unused_layers no)
			(net "GND")
			(clearance 0.1651)
			(thermal_gap 0.1651)
		)
		(pad "GND28" thru_hole circle
			(at 12.599924 -8.50011)
			(size 0.762 0.762)
			(drill 0.359918)
			(layers "*.Cu" "*.Mask")
			(remove_unused_layers no)
			(net "GND")
			(clearance 0.1651)
			(thermal_gap 0.1651)
		)
	)
	(footprint ""
		(layer "F.Cu")
		(at 180.436012 -24.040846 90)
		(property "Reference" "VIA8"
			(at 0 0 90)
			(layer "F.SilkS")
			(hide yes)
			(effects
				(font
					(size 1.27 1.27)
				)
			)
		)
		(property "Value" "85OHM-8L-1D6MM-L16L18-GP"
			(at 4.064 0.6096 90)
			(unlocked yes)
			(layer "F.Fab")
			(hide yes)
			(effects
				(font
					(size 1.016 1.016)
					(thickness 0.1524)
				)
			)
		)
		(property "Device Type" "VIA-PCIE-4P-368076"
			(at 4.064 -0.9144 90)
			(unlocked yes)
			(layer "F.Fab")
			(hide yes)
			(effects
				(font
					(size 1.016 1.016)
					(thickness 0.1524)
				)
			)
		)
		(duplicate_pad_numbers_are_jumpers no)
		(fp_rect
			(start -1.8415 0.381)
			(end 1.8415 -0.381)
			(stroke
				(width 0)
				(type default)
			)
			(fill no)
			(layer "F.CrtYd")
		)
		(fp_rect
			(start -1.8415 0.381)
			(end 1.8415 -0.381)
			(stroke
				(width 0)
				(type default)
			)
			(fill no)
			(layer "F.Fab")
		)
		(pad "1" thru_hole circle
			(at -1.4605 0 90)
			(size 0.508 0.508)
			(drill 0.254)
			(layers "*.Cu" "*.Mask")
			(remove_unused_layers no)
			(net "GND")
			(clearance 0.127)
			(thermal_gap 0.127)
		)
		(pad "2" thru_hole circle
			(at -0.4445 0 90)
			(size 0.508 0.508)
			(drill 0.254)
			(layers "*.Cu" "*.Mask")
			(remove_unused_layers no)
			(net "PCIE_COMP_TO_SCC_7_DP")
			(clearance 0.127)
			(thermal_gap 0.127)
		)
		(pad "3" thru_hole circle
			(at 0.4445 0 90)
			(size 0.508 0.508)
			(drill 0.254)
			(layers "*.Cu" "*.Mask")
			(remove_unused_layers no)
			(net "PCIE_COMP_TO_SCC_7_DN")
			(clearance 0.127)
			(thermal_gap 0.127)
		)
		(pad "4" thru_hole circle
			(at 1.4605 0 90)
			(size 0.508 0.508)
			(drill 0.254)
			(layers "*.Cu" "*.Mask")
			(remove_unused_layers no)
			(net "GND")
			(clearance 0.127)
			(thermal_gap 0.127)
		)
	)
	(footprint ""
		(layer "F.Cu")
		(at 136.181592 -77.830934 90)
		(property "Reference" "C681"
			(at 0 0 90)
			(layer "F.SilkS")
			(hide yes)
			(effects
				(font
					(size 1.27 1.27)
				)
			)
		)
		(property "Value" "SCD01U16V1KX-GP"
			(at -2.8321 -1.7399 90)
			(unlocked yes)
			(layer "F.Fab")
			(hide yes)
			(effects
				(font
					(size 1.016 1.016)
					(thickness 0.1524)
				)
			)
		)
		(property "Device Type" "C0201H13"
			(at -2.8321 -3.2639 90)
			(unlocked yes)
			(layer "F.Fab")
			(hide yes)
			(effects
				(font
					(size 1.016 1.016)
					(thickness 0.1524)
				)
			)
		)
		(duplicate_pad_numbers_are_jumpers no)
		(fp_rect
			(start -0.2794 0.6477)
			(end 0.2794 -0.6477)
			(stroke
				(width 0)
				(type default)
			)
			(fill no)
			(layer "F.CrtYd")
		)
		(fp_rect
			(start -0.2794 0.6477)
			(end 0.2794 -0.6477)
			(stroke
				(width 0)
				(type default)
			)
			(fill no)
			(layer "F.Fab")
		)
		(pad "1" smd custom
			(at 0 -0.2794 90)
			(size 0.0762 0.0762)
			(layers "F.Cu" "F.Mask" "F.Paste")
			(net "PHY_EXP_TO_CONN_C_9_DN")
			(options
				(clearance outline)
				(anchor circle)
			)
			(primitives
				(gr_poly
					(pts
						(arc
							(start 0.1524 -0.127)
							(mid 0.137521 -0.162921)
							(end 0.1016 -0.1778)
						)
						(arc
							(start -0.1016 -0.1778)
							(mid -0.137521 -0.162921)
							(end -0.1524 -0.127)
						)
						(arc
							(start -0.1524 0.127)
							(mid -0.137521 0.162921)
							(end -0.1016 0.1778)
						)
						(arc
							(start 0.1016 0.1778)
							(mid 0.137521 0.162921)
							(end 0.1524 0.127)
						)
					)
					(width 0)
					(fill yes)
				)
			)
		)
		(pad "2" smd custom
			(at 0 0.2794 90)
			(size 0.0762 0.0762)
			(layers "F.Cu" "F.Mask" "F.Paste")
			(net "PHY_EXP_TO_CONN_9_DN")
			(options
				(clearance outline)
				(anchor circle)
			)
			(primitives
				(gr_poly
					(pts
						(arc
							(start 0.1524 -0.127)
							(mid 0.137521 -0.162921)
							(end 0.1016 -0.1778)
						)
						(arc
							(start -0.1016 -0.1778)
							(mid -0.137521 -0.162921)
							(end -0.1524 -0.127)
						)
						(arc
							(start -0.1524 0.127)
							(mid -0.137521 0.162921)
							(end -0.1016 0.1778)
						)
						(arc
							(start 0.1016 0.1778)
							(mid 0.137521 0.162921)
							(end 0.1524 0.127)
						)
					)
					(width 0)
					(fill yes)
				)
			)
		)
	)
	(footprint ""
		(layer "F.Cu")
		(at 197.23608 -87.4522 180)
		(property "Reference" "DEBUG2"
			(at 0 0 180)
			(layer "F.SilkS")
			(hide yes)
			(effects
				(font
					(size 1.27 1.27)
				)
			)
		)
		(property "Value" "AMP-CONN4D-2-GP"
			(at -6.35 -0.254 180)
			(unlocked yes)
			(layer "F.Fab")
			(hide yes)
			(effects
				(font
					(size 1.016 1.016)
					(thickness 0.1524)
				)
			)
		)
		(property "Device Type" "G800MR304010HR"
			(at -6.35 -1.778 180)
			(unlocked yes)
			(layer "F.Fab")
			(hide yes)
			(effects
				(font
					(size 1.016 1.016)
					(thickness 0.1524)
				)
			)
		)
		(duplicate_pad_numbers_are_jumpers no)
		(fp_line
			(start 5.334 3.2512)
			(end 5.334 -3.2512)
			(stroke
				(width 0.1524)
				(type default)
			)
			(layer "F.SilkS")
		)
		(fp_line
			(start 5.334 -3.2512)
			(end -5.334 -3.2512)
			(stroke
				(width 0.1524)
				(type default)
			)
			(layer "F.SilkS")
		)
		(fp_line
			(start -4.2672 -3.3401)
			(end -3.2512 -3.3401)
			(stroke
				(width 0.3302)
				(type default)
			)
			(layer "F.SilkS")
		)
		(fp_line
			(start -5.334 3.2512)
			(end 5.334 3.2512)
			(stroke
				(width 0.1524)
				(type default)
			)
			(layer "F.SilkS")
		)
		(fp_line
			(start -5.334 -3.2512)
			(end -5.334 3.2512)
			(stroke
				(width 0.1524)
				(type default)
			)
			(layer "F.SilkS")
		)
		(fp_poly
			(pts
				(xy -3.81 -3.3274) (xy -3.175 -3.9624) (xy -4.445 -3.9624)
			)
			(stroke
				(width 0)
				(type default)
			)
			(fill yes)
			(layer "F.SilkS")
		)
		(fp_rect
			(start -5.08 2.4892)
			(end 5.08 -2.4892)
			(stroke
				(width 0)
				(type default)
			)
			(fill no)
			(layer "F.CrtYd")
		)
		(fp_poly
			(pts
				(xy 5.588 -2.4892) (xy -5.08 -2.4892) (xy -5.08 2.4892) (xy 5.08 2.4892) (xy 5.08 -2.4765) (xy 5.588 -2.4765)
				(xy 5.588 3.5052) (xy -5.588 3.5052) (xy -5.588 -3.5052) (xy 5.588 -3.5052)
			)
			(stroke
				(width 0)
				(type default)
			)
			(fill no)
			(layer "F.CrtYd")
		)
		(fp_rect
			(start -5.588 3.5052)
			(end 5.588 -3.5052)
			(stroke
				(width 0)
				(type default)
			)
			(fill no)
			(layer "F.Fab")
		)
		(pad "1" smd rect
			(at -3.81 -1.500124 180)
			(size 0.9906 2.9972)
			(layers "F.Cu" "F.Mask" "F.Paste")
			(net "SDB_CONN_PWR_3")
		)
		(pad "2" smd rect
			(at -1.27 1.500124 180)
			(size 0.9906 2.9972)
			(layers "F.Cu" "F.Mask" "F.Paste")
			(net "UART_IOC_TX")
		)
		(pad "3" smd rect
			(at 1.27 -1.500124 180)
			(size 0.9906 2.9972)
			(layers "F.Cu" "F.Mask" "F.Paste")
			(net "UART_IOC_RX")
		)
		(pad "4" smd rect
			(at 3.81 1.500124 180)
			(size 0.9906 2.9972)
			(layers "F.Cu" "F.Mask" "F.Paste")
			(net "GND")
		)
	)
	(footprint ""
		(layer "F.Cu")
		(at 158.369 -70.80123 90)
		(property "Reference" "R353"
			(at 0 0 90)
			(layer "F.SilkS")
			(hide yes)
			(effects
				(font
					(size 1.27 1.27)
				)
			)
		)
		(property "Value" "1KR2F-3-GP"
			(at 0.064008 -3.993896 90)
			(unlocked yes)
			(layer "F.Fab")
			(hide yes)
			(effects
				(font
					(size 1.016 1.016)
					(thickness 0.1524)
				)
			)
		)
		(property "Device Type" "R402H16"
			(at 0.064008 -5.517896 90)
			(unlocked yes)
			(layer "F.Fab")
			(hide yes)
			(effects
				(font
					(size 1.016 1.016)
					(thickness 0.1524)
				)
			)
		)
		(duplicate_pad_numbers_are_jumpers no)
		(fp_line
			(start 0.508 -0.9398)
			(end -0.508 -0.9398)
			(stroke
				(width 0.1524)
				(type default)
			)
			(layer "F.SilkS")
		)
		(fp_line
			(start -0.508 -0.9398)
			(end -0.508 0.9398)
			(stroke
				(width 0.1524)
				(type default)
			)
			(layer "F.SilkS")
		)
		(fp_rect
			(start -0.508 0.9398)
			(end 0.508 -0.9398)
			(stroke
				(width 0)
				(type default)
			)
			(fill no)
			(layer "F.CrtYd")
		)
		(fp_rect
			(start -0.508 0.9398)
			(end 0.508 -0.9398)
			(stroke
				(width 0)
				(type default)
			)
			(fill no)
			(layer "F.Fab")
		)
		(pad "1" smd custom
			(at 0 -0.4445 90)
			(size 0.1397 0.1397)
			(layers "F.Cu" "F.Mask" "F.Paste")
			(net "P1V5_C")
			(options
				(clearance outline)
				(anchor circle)
			)
			(primitives
				(gr_poly
					(pts
						(arc
							(start -0.1778 -0.2794)
							(mid -0.249642 -0.249642)
							(end -0.2794 -0.1778)
						)
						(arc
							(start -0.2794 0.1778)
							(mid -0.249642 0.249642)
							(end -0.1778 0.2794)
						)
						(arc
							(start 0.1778 0.2794)
							(mid 0.249642 0.249642)
							(end 0.2794 0.1778)
						)
						(arc
							(start 0.2794 -0.1778)
							(mid 0.249642 -0.249642)
							(end 0.1778 -0.2794)
						)
					)
					(width 0)
					(fill yes)
				)
			)
		)
		(pad "2" smd custom
			(at 0 0.4445 90)
			(size 0.1397 0.1397)
			(layers "F.Cu" "F.Mask" "F.Paste")
			(net "P1V5_C_SENSE")
			(options
				(clearance outline)
				(anchor circle)
			)
			(primitives
				(gr_poly
					(pts
						(arc
							(start -0.1778 -0.2794)
							(mid -0.249642 -0.249642)
							(end -0.2794 -0.1778)
						)
						(arc
							(start -0.2794 0.1778)
							(mid -0.249642 0.249642)
							(end -0.1778 0.2794)
						)
						(arc
							(start 0.1778 0.2794)
							(mid 0.249642 0.249642)
							(end 0.2794 0.1778)
						)
						(arc
							(start 0.2794 -0.1778)
							(mid 0.249642 -0.249642)
							(end 0.1778 -0.2794)
						)
					)
					(width 0)
					(fill yes)
				)
			)
		)
	)
	(footprint ""
		(layer "F.Cu")
		(at 184.42686 -113.64722 90)
		(property "Reference" "R606"
			(at 0 0 90)
			(layer "F.SilkS")
			(hide yes)
			(effects
				(font
					(size 1.27 1.27)
				)
			)
		)
		(property "Value" "10KR2F-2-GP"
			(at 0.064008 -3.993896 90)
			(unlocked yes)
			(layer "F.Fab")
			(hide yes)
			(effects
				(font
					(size 1.016 1.016)
					(thickness 0.1524)
				)
			)
		)
		(property "Device Type" "R402H16"
			(at 0.064008 -5.517896 90)
			(unlocked yes)
			(layer "F.Fab")
			(hide yes)
			(effects
				(font
					(size 1.016 1.016)
					(thickness 0.1524)
				)
			)
		)
		(duplicate_pad_numbers_are_jumpers no)
		(fp_line
			(start 0.508 -0.9398)
			(end -0.508 -0.9398)
			(stroke
				(width 0.1524)
				(type default)
			)
			(layer "F.SilkS")
		)
		(fp_line
			(start -0.508 -0.9398)
			(end -0.508 0.9398)
			(stroke
				(width 0.1524)
				(type default)
			)
			(layer "F.SilkS")
		)
		(fp_rect
			(start -0.508 0.9398)
			(end 0.508 -0.9398)
			(stroke
				(width 0)
				(type default)
			)
			(fill no)
			(layer "F.CrtYd")
		)
		(fp_rect
			(start -0.508 0.9398)
			(end 0.508 -0.9398)
			(stroke
				(width 0)
				(type default)
			)
			(fill no)
			(layer "F.Fab")
		)
		(pad "1" smd custom
			(at 0 -0.4445 90)
			(size 0.1397 0.1397)
			(layers "F.Cu" "F.Mask" "F.Paste")
			(net "P12V_STBY_Q12_G")
			(options
				(clearance outline)
				(anchor circle)
			)
			(primitives
				(gr_poly
					(pts
						(arc
							(start -0.1778 -0.2794)
							(mid -0.249642 -0.249642)
							(end -0.2794 -0.1778)
						)
						(arc
							(start -0.2794 0.1778)
							(mid -0.249642 0.249642)
							(end -0.1778 0.2794)
						)
						(arc
							(start 0.1778 0.2794)
							(mid 0.249642 0.249642)
							(end 0.2794 0.1778)
						)
						(arc
							(start 0.2794 -0.1778)
							(mid 0.249642 -0.249642)
							(end 0.1778 -0.2794)
						)
					)
					(width 0)
					(fill yes)
				)
			)
		)
		(pad "2" smd custom
			(at 0 0.4445 90)
			(size 0.1397 0.1397)
			(layers "F.Cu" "F.Mask" "F.Paste")
			(net "P12V_STBY_SCC")
			(options
				(clearance outline)
				(anchor circle)
			)
			(primitives
				(gr_poly
					(pts
						(arc
							(start -0.1778 -0.2794)
							(mid -0.249642 -0.249642)
							(end -0.2794 -0.1778)
						)
						(arc
							(start -0.2794 0.1778)
							(mid -0.249642 0.249642)
							(end -0.1778 0.2794)
						)
						(arc
							(start 0.1778 0.2794)
							(mid 0.249642 0.249642)
							(end 0.2794 0.1778)
						)
						(arc
							(start 0.2794 -0.1778)
							(mid 0.249642 -0.249642)
							(end 0.1778 -0.2794)
						)
					)
					(width 0)
					(fill yes)
				)
			)
		)
	)
	(footprint ""
		(layer "F.Cu")
		(at 6.5278 -99.1108)
		(property "Reference" "R572"
			(at 0 0 0)
			(layer "F.SilkS")
			(hide yes)
			(effects
				(font
					(size 1.27 1.27)
				)
			)
		)
		(property "Value" "0R2J-2-GP"
			(at 0.064008 -3.993896 0)
			(unlocked yes)
			(layer "F.Fab")
			(hide yes)
			(effects
				(font
					(size 1.016 1.016)
					(thickness 0.1524)
				)
			)
		)
		(property "Device Type" "R402H16"
			(at 0.064008 -5.517896 0)
			(unlocked yes)
			(layer "F.Fab")
			(hide yes)
			(effects
				(font
					(size 1.016 1.016)
					(thickness 0.1524)
				)
			)
		)
		(duplicate_pad_numbers_are_jumpers no)
		(fp_line
			(start -0.508 -0.9398)
			(end -0.508 0.9398)
			(stroke
				(width 0.1524)
				(type default)
			)
			(layer "F.SilkS")
		)
		(fp_line
			(start 0.508 -0.9398)
			(end -0.508 -0.9398)
			(stroke
				(width 0.1524)
				(type default)
			)
			(layer "F.SilkS")
		)
		(fp_rect
			(start -0.508 0.9398)
			(end 0.508 -0.9398)
			(stroke
				(width 0)
				(type default)
			)
			(fill no)
			(layer "F.CrtYd")
		)
		(fp_rect
			(start -0.508 0.9398)
			(end 0.508 -0.9398)
			(stroke
				(width 0)
				(type default)
			)
			(fill no)
			(layer "F.Fab")
		)
		(pad "1" smd custom
			(at 0 -0.4445)
			(size 0.1397 0.1397)
			(layers "F.Cu" "F.Mask" "F.Paste")
			(net "SCC_FULL_PGOOD_BUF_R")
			(options
				(clearance outline)
				(anchor circle)
			)
			(primitives
				(gr_poly
					(pts
						(arc
							(start -0.1778 -0.2794)
							(mid -0.249642 -0.249642)
							(end -0.2794 -0.1778)
						)
						(arc
							(start -0.2794 0.1778)
							(mid -0.249642 0.249642)
							(end -0.1778 0.2794)
						)
						(arc
							(start 0.1778 0.2794)
							(mid 0.249642 0.249642)
							(end 0.2794 0.1778)
						)
						(arc
							(start 0.2794 -0.1778)
							(mid 0.249642 -0.249642)
							(end 0.1778 -0.2794)
						)
					)
					(width 0)
					(fill yes)
				)
			)
		)
		(pad "2" smd custom
			(at 0 0.4445)
			(size 0.1397 0.1397)
			(layers "F.Cu" "F.Mask" "F.Paste")
			(net "SCC_FULL_PGOOD_BUF")
			(options
				(clearance outline)
				(anchor circle)
			)
			(primitives
				(gr_poly
					(pts
						(arc
							(start -0.1778 -0.2794)
							(mid -0.249642 -0.249642)
							(end -0.2794 -0.1778)
						)
						(arc
							(start -0.2794 0.1778)
							(mid -0.249642 0.249642)
							(end -0.1778 0.2794)
						)
						(arc
							(start 0.1778 0.2794)
							(mid 0.249642 0.249642)
							(end 0.2794 0.1778)
						)
						(arc
							(start 0.2794 -0.1778)
							(mid 0.249642 -0.249642)
							(end 0.1778 -0.2794)
						)
					)
					(width 0)
					(fill yes)
				)
			)
		)
	)
	(footprint ""
		(layer "F.Cu")
		(at 190.23838 -76.61148 90)
		(property "Reference" "R370"
			(at 0 0 90)
			(layer "F.SilkS")
			(hide yes)
			(effects
				(font
					(size 1.27 1.27)
				)
			)
		)
		(property "Value" "4K7R2F-GP"
			(at 0.064008 -3.993896 90)
			(unlocked yes)
			(layer "F.Fab")
			(hide yes)
			(effects
				(font
					(size 1.016 1.016)
					(thickness 0.1524)
				)
			)
		)
		(property "Device Type" "R402H16"
			(at 0.064008 -5.517896 90)
			(unlocked yes)
			(layer "F.Fab")
			(hide yes)
			(effects
				(font
					(size 1.016 1.016)
					(thickness 0.1524)
				)
			)
		)
		(duplicate_pad_numbers_are_jumpers no)
		(fp_line
			(start 0.508 -0.9398)
			(end -0.508 -0.9398)
			(stroke
				(width 0.1524)
				(type default)
			)
			(layer "F.SilkS")
		)
		(fp_line
			(start -0.508 -0.9398)
			(end -0.508 0.9398)
			(stroke
				(width 0.1524)
				(type default)
			)
			(layer "F.SilkS")
		)
		(fp_rect
			(start -0.508 0.9398)
			(end 0.508 -0.9398)
			(stroke
				(width 0)
				(type default)
			)
			(fill no)
			(layer "F.CrtYd")
		)
		(fp_rect
			(start -0.508 0.9398)
			(end 0.508 -0.9398)
			(stroke
				(width 0)
				(type default)
			)
			(fill no)
			(layer "F.Fab")
		)
		(pad "1" smd custom
			(at 0 -0.4445 90)
			(size 0.1397 0.1397)
			(layers "F.Cu" "F.Mask" "F.Paste")
			(net "TEMP2_A0")
			(options
				(clearance outline)
				(anchor circle)
			)
			(primitives
				(gr_poly
					(pts
						(arc
							(start -0.1778 -0.2794)
							(mid -0.249642 -0.249642)
							(end -0.2794 -0.1778)
						)
						(arc
							(start -0.2794 0.1778)
							(mid -0.249642 0.249642)
							(end -0.1778 0.2794)
						)
						(arc
							(start 0.1778 0.2794)
							(mid 0.249642 0.249642)
							(end 0.2794 0.1778)
						)
						(arc
							(start 0.2794 -0.1778)
							(mid 0.249642 -0.249642)
							(end 0.1778 -0.2794)
						)
					)
					(width 0)
					(fill yes)
				)
			)
		)
		(pad "2" smd custom
			(at 0 0.4445 90)
			(size 0.1397 0.1397)
			(layers "F.Cu" "F.Mask" "F.Paste")
			(net "GND")
			(options
				(clearance outline)
				(anchor circle)
			)
			(primitives
				(gr_poly
					(pts
						(arc
							(start -0.1778 -0.2794)
							(mid -0.249642 -0.249642)
							(end -0.2794 -0.1778)
						)
						(arc
							(start -0.2794 0.1778)
							(mid -0.249642 0.249642)
							(end -0.1778 0.2794)
						)
						(arc
							(start 0.1778 0.2794)
							(mid 0.249642 0.249642)
							(end 0.2794 0.1778)
						)
						(arc
							(start 0.2794 -0.1778)
							(mid 0.249642 -0.249642)
							(end 0.1778 -0.2794)
						)
					)
					(width 0)
					(fill yes)
				)
			)
		)
	)
	(footprint ""
		(layer "F.Cu")
		(at 202.30338 -78.00848 -90)
		(property "Reference" "R366"
			(at 0 0 270)
			(layer "F.SilkS")
			(hide yes)
			(effects
				(font
					(size 1.27 1.27)
				)
			)
		)
		(property "Value" "0R2J-2-GP"
			(at 0.064008 -3.993896 270)
			(unlocked yes)
			(layer "F.Fab")
			(hide yes)
			(effects
				(font
					(size 1.016 1.016)
					(thickness 0.1524)
				)
			)
		)
		(property "Device Type" "R402H16"
			(at 0.064008 -5.517896 270)
			(unlocked yes)
			(layer "F.Fab")
			(hide yes)
			(effects
				(font
					(size 1.016 1.016)
					(thickness 0.1524)
				)
			)
		)
		(duplicate_pad_numbers_are_jumpers no)
		(fp_line
			(start -0.508 -0.9398)
			(end -0.508 0.9398)
			(stroke
				(width 0.1524)
				(type default)
			)
			(layer "F.SilkS")
		)
		(fp_line
			(start 0.508 -0.9398)
			(end -0.508 -0.9398)
			(stroke
				(width 0.1524)
				(type default)
			)
			(layer "F.SilkS")
		)
		(fp_rect
			(start -0.508 0.9398)
			(end 0.508 -0.9398)
			(stroke
				(width 0)
				(type default)
			)
			(fill no)
			(layer "F.CrtYd")
		)
		(fp_rect
			(start -0.508 0.9398)
			(end 0.508 -0.9398)
			(stroke
				(width 0)
				(type default)
			)
			(fill no)
			(layer "F.Fab")
		)
		(pad "1" smd custom
			(at 0 -0.4445 270)
			(size 0.1397 0.1397)
			(layers "F.Cu" "F.Mask" "F.Paste")
			(net "I2C_SCC_SCL2")
			(options
				(clearance outline)
				(anchor circle)
			)
			(primitives
				(gr_poly
					(pts
						(arc
							(start -0.1778 -0.2794)
							(mid -0.249642 -0.249642)
							(end -0.2794 -0.1778)
						)
						(arc
							(start -0.2794 0.1778)
							(mid -0.249642 0.249642)
							(end -0.1778 0.2794)
						)
						(arc
							(start 0.1778 0.2794)
							(mid 0.249642 0.249642)
							(end 0.2794 0.1778)
						)
						(arc
							(start 0.2794 -0.1778)
							(mid 0.249642 -0.249642)
							(end 0.1778 -0.2794)
						)
					)
					(width 0)
					(fill yes)
				)
			)
		)
		(pad "2" smd custom
			(at 0 0.4445 270)
			(size 0.1397 0.1397)
			(layers "F.Cu" "F.Mask" "F.Paste")
			(net "TEMP2_SCL")
			(options
				(clearance outline)
				(anchor circle)
			)
			(primitives
				(gr_poly
					(pts
						(arc
							(start -0.1778 -0.2794)
							(mid -0.249642 -0.249642)
							(end -0.2794 -0.1778)
						)
						(arc
							(start -0.2794 0.1778)
							(mid -0.249642 0.249642)
							(end -0.1778 0.2794)
						)
						(arc
							(start 0.1778 0.2794)
							(mid 0.249642 0.249642)
							(end 0.2794 0.1778)
						)
						(arc
							(start 0.2794 -0.1778)
							(mid 0.249642 -0.249642)
							(end 0.1778 -0.2794)
						)
					)
					(width 0)
					(fill yes)
				)
			)
		)
	)
	(footprint ""
		(layer "F.Cu")
		(at 58.293 -18.542 90)
		(property "Reference" "R96"
			(at 0 0 90)
			(layer "F.SilkS")
			(hide yes)
			(effects
				(font
					(size 1.27 1.27)
				)
			)
		)
		(property "Value" "100KR2F-L1-GP"
			(at 0.064008 -3.993896 90)
			(unlocked yes)
			(layer "F.Fab")
			(hide yes)
			(effects
				(font
					(size 1.016 1.016)
					(thickness 0.1524)
				)
			)
		)
		(property "Device Type" "R402H16"
			(at 0.064008 -5.517896 90)
			(unlocked yes)
			(layer "F.Fab")
			(hide yes)
			(effects
				(font
					(size 1.016 1.016)
					(thickness 0.1524)
				)
			)
		)
		(duplicate_pad_numbers_are_jumpers no)
		(fp_line
			(start 0.508 -0.9398)
			(end -0.508 -0.9398)
			(stroke
				(width 0.1524)
				(type default)
			)
			(layer "F.SilkS")
		)
		(fp_line
			(start -0.508 -0.9398)
			(end -0.508 0.9398)
			(stroke
				(width 0.1524)
				(type default)
			)
			(layer "F.SilkS")
		)
		(fp_rect
			(start -0.508 0.9398)
			(end 0.508 -0.9398)
			(stroke
				(width 0)
				(type default)
			)
			(fill no)
			(layer "F.CrtYd")
		)
		(fp_rect
			(start -0.508 0.9398)
			(end 0.508 -0.9398)
			(stroke
				(width 0)
				(type default)
			)
			(fill no)
			(layer "F.Fab")
		)
		(pad "1" smd custom
			(at 0 -0.4445 90)
			(size 0.1397 0.1397)
			(layers "F.Cu" "F.Mask" "F.Paste")
			(net "SCC_STBY_PWR_EN")
			(options
				(clearance outline)
				(anchor circle)
			)
			(primitives
				(gr_poly
					(pts
						(arc
							(start -0.1778 -0.2794)
							(mid -0.249642 -0.249642)
							(end -0.2794 -0.1778)
						)
						(arc
							(start -0.2794 0.1778)
							(mid -0.249642 0.249642)
							(end -0.1778 0.2794)
						)
						(arc
							(start 0.1778 0.2794)
							(mid 0.249642 0.249642)
							(end 0.2794 0.1778)
						)
						(arc
							(start 0.2794 -0.1778)
							(mid 0.249642 -0.249642)
							(end 0.1778 -0.2794)
						)
					)
					(width 0)
					(fill yes)
				)
			)
		)
		(pad "2" smd custom
			(at 0 0.4445 90)
			(size 0.1397 0.1397)
			(layers "F.Cu" "F.Mask" "F.Paste")
			(net "GND")
			(options
				(clearance outline)
				(anchor circle)
			)
			(primitives
				(gr_poly
					(pts
						(arc
							(start -0.1778 -0.2794)
							(mid -0.249642 -0.249642)
							(end -0.2794 -0.1778)
						)
						(arc
							(start -0.2794 0.1778)
							(mid -0.249642 0.249642)
							(end -0.1778 0.2794)
						)
						(arc
							(start 0.1778 0.2794)
							(mid 0.249642 0.249642)
							(end 0.2794 0.1778)
						)
						(arc
							(start 0.2794 -0.1778)
							(mid 0.249642 -0.249642)
							(end 0.1778 -0.2794)
						)
					)
					(width 0)
					(fill yes)
				)
			)
		)
	)
	(footprint ""
		(layer "F.Cu")
		(at 51.535076 -53.33619 -90)
		(property "Reference" "C618"
			(at 0 0 270)
			(layer "F.SilkS")
			(hide yes)
			(effects
				(font
					(size 1.27 1.27)
				)
			)
		)
		(property "Value" "SC1KP50V2KX-1GP"
			(at 1.1811 -2.7051 270)
			(unlocked yes)
			(layer "F.Fab")
			(hide yes)
			(effects
				(font
					(size 1.016 1.016)
					(thickness 0.1524)
				)
			)
		)
		(property "Device Type" "C402H22"
			(at 1.1811 -4.2291 270)
			(unlocked yes)
			(layer "F.Fab")
			(hide yes)
			(effects
				(font
					(size 1.016 1.016)
					(thickness 0.1524)
				)
			)
		)
		(duplicate_pad_numbers_are_jumpers no)
		(fp_rect
			(start -0.4318 0.9525)
			(end 0.4318 -0.9525)
			(stroke
				(width 0)
				(type default)
			)
			(fill no)
			(layer "F.CrtYd")
		)
		(fp_rect
			(start -0.4318 0.9525)
			(end 0.4318 -0.9525)
			(stroke
				(width 0)
				(type default)
			)
			(fill no)
			(layer "F.Fab")
		)
		(pad "1" smd custom
			(at 0 -0.4445 270)
			(size 0.1524 0.1524)
			(layers "F.Cu" "F.Mask" "F.Paste")
			(net "P0V9_SNB")
			(options
				(clearance outline)
				(anchor circle)
			)
			(primitives
				(gr_poly
					(pts
						(arc
							(start 0.3048 -0.2032)
							(mid 0.275042 -0.275042)
							(end 0.2032 -0.3048)
						)
						(arc
							(start -0.2032 -0.3048)
							(mid -0.275042 -0.275042)
							(end -0.3048 -0.2032)
						)
						(arc
							(start -0.3048 0.2032)
							(mid -0.275042 0.275042)
							(end -0.2032 0.3048)
						)
						(arc
							(start 0.2032 0.3048)
							(mid 0.275042 0.275042)
							(end 0.3048 0.2032)
						)
					)
					(width 0)
					(fill yes)
				)
			)
		)
		(pad "2" smd custom
			(at 0 0.4445 270)
			(size 0.1524 0.1524)
			(layers "F.Cu" "F.Mask" "F.Paste")
			(net "GND")
			(options
				(clearance outline)
				(anchor circle)
			)
			(primitives
				(gr_poly
					(pts
						(arc
							(start 0.3048 -0.2032)
							(mid 0.275042 -0.275042)
							(end 0.2032 -0.3048)
						)
						(arc
							(start -0.2032 -0.3048)
							(mid -0.275042 -0.275042)
							(end -0.3048 -0.2032)
						)
						(arc
							(start -0.3048 0.2032)
							(mid -0.275042 0.275042)
							(end -0.2032 0.3048)
						)
						(arc
							(start 0.2032 0.3048)
							(mid 0.275042 0.275042)
							(end 0.3048 0.2032)
						)
					)
					(width 0)
					(fill yes)
				)
			)
		)
	)
	(footprint ""
		(layer "F.Cu")
		(at 191.85382 -51.2318 90)
		(property "Reference" "R228"
			(at 0 0 90)
			(layer "F.SilkS")
			(hide yes)
			(effects
				(font
					(size 1.27 1.27)
				)
			)
		)
		(property "Value" "10KR2F-2-GP"
			(at 0.064008 -3.993896 90)
			(unlocked yes)
			(layer "F.Fab")
			(hide yes)
			(effects
				(font
					(size 1.016 1.016)
					(thickness 0.1524)
				)
			)
		)
		(property "Device Type" "R402H16"
			(at 0.064008 -5.517896 90)
			(unlocked yes)
			(layer "F.Fab")
			(hide yes)
			(effects
				(font
					(size 1.016 1.016)
					(thickness 0.1524)
				)
			)
		)
		(duplicate_pad_numbers_are_jumpers no)
		(fp_line
			(start 0.508 -0.9398)
			(end -0.508 -0.9398)
			(stroke
				(width 0.1524)
				(type default)
			)
			(layer "F.SilkS")
		)
		(fp_line
			(start -0.508 -0.9398)
			(end -0.508 0.9398)
			(stroke
				(width 0.1524)
				(type default)
			)
			(layer "F.SilkS")
		)
		(fp_rect
			(start -0.508 0.9398)
			(end 0.508 -0.9398)
			(stroke
				(width 0)
				(type default)
			)
			(fill no)
			(layer "F.CrtYd")
		)
		(fp_rect
			(start -0.508 0.9398)
			(end 0.508 -0.9398)
			(stroke
				(width 0)
				(type default)
			)
			(fill no)
			(layer "F.Fab")
		)
		(pad "1" smd custom
			(at 0 -0.4445 90)
			(size 0.1397 0.1397)
			(layers "F.Cu" "F.Mask" "F.Paste")
			(net "XM_ADDR_11")
			(options
				(clearance outline)
				(anchor circle)
			)
			(primitives
				(gr_poly
					(pts
						(arc
							(start -0.1778 -0.2794)
							(mid -0.249642 -0.249642)
							(end -0.2794 -0.1778)
						)
						(arc
							(start -0.2794 0.1778)
							(mid -0.249642 0.249642)
							(end -0.1778 0.2794)
						)
						(arc
							(start 0.1778 0.2794)
							(mid 0.249642 0.249642)
							(end 0.2794 0.1778)
						)
						(arc
							(start 0.2794 -0.1778)
							(mid 0.249642 -0.249642)
							(end 0.1778 -0.2794)
						)
					)
					(width 0)
					(fill yes)
				)
			)
		)
		(pad "2" smd custom
			(at 0 0.4445 90)
			(size 0.1397 0.1397)
			(layers "F.Cu" "F.Mask" "F.Paste")
			(net "GND")
			(options
				(clearance outline)
				(anchor circle)
			)
			(primitives
				(gr_poly
					(pts
						(arc
							(start -0.1778 -0.2794)
							(mid -0.249642 -0.249642)
							(end -0.2794 -0.1778)
						)
						(arc
							(start -0.2794 0.1778)
							(mid -0.249642 0.249642)
							(end -0.1778 0.2794)
						)
						(arc
							(start 0.1778 0.2794)
							(mid 0.249642 0.249642)
							(end 0.2794 0.1778)
						)
						(arc
							(start 0.2794 -0.1778)
							(mid 0.249642 -0.249642)
							(end 0.1778 -0.2794)
						)
					)
					(width 0)
					(fill yes)
				)
			)
		)
	)
	(footprint ""
		(layer "F.Cu")
		(at 59.3344 -80.4926 90)
		(property "Reference" "C549"
			(at 0 0 90)
			(layer "F.SilkS")
			(hide yes)
			(effects
				(font
					(size 1.27 1.27)
				)
			)
		)
		(property "Value" "SCD1U16V2KX-3GP"
			(at 1.1811 -2.7051 90)
			(unlocked yes)
			(layer "F.Fab")
			(hide yes)
			(effects
				(font
					(size 1.016 1.016)
					(thickness 0.1524)
				)
			)
		)
		(property "Device Type" "C402H22"
			(at 1.1811 -4.2291 90)
			(unlocked yes)
			(layer "F.Fab")
			(hide yes)
			(effects
				(font
					(size 1.016 1.016)
					(thickness 0.1524)
				)
			)
		)
		(duplicate_pad_numbers_are_jumpers no)
		(fp_rect
			(start -0.4318 0.9525)
			(end 0.4318 -0.9525)
			(stroke
				(width 0)
				(type default)
			)
			(fill no)
			(layer "F.CrtYd")
		)
		(fp_rect
			(start -0.4318 0.9525)
			(end 0.4318 -0.9525)
			(stroke
				(width 0)
				(type default)
			)
			(fill no)
			(layer "F.Fab")
		)
		(pad "1" smd custom
			(at 0 -0.4445 90)
			(size 0.1524 0.1524)
			(layers "F.Cu" "F.Mask" "F.Paste")
			(net "P1V8_E")
			(options
				(clearance outline)
				(anchor circle)
			)
			(primitives
				(gr_poly
					(pts
						(arc
							(start 0.3048 -0.2032)
							(mid 0.275042 -0.275042)
							(end 0.2032 -0.3048)
						)
						(arc
							(start -0.2032 -0.3048)
							(mid -0.275042 -0.275042)
							(end -0.3048 -0.2032)
						)
						(arc
							(start -0.3048 0.2032)
							(mid -0.275042 0.275042)
							(end -0.2032 0.3048)
						)
						(arc
							(start 0.2032 0.3048)
							(mid 0.275042 0.275042)
							(end 0.3048 0.2032)
						)
					)
					(width 0)
					(fill yes)
				)
			)
		)
		(pad "2" smd custom
			(at 0 0.4445 90)
			(size 0.1524 0.1524)
			(layers "F.Cu" "F.Mask" "F.Paste")
			(net "GND")
			(options
				(clearance outline)
				(anchor circle)
			)
			(primitives
				(gr_poly
					(pts
						(arc
							(start 0.3048 -0.2032)
							(mid 0.275042 -0.275042)
							(end 0.2032 -0.3048)
						)
						(arc
							(start -0.2032 -0.3048)
							(mid -0.275042 -0.275042)
							(end -0.3048 -0.2032)
						)
						(arc
							(start -0.3048 0.2032)
							(mid -0.275042 0.275042)
							(end -0.2032 0.3048)
						)
						(arc
							(start 0.2032 0.3048)
							(mid 0.275042 0.275042)
							(end 0.3048 0.2032)
						)
					)
					(width 0)
					(fill yes)
				)
			)
		)
	)
	(footprint ""
		(layer "F.Cu")
		(at 154.84348 -92.65158 -90)
		(property "Reference" "U20"
			(at 0 0 270)
			(layer "F.SilkS")
			(hide yes)
			(effects
				(font
					(size 1.27 1.27)
				)
			)
		)
		(property "Value" "TXS0102DCUR-1-GP"
			(at 0 -11.1252 270)
			(unlocked yes)
			(layer "F.Fab")
			(hide yes)
			(effects
				(font
					(size 1.016 1.016)
					(thickness 0.1524)
				)
			)
		)
		(property "Device Type" "SSOIC8-4H36"
			(at 0 -12.6492 270)
			(unlocked yes)
			(layer "F.Fab")
			(hide yes)
			(effects
				(font
					(size 1.016 1.016)
					(thickness 0.1524)
				)
			)
		)
		(duplicate_pad_numbers_are_jumpers no)
		(fp_line
			(start -1.2573 2.1844)
			(end -1.2573 -2.1844)
			(stroke
				(width 0.1524)
				(type default)
			)
			(layer "F.SilkS")
		)
		(fp_line
			(start 1.2573 2.1844)
			(end -1.2573 2.1844)
			(stroke
				(width 0.1524)
				(type default)
			)
			(layer "F.SilkS")
		)
		(fp_line
			(start -1.2954 0.4572)
			(end -1.2954 2.159)
			(stroke
				(width 0.4064)
				(type default)
			)
			(layer "F.SilkS")
		)
		(fp_line
			(start -1.2065 0.2667)
			(end -1.27 0.2667)
			(stroke
				(width 0.1524)
				(type default)
			)
			(layer "F.SilkS")
		)
		(fp_line
			(start -0.9017 -0.0381)
			(end -1.2065 0.2667)
			(stroke
				(width 0.1524)
				(type default)
			)
			(layer "F.SilkS")
		)
		(fp_line
			(start -1.2573 -0.3556)
			(end -1.2192 -0.3556)
			(stroke
				(width 0.1524)
				(type default)
			)
			(layer "F.SilkS")
		)
		(fp_line
			(start -1.2192 -0.3556)
			(end -0.9017 -0.0381)
			(stroke
				(width 0.1524)
				(type default)
			)
			(layer "F.SilkS")
		)
		(fp_line
			(start -1.2573 -2.1844)
			(end 1.2573 -2.1844)
			(stroke
				(width 0.1524)
				(type default)
			)
			(layer "F.SilkS")
		)
		(fp_line
			(start 1.2573 -2.1844)
			(end 1.2573 2.1844)
			(stroke
				(width 0.1524)
				(type default)
			)
			(layer "F.SilkS")
		)
		(fp_poly
			(pts
				(xy -1.5113 2.4384) (xy 1.5113 2.4384) (xy 1.5113 -2.4384) (xy -1.5113 -2.4384)
			)
			(stroke
				(width 0)
				(type default)
			)
			(fill no)
			(layer "F.CrtYd")
		)
		(fp_poly
			(pts
				(xy -1.5113 -2.4384) (xy 1.5113 -2.4384) (xy 1.5113 2.4384) (xy -1.5113 2.4384)
			)
			(stroke
				(width 0)
				(type default)
			)
			(fill no)
			(layer "F.Fab")
		)
		(pad "1" smd rect
			(at -0.75057 1.1684 270)
			(size 0.3048 1.524)
			(layers "F.Cu" "F.Mask" "F.Paste")
			(net "EXP_SMART_RX_R")
		)
		(pad "2" smd rect
			(at -0.25019 1.1684 270)
			(size 0.3048 1.524)
			(layers "F.Cu" "F.Mask" "F.Paste")
			(net "GND")
		)
		(pad "3" smd rect
			(at 0.25019 1.1684 270)
			(size 0.3048 1.524)
			(layers "F.Cu" "F.Mask" "F.Paste")
			(net "P1V8_E")
		)
		(pad "4" smd rect
			(at 0.75057 1.1684 270)
			(size 0.3048 1.524)
			(layers "F.Cu" "F.Mask" "F.Paste")
			(net "SAS_SMART_R_RX")
		)
		(pad "5" smd rect
			(at 0.75057 -1.1684 270)
			(size 0.3048 1.524)
			(layers "F.Cu" "F.Mask" "F.Paste")
			(net "SAS_SMART_R_TX")
		)
		(pad "6" smd rect
			(at 0.25019 -1.1684 270)
			(size 0.3048 1.524)
			(layers "F.Cu" "F.Mask" "F.Paste")
			(net "SMART_UART_EN")
		)
		(pad "7" smd rect
			(at -0.25019 -1.1684 270)
			(size 0.3048 1.524)
			(layers "F.Cu" "F.Mask" "F.Paste")
			(net "P3V3")
		)
		(pad "8" smd rect
			(at -0.75057 -1.1684 270)
			(size 0.3048 1.524)
			(layers "F.Cu" "F.Mask" "F.Paste")
			(net "EXP_SMART_TX_R")
		)
	)
	(footprint ""
		(layer "F.Cu")
		(at 187.2234 -24.2824)
		(property "Reference" "TP130"
			(at 0 0 0)
			(layer "F.SilkS")
			(hide yes)
			(effects
				(font
					(size 1.27 1.27)
				)
			)
		)
		(property "Value" "TPAD28-2-GP"
			(at -0.0127 -1.6637 0)
			(unlocked yes)
			(layer "F.Fab")
			(hide yes)
			(effects
				(font
					(size 1.016 1.016)
					(thickness 0.1524)
				)
			)
		)
		(property "Device Type" "TPAD28"
			(at -0.0127 -3.1877 0)
			(unlocked yes)
			(layer "F.Fab")
			(hide yes)
			(effects
				(font
					(size 1.016 1.016)
					(thickness 0.1524)
				)
			)
		)
		(duplicate_pad_numbers_are_jumpers no)
		(fp_poly
			(pts
				(arc
					(start 0.3556 0)
					(mid -0.3556 0)
					(end 0.3556 0)
				)
			)
			(stroke
				(width 0)
				(type default)
			)
			(fill no)
			(layer "F.CrtYd")
		)
		(fp_poly
			(pts
				(arc
					(start 0.6096 0)
					(mid -0.6096 0)
					(end 0.6096 0)
				)
			)
			(stroke
				(width 0)
				(type default)
			)
			(fill no)
			(layer "F.Fab")
		)
		(pad "1" smd circle
			(at 0 0)
			(size 0.7112 0.7112)
			(layers "F.Cu" "F.Mask" "F.Paste")
			(net "SYS_HALT0#")
		)
	)
	(footprint ""
		(layer "F.Cu")
		(at 48.680878 -38.911784 90)
		(property "Reference" "R482"
			(at 0 0 90)
			(layer "F.SilkS")
			(hide yes)
			(effects
				(font
					(size 1.27 1.27)
				)
			)
		)
		(property "Value" "0R3J-0-U-GP"
			(at -0.0254 -2.5146 90)
			(unlocked yes)
			(layer "F.Fab")
			(hide yes)
			(effects
				(font
					(size 1.016 1.016)
					(thickness 0.1524)
				)
			)
		)
		(property "Device Type" "R603H22"
			(at -0.0254 -4.0386 90)
			(unlocked yes)
			(layer "F.Fab")
			(hide yes)
			(effects
				(font
					(size 1.016 1.016)
					(thickness 0.1524)
				)
			)
		)
		(duplicate_pad_numbers_are_jumpers no)
		(fp_line
			(start 0.2032 0)
			(end 0.4826 0)
			(stroke
				(width 0.2032)
				(type default)
			)
			(layer "F.SilkS")
		)
		(fp_line
			(start -0.4826 0)
			(end -0.2032 0)
			(stroke
				(width 0.2032)
				(type default)
			)
			(layer "F.SilkS")
		)
		(fp_rect
			(start -0.5842 1.3335)
			(end 0.5842 -1.3335)
			(stroke
				(width 0)
				(type default)
			)
			(fill no)
			(layer "F.CrtYd")
		)
		(fp_rect
			(start -0.5842 1.3335)
			(end 0.5842 -1.3335)
			(stroke
				(width 0)
				(type default)
			)
			(fill no)
			(layer "F.Fab")
		)
		(pad "1" smd custom
			(at 0 -0.762 90)
			(size 0.2159 0.2159)
			(layers "F.Cu" "F.Mask" "F.Paste")
			(net "P0V9_V5")
			(options
				(clearance outline)
				(anchor circle)
			)
			(primitives
				(gr_poly
					(pts
						(arc
							(start -0.3302 -0.4318)
							(mid -0.402042 -0.402042)
							(end -0.4318 -0.3302)
						)
						(arc
							(start -0.4318 0.3302)
							(mid -0.402042 0.402042)
							(end -0.3302 0.4318)
						)
						(arc
							(start 0.3302 0.4318)
							(mid 0.402042 0.402042)
							(end 0.4318 0.3302)
						)
						(arc
							(start 0.4318 -0.3302)
							(mid 0.402042 -0.402042)
							(end 0.3302 -0.4318)
						)
					)
					(width 0)
					(fill yes)
				)
			)
		)
		(pad "2" smd custom
			(at 0 0.762 90)
			(size 0.2159 0.2159)
			(layers "F.Cu" "F.Mask" "F.Paste")
			(net "P5V")
			(options
				(clearance outline)
				(anchor circle)
			)
			(primitives
				(gr_poly
					(pts
						(arc
							(start -0.3302 -0.4318)
							(mid -0.402042 -0.402042)
							(end -0.4318 -0.3302)
						)
						(arc
							(start -0.4318 0.3302)
							(mid -0.402042 0.402042)
							(end -0.3302 0.4318)
						)
						(arc
							(start 0.3302 0.4318)
							(mid 0.402042 0.402042)
							(end 0.4318 0.3302)
						)
						(arc
							(start 0.4318 -0.3302)
							(mid 0.402042 -0.402042)
							(end 0.3302 -0.4318)
						)
					)
					(width 0)
					(fill yes)
				)
			)
		)
	)
	(footprint ""
		(layer "F.Cu")
		(at 182.7022 -55.6768 180)
		(property "Reference" "R221"
			(at 0 0 180)
			(layer "F.SilkS")
			(hide yes)
			(effects
				(font
					(size 1.27 1.27)
				)
			)
		)
		(property "Value" "10KR2F-2-GP"
			(at 0.064008 -3.993896 180)
			(unlocked yes)
			(layer "F.Fab")
			(hide yes)
			(effects
				(font
					(size 1.016 1.016)
					(thickness 0.1524)
				)
			)
		)
		(property "Device Type" "R402H16"
			(at 0.064008 -5.517896 180)
			(unlocked yes)
			(layer "F.Fab")
			(hide yes)
			(effects
				(font
					(size 1.016 1.016)
					(thickness 0.1524)
				)
			)
		)
		(duplicate_pad_numbers_are_jumpers no)
		(fp_line
			(start 0.508 -0.9398)
			(end -0.508 -0.9398)
			(stroke
				(width 0.1524)
				(type default)
			)
			(layer "F.SilkS")
		)
		(fp_line
			(start -0.508 -0.9398)
			(end -0.508 0.9398)
			(stroke
				(width 0.1524)
				(type default)
			)
			(layer "F.SilkS")
		)
		(fp_rect
			(start -0.508 0.9398)
			(end 0.508 -0.9398)
			(stroke
				(width 0)
				(type default)
			)
			(fill no)
			(layer "F.CrtYd")
		)
		(fp_rect
			(start -0.508 0.9398)
			(end 0.508 -0.9398)
			(stroke
				(width 0)
				(type default)
			)
			(fill no)
			(layer "F.Fab")
		)
		(pad "1" smd custom
			(at 0 -0.4445 180)
			(size 0.1397 0.1397)
			(layers "F.Cu" "F.Mask" "F.Paste")
			(net "XM_ADDR_0")
			(options
				(clearance outline)
				(anchor circle)
			)
			(primitives
				(gr_poly
					(pts
						(arc
							(start -0.1778 -0.2794)
							(mid -0.249642 -0.249642)
							(end -0.2794 -0.1778)
						)
						(arc
							(start -0.2794 0.1778)
							(mid -0.249642 0.249642)
							(end -0.1778 0.2794)
						)
						(arc
							(start 0.1778 0.2794)
							(mid 0.249642 0.249642)
							(end 0.2794 0.1778)
						)
						(arc
							(start 0.2794 -0.1778)
							(mid 0.249642 -0.249642)
							(end 0.1778 -0.2794)
						)
					)
					(width 0)
					(fill yes)
				)
			)
		)
		(pad "2" smd custom
			(at 0 0.4445 180)
			(size 0.1397 0.1397)
			(layers "F.Cu" "F.Mask" "F.Paste")
			(net "GND")
			(options
				(clearance outline)
				(anchor circle)
			)
			(primitives
				(gr_poly
					(pts
						(arc
							(start -0.1778 -0.2794)
							(mid -0.249642 -0.249642)
							(end -0.2794 -0.1778)
						)
						(arc
							(start -0.2794 0.1778)
							(mid -0.249642 0.249642)
							(end -0.1778 0.2794)
						)
						(arc
							(start 0.1778 0.2794)
							(mid 0.249642 0.249642)
							(end 0.2794 0.1778)
						)
						(arc
							(start 0.2794 -0.1778)
							(mid 0.249642 -0.249642)
							(end 0.1778 -0.2794)
						)
					)
					(width 0)
					(fill yes)
				)
			)
		)
	)
	(footprint ""
		(layer "F.Cu")
		(at 155.74518 -76.019406 -90)
		(property "Reference" "U26"
			(at 0 0 270)
			(layer "F.SilkS")
			(hide yes)
			(effects
				(font
					(size 1.27 1.27)
				)
			)
		)
		(property "Value" "ADS1015IDGSR-GP"
			(at 0 -11.1252 270)
			(unlocked yes)
			(layer "F.Fab")
			(hide yes)
			(effects
				(font
					(size 1.016 1.016)
					(thickness 0.1524)
				)
			)
		)
		(property "Device Type" "MSOP10H44"
			(at 0 -12.6492 270)
			(unlocked yes)
			(layer "F.Fab")
			(hide yes)
			(effects
				(font
					(size 1.016 1.016)
					(thickness 0.1524)
				)
			)
		)
		(duplicate_pad_numbers_are_jumpers no)
		(fp_line
			(start -2.0066 1.016)
			(end -2.0066 -1.016)
			(stroke
				(width 0.1524)
				(type default)
			)
			(layer "F.SilkS")
		)
		(fp_line
			(start -1.8288 1.016)
			(end -1.8288 3.048)
			(stroke
				(width 0.508)
				(type default)
			)
			(layer "F.SilkS")
		)
		(fp_line
			(start 1.143 1.016)
			(end -2.0066 1.016)
			(stroke
				(width 0.1524)
				(type default)
			)
			(layer "F.SilkS")
		)
		(fp_line
			(start -1.5748 0)
			(end -1.9558 0.381)
			(stroke
				(width 0.1524)
				(type default)
			)
			(layer "F.SilkS")
		)
		(fp_line
			(start -1.5748 0)
			(end -1.9558 -0.381)
			(stroke
				(width 0.1524)
				(type default)
			)
			(layer "F.SilkS")
		)
		(fp_line
			(start -2.0066 -1.016)
			(end 1.143 -1.016)
			(stroke
				(width 0.1524)
				(type default)
			)
			(layer "F.SilkS")
		)
		(fp_line
			(start 1.143 -1.016)
			(end 1.143 1.016)
			(stroke
				(width 0.1524)
				(type default)
			)
			(layer "F.SilkS")
		)
		(fp_poly
			(pts
				(xy -2.0828 3.3401) (xy 2.0828 3.3401) (xy 2.0828 -3.3401) (xy -2.0828 -3.3401)
			)
			(stroke
				(width 0)
				(type default)
			)
			(fill no)
			(layer "F.CrtYd")
		)
		(fp_poly
			(pts
				(xy -2.0828 3.3401) (xy 2.0828 3.3401) (xy 2.0828 -3.3401) (xy -2.0828 -3.3401)
			)
			(stroke
				(width 0)
				(type default)
			)
			(fill no)
			(layer "F.Fab")
		)
		(pad "1" smd rect
			(at -0.99949 2.0701 270)
			(size 0.3048 1.524)
			(layers "F.Cu" "F.Mask" "F.Paste")
			(net "VOL_SEN2_ADDR")
		)
		(pad "2" smd rect
			(at -0.50038 2.0701 270)
			(size 0.3048 1.524)
			(layers "F.Cu" "F.Mask" "F.Paste")
			(net "VOL_SEN2_ALERT")
		)
		(pad "3" smd rect
			(at 0 2.0701 270)
			(size 0.3048 1.524)
			(layers "F.Cu" "F.Mask" "F.Paste")
			(net "GND")
		)
		(pad "4" smd rect
			(at 0.50038 2.0701 270)
			(size 0.3048 1.524)
			(layers "F.Cu" "F.Mask" "F.Paste")
			(net "Net_68")
		)
		(pad "5" smd rect
			(at 0.99949 2.0701 270)
			(size 0.3048 1.524)
			(layers "F.Cu" "F.Mask" "F.Paste")
			(net "P1V8_C_SENSE")
		)
		(pad "6" smd rect
			(at 0.99949 -2.0701 270)
			(size 0.3048 1.524)
			(layers "F.Cu" "F.Mask" "F.Paste")
			(net "P1V5_C_SENSE")
		)
		(pad "7" smd rect
			(at 0.50038 -2.0701 270)
			(size 0.3048 1.524)
			(layers "F.Cu" "F.Mask" "F.Paste")
			(net "P0V975_SENSE")
		)
		(pad "8" smd rect
			(at 0 -2.0701 270)
			(size 0.3048 1.524)
			(layers "F.Cu" "F.Mask" "F.Paste")
			(net "P3V3")
		)
		(pad "9" smd rect
			(at -0.50038 -2.0701 270)
			(size 0.3048 1.524)
			(layers "F.Cu" "F.Mask" "F.Paste")
			(net "VOL_SEN2_SDA")
		)
		(pad "10" smd rect
			(at -0.99949 -2.0701 270)
			(size 0.3048 1.524)
			(layers "F.Cu" "F.Mask" "F.Paste")
			(net "VOL_SEN2_SCL")
		)
	)
	(footprint ""
		(layer "F.Cu")
		(at 125.526546 -44.74718 180)
		(property "Reference" "C47"
			(at 0 0 180)
			(layer "F.SilkS")
			(hide yes)
			(effects
				(font
					(size 1.27 1.27)
				)
			)
		)
		(property "Value" "SCD01U16V1KX-GP"
			(at -2.8321 -1.7399 180)
			(unlocked yes)
			(layer "F.Fab")
			(hide yes)
			(effects
				(font
					(size 1.016 1.016)
					(thickness 0.1524)
				)
			)
		)
		(property "Device Type" "C0201H13"
			(at -2.8321 -3.2639 180)
			(unlocked yes)
			(layer "F.Fab")
			(hide yes)
			(effects
				(font
					(size 1.016 1.016)
					(thickness 0.1524)
				)
			)
		)
		(duplicate_pad_numbers_are_jumpers no)
		(fp_rect
			(start -0.2794 0.6477)
			(end 0.2794 -0.6477)
			(stroke
				(width 0)
				(type default)
			)
			(fill no)
			(layer "F.CrtYd")
		)
		(fp_rect
			(start -0.2794 0.6477)
			(end 0.2794 -0.6477)
			(stroke
				(width 0)
				(type default)
			)
			(fill no)
			(layer "F.Fab")
		)
		(pad "1" smd custom
			(at 0 -0.2794 180)
			(size 0.0762 0.0762)
			(layers "F.Cu" "F.Mask" "F.Paste")
			(net "PHY_IOC_TO_SCC_40_DP")
			(options
				(clearance outline)
				(anchor circle)
			)
			(primitives
				(gr_poly
					(pts
						(arc
							(start 0.1524 -0.127)
							(mid 0.137521 -0.162921)
							(end 0.1016 -0.1778)
						)
						(arc
							(start -0.1016 -0.1778)
							(mid -0.137521 -0.162921)
							(end -0.1524 -0.127)
						)
						(arc
							(start -0.1524 0.127)
							(mid -0.137521 0.162921)
							(end -0.1016 0.1778)
						)
						(arc
							(start 0.1016 0.1778)
							(mid 0.137521 0.162921)
							(end 0.1524 0.127)
						)
					)
					(width 0)
					(fill yes)
				)
			)
		)
		(pad "2" smd custom
			(at 0 0.2794 180)
			(size 0.0762 0.0762)
			(layers "F.Cu" "F.Mask" "F.Paste")
			(net "PHY_IOC_TO_SCC_C_40_DP")
			(options
				(clearance outline)
				(anchor circle)
			)
			(primitives
				(gr_poly
					(pts
						(arc
							(start 0.1524 -0.127)
							(mid 0.137521 -0.162921)
							(end 0.1016 -0.1778)
						)
						(arc
							(start -0.1016 -0.1778)
							(mid -0.137521 -0.162921)
							(end -0.1524 -0.127)
						)
						(arc
							(start -0.1524 0.127)
							(mid -0.137521 0.162921)
							(end -0.1016 0.1778)
						)
						(arc
							(start 0.1016 0.1778)
							(mid 0.137521 0.162921)
							(end 0.1524 0.127)
						)
					)
					(width 0)
					(fill yes)
				)
			)
		)
	)
	(footprint ""
		(layer "F.Cu")
		(at 10.9728 -67.5894 -90)
		(property "Reference" "R609"
			(at 0 0 270)
			(layer "F.SilkS")
			(hide yes)
			(effects
				(font
					(size 1.27 1.27)
				)
			)
		)
		(property "Value" "75KR2J-GP"
			(at 0.064008 -3.993896 270)
			(unlocked yes)
			(layer "F.Fab")
			(hide yes)
			(effects
				(font
					(size 1.016 1.016)
					(thickness 0.1524)
				)
			)
		)
		(property "Device Type" "R402H16"
			(at 0.064008 -5.517896 270)
			(unlocked yes)
			(layer "F.Fab")
			(hide yes)
			(effects
				(font
					(size 1.016 1.016)
					(thickness 0.1524)
				)
			)
		)
		(duplicate_pad_numbers_are_jumpers no)
		(fp_line
			(start -0.508 -0.9398)
			(end -0.508 0.9398)
			(stroke
				(width 0.1524)
				(type default)
			)
			(layer "F.SilkS")
		)
		(fp_line
			(start 0.508 -0.9398)
			(end -0.508 -0.9398)
			(stroke
				(width 0.1524)
				(type default)
			)
			(layer "F.SilkS")
		)
		(fp_rect
			(start -0.508 0.9398)
			(end 0.508 -0.9398)
			(stroke
				(width 0)
				(type default)
			)
			(fill no)
			(layer "F.CrtYd")
		)
		(fp_rect
			(start -0.508 0.9398)
			(end 0.508 -0.9398)
			(stroke
				(width 0)
				(type default)
			)
			(fill no)
			(layer "F.Fab")
		)
		(pad "1" smd custom
			(at 0 -0.4445 270)
			(size 0.1397 0.1397)
			(layers "F.Cu" "F.Mask" "F.Paste")
			(net "P12V_MAIN")
			(options
				(clearance outline)
				(anchor circle)
			)
			(primitives
				(gr_poly
					(pts
						(arc
							(start -0.1778 -0.2794)
							(mid -0.249642 -0.249642)
							(end -0.2794 -0.1778)
						)
						(arc
							(start -0.2794 0.1778)
							(mid -0.249642 0.249642)
							(end -0.1778 0.2794)
						)
						(arc
							(start 0.1778 0.2794)
							(mid 0.249642 0.249642)
							(end 0.2794 0.1778)
						)
						(arc
							(start 0.2794 -0.1778)
							(mid 0.249642 -0.249642)
							(end 0.1778 -0.2794)
						)
					)
					(width 0)
					(fill yes)
				)
			)
		)
		(pad "2" smd custom
			(at 0 0.4445 270)
			(size 0.1397 0.1397)
			(layers "F.Cu" "F.Mask" "F.Paste")
			(net "MB0_HS_ENABLE_R")
			(options
				(clearance outline)
				(anchor circle)
			)
			(primitives
				(gr_poly
					(pts
						(arc
							(start -0.1778 -0.2794)
							(mid -0.249642 -0.249642)
							(end -0.2794 -0.1778)
						)
						(arc
							(start -0.2794 0.1778)
							(mid -0.249642 0.249642)
							(end -0.1778 0.2794)
						)
						(arc
							(start 0.1778 0.2794)
							(mid 0.249642 0.249642)
							(end 0.2794 0.1778)
						)
						(arc
							(start 0.2794 -0.1778)
							(mid 0.249642 -0.249642)
							(end 0.1778 -0.2794)
						)
					)
					(width 0)
					(fill yes)
				)
			)
		)
	)
	(footprint ""
		(layer "F.Cu")
		(at 69.139308 -16.9291 90)
		(property "Reference" "U14"
			(at 0 0 90)
			(layer "F.SilkS")
			(hide yes)
			(effects
				(font
					(size 1.27 1.27)
				)
			)
		)
		(property "Value" "SNLVC8T245DGVR-GP"
			(at 0 -11.1252 90)
			(unlocked yes)
			(layer "F.Fab")
			(hide yes)
			(effects
				(font
					(size 1.016 1.016)
					(thickness 0.1524)
				)
			)
		)
		(property "Device Type" "TVSOP24H48"
			(at 0 -12.6492 90)
			(unlocked yes)
			(layer "F.Fab")
			(hide yes)
			(effects
				(font
					(size 1.016 1.016)
					(thickness 0.1524)
				)
			)
		)
		(duplicate_pad_numbers_are_jumpers no)
		(fp_line
			(start 2.2987 -1.397)
			(end -2.9337 -1.397)
			(stroke
				(width 0.1524)
				(type default)
			)
			(layer "F.SilkS")
		)
		(fp_line
			(start -2.9337 -1.397)
			(end -2.9337 1.397)
			(stroke
				(width 0.1524)
				(type default)
			)
			(layer "F.SilkS")
		)
		(fp_line
			(start -2.9337 -0.3683)
			(end -2.5654 0)
			(stroke
				(width 0.1524)
				(type default)
			)
			(layer "F.SilkS")
		)
		(fp_line
			(start -2.5654 0)
			(end -2.9337 0.3683)
			(stroke
				(width 0.1524)
				(type default)
			)
			(layer "F.SilkS")
		)
		(fp_line
			(start 2.2987 1.397)
			(end 2.2987 -1.397)
			(stroke
				(width 0.1524)
				(type default)
			)
			(layer "F.SilkS")
		)
		(fp_line
			(start -2.7559 1.397)
			(end -2.7559 3.8354)
			(stroke
				(width 0.508)
				(type default)
			)
			(layer "F.SilkS")
		)
		(fp_line
			(start -2.9337 1.397)
			(end 2.2987 1.397)
			(stroke
				(width 0.1524)
				(type default)
			)
			(layer "F.SilkS")
		)
		(fp_rect
			(start -3.0099 4.0894)
			(end 3.0099 -4.0894)
			(stroke
				(width 0)
				(type default)
			)
			(fill no)
			(layer "F.CrtYd")
		)
		(fp_poly
			(pts
				(xy -3.0099 -4.0894) (xy 3.0099 -4.0894) (xy 3.0099 4.0894) (xy -3.0099 4.0894)
			)
			(stroke
				(width 0)
				(type default)
			)
			(fill no)
			(layer "F.Fab")
		)
		(pad "1" smd rect
			(at -2.19964 2.8194 90)
			(size 0.2032 1.524)
			(layers "F.Cu" "F.Mask" "F.Paste")
			(net "P3V3")
		)
		(pad "2" smd rect
			(at -1.79959 2.8194 90)
			(size 0.2032 1.524)
			(layers "F.Cu" "F.Mask" "F.Paste")
			(net "GND")
		)
		(pad "3" smd rect
			(at -1.39954 2.8194 90)
			(size 0.2032 1.524)
			(layers "F.Cu" "F.Mask" "F.Paste")
			(net "SCC_LOC_HEARTBEAT")
		)
		(pad "4" smd rect
			(at -0.99949 2.8194 90)
			(size 0.2032 1.524)
			(layers "F.Cu" "F.Mask" "F.Paste")
			(net "PWM_OUT_ZONE_C")
		)
		(pad "5" smd rect
			(at -0.59944 2.8194 90)
			(size 0.2032 1.524)
			(layers "F.Cu" "F.Mask" "F.Paste")
			(net "PWM_OUT_ZONE_D")
		)
		(pad "6" smd rect
			(at -0.19939 2.8194 90)
			(size 0.2032 1.524)
			(layers "F.Cu" "F.Mask" "F.Paste")
			(net "SYS_PWR_LED_N")
		)
		(pad "7" smd rect
			(at 0.19939 2.8194 90)
			(size 0.2032 1.524)
			(layers "F.Cu" "F.Mask" "F.Paste")
			(net "ENCL_FAULT_LED")
		)
		(pad "8" smd rect
			(at 0.59944 2.8194 90)
			(size 0.2032 1.524)
			(layers "F.Cu" "F.Mask" "F.Paste")
			(net "BMC_SPARE_1")
		)
		(pad "9" smd rect
			(at 0.99949 2.8194 90)
			(size 0.2032 1.524)
			(layers "F.Cu" "F.Mask" "F.Paste")
			(net "Net_36")
		)
		(pad "10" smd rect
			(at 1.39954 2.8194 90)
			(size 0.2032 1.524)
			(layers "F.Cu" "F.Mask" "F.Paste")
			(net "Net_38")
		)
		(pad "11" smd rect
			(at 1.79959 2.8194 90)
			(size 0.2032 1.524)
			(layers "F.Cu" "F.Mask" "F.Paste")
			(net "GND")
		)
		(pad "12" smd rect
			(at 2.19964 2.8194 90)
			(size 0.2032 1.524)
			(layers "F.Cu" "F.Mask" "F.Paste")
			(net "GND")
		)
		(pad "13" smd rect
			(at 2.19964 -2.8194 90)
			(size 0.2032 1.524)
			(layers "F.Cu" "F.Mask" "F.Paste")
			(net "GND")
		)
		(pad "14" smd rect
			(at 1.79959 -2.8194 90)
			(size 0.2032 1.524)
			(layers "F.Cu" "F.Mask" "F.Paste")
			(net "Net_39")
		)
		(pad "15" smd rect
			(at 1.39954 -2.8194 90)
			(size 0.2032 1.524)
			(layers "F.Cu" "F.Mask" "F.Paste")
			(net "Net_37")
		)
		(pad "16" smd rect
			(at 0.99949 -2.8194 90)
			(size 0.2032 1.524)
			(layers "F.Cu" "F.Mask" "F.Paste")
			(net "BMC_SPARE_1_LS")
		)
		(pad "17" smd rect
			(at 0.59944 -2.8194 90)
			(size 0.2032 1.524)
			(layers "F.Cu" "F.Mask" "F.Paste")
			(net "ENCL_FAULT_LED_LS")
		)
		(pad "18" smd rect
			(at 0.19939 -2.8194 90)
			(size 0.2032 1.524)
			(layers "F.Cu" "F.Mask" "F.Paste")
			(net "SYS_PWR_LED_LS_N")
		)
		(pad "19" smd rect
			(at -0.19939 -2.8194 90)
			(size 0.2032 1.524)
			(layers "F.Cu" "F.Mask" "F.Paste")
			(net "PWM_OUT_ZONE_D_LS")
		)
		(pad "20" smd rect
			(at -0.59944 -2.8194 90)
			(size 0.2032 1.524)
			(layers "F.Cu" "F.Mask" "F.Paste")
			(net "PWM_OUT_ZONE_C_LS")
		)
		(pad "21" smd rect
			(at -0.99949 -2.8194 90)
			(size 0.2032 1.524)
			(layers "F.Cu" "F.Mask" "F.Paste")
			(net "SCC_LOC_HEARTBEAT_LS")
		)
		(pad "22" smd rect
			(at -1.39954 -2.8194 90)
			(size 0.2032 1.524)
			(layers "F.Cu" "F.Mask" "F.Paste")
			(net "LS_EN_U14")
		)
		(pad "23" smd rect
			(at -1.79959 -2.8194 90)
			(size 0.2032 1.524)
			(layers "F.Cu" "F.Mask" "F.Paste")
			(net "P1V8_E")
		)
		(pad "24" smd rect
			(at -2.19964 -2.8194 90)
			(size 0.2032 1.524)
			(layers "F.Cu" "F.Mask" "F.Paste")
			(net "P1V8_E")
		)
	)
	(footprint ""
		(layer "F.Cu")
		(at 170.955716 -108.891324)
		(property "Reference" "U9"
			(at 0 0 0)
			(layer "F.SilkS")
			(hide yes)
			(effects
				(font
					(size 1.27 1.27)
				)
			)
		)
		(property "Value" "SN74LVC1G07DCKR-GP"
			(at -2.3368 -8.6868 0)
			(unlocked yes)
			(layer "F.Fab")
			(hide yes)
			(effects
				(font
					(size 1.016 1.016)
					(thickness 0.1524)
				)
			)
		)
		(property "Device Type" "SC70-5H44"
			(at -2.3114 -10.414 0)
			(unlocked yes)
			(layer "F.Fab")
			(hide yes)
			(effects
				(font
					(size 1.016 1.016)
					(thickness 0.1524)
				)
			)
		)
		(duplicate_pad_numbers_are_jumpers no)
		(fp_line
			(start -1.27 -1.7018)
			(end 1.27 -1.7018)
			(stroke
				(width 0.1524)
				(type default)
			)
			(layer "F.SilkS")
		)
		(fp_line
			(start -1.27 1.7018)
			(end -1.27 -1.7018)
			(stroke
				(width 0.1524)
				(type default)
			)
			(layer "F.SilkS")
		)
		(fp_line
			(start 0.6604 -1.8034)
			(end 1.3843 -1.8034)
			(stroke
				(width 0.3302)
				(type default)
			)
			(layer "F.SilkS")
		)
		(fp_line
			(start 1.27 -1.7018)
			(end 1.27 1.7018)
			(stroke
				(width 0.1524)
				(type default)
			)
			(layer "F.SilkS")
		)
		(fp_line
			(start 1.27 1.7018)
			(end -1.27 1.7018)
			(stroke
				(width 0.1524)
				(type default)
			)
			(layer "F.SilkS")
		)
		(fp_line
			(start 1.3843 -1.8034)
			(end 1.3843 -1.1176)
			(stroke
				(width 0.3302)
				(type default)
			)
			(layer "F.SilkS")
		)
		(fp_rect
			(start -1.524 1.9558)
			(end 1.524 -1.9558)
			(stroke
				(width 0)
				(type default)
			)
			(fill no)
			(layer "F.CrtYd")
		)
		(fp_poly
			(pts
				(xy -1.524 -1.9558) (xy 1.524 -1.9558) (xy 1.524 1.9558) (xy -1.524 1.9558)
			)
			(stroke
				(width 0)
				(type default)
			)
			(fill no)
			(layer "F.Fab")
		)
		(pad "1" smd rect
			(at 0.65024 -0.8255)
			(size 0.4064 1.2192)
			(layers "F.Cu" "F.Mask" "F.Paste")
			(net "Net_48")
		)
		(pad "2" smd rect
			(at 0 -0.8255)
			(size 0.4064 1.2192)
			(layers "F.Cu" "F.Mask" "F.Paste")
			(net "P0V975_STAT")
		)
		(pad "3" smd rect
			(at -0.65024 -0.8255)
			(size 0.4064 1.2192)
			(layers "F.Cu" "F.Mask" "F.Paste")
			(net "GND")
		)
		(pad "4" smd rect
			(at -0.65024 0.8255)
			(size 0.4064 1.2192)
			(layers "F.Cu" "F.Mask" "F.Paste")
			(net "SCC_FULL_PGOOD_LS")
		)
		(pad "5" smd rect
			(at 0.65024 0.8255)
			(size 0.4064 1.2192)
			(layers "F.Cu" "F.Mask" "F.Paste")
			(net "P3V3")
		)
	)
	(footprint ""
		(layer "F.Cu")
		(at 10.1854 -100.584 90)
		(property "Reference" "U120"
			(at 0 0 90)
			(layer "F.SilkS")
			(hide yes)
			(effects
				(font
					(size 1.27 1.27)
				)
			)
		)
		(property "Value" "NX3L1G66GW-GP"
			(at -2.3368 -8.6868 90)
			(unlocked yes)
			(layer "F.Fab")
			(hide yes)
			(effects
				(font
					(size 1.016 1.016)
					(thickness 0.1524)
				)
			)
		)
		(property "Device Type" "SC70-5H44"
			(at -2.3114 -10.414 90)
			(unlocked yes)
			(layer "F.Fab")
			(hide yes)
			(effects
				(font
					(size 1.016 1.016)
					(thickness 0.1524)
				)
			)
		)
		(duplicate_pad_numbers_are_jumpers no)
		(fp_line
			(start 1.3843 -1.8034)
			(end 1.3843 -1.1176)
			(stroke
				(width 0.3302)
				(type default)
			)
			(layer "F.SilkS")
		)
		(fp_line
			(start 0.6604 -1.8034)
			(end 1.3843 -1.8034)
			(stroke
				(width 0.3302)
				(type default)
			)
			(layer "F.SilkS")
		)
		(fp_line
			(start 1.27 -1.7018)
			(end 1.27 1.7018)
			(stroke
				(width 0.1524)
				(type default)
			)
			(layer "F.SilkS")
		)
		(fp_line
			(start -1.27 -1.7018)
			(end 1.27 -1.7018)
			(stroke
				(width 0.1524)
				(type default)
			)
			(layer "F.SilkS")
		)
		(fp_line
			(start 1.27 1.7018)
			(end -1.27 1.7018)
			(stroke
				(width 0.1524)
				(type default)
			)
			(layer "F.SilkS")
		)
		(fp_line
			(start -1.27 1.7018)
			(end -1.27 -1.7018)
			(stroke
				(width 0.1524)
				(type default)
			)
			(layer "F.SilkS")
		)
		(fp_rect
			(start -1.524 1.9558)
			(end 1.524 -1.9558)
			(stroke
				(width 0)
				(type default)
			)
			(fill no)
			(layer "F.CrtYd")
		)
		(fp_poly
			(pts
				(xy -1.524 -1.9558) (xy 1.524 -1.9558) (xy 1.524 1.9558) (xy -1.524 1.9558)
			)
			(stroke
				(width 0)
				(type default)
			)
			(fill no)
			(layer "F.Fab")
		)
		(pad "1" smd rect
			(at 0.65024 -0.8255 90)
			(size 0.4064 1.2192)
			(layers "F.Cu" "F.Mask" "F.Paste")
			(net "SCC_FULL_PGOOD")
		)
		(pad "2" smd rect
			(at 0 -0.8255 90)
			(size 0.4064 1.2192)
			(layers "F.Cu" "F.Mask" "F.Paste")
			(net "SCC_FULL_PGOOD_BUF_R")
		)
		(pad "3" smd rect
			(at -0.65024 -0.8255 90)
			(size 0.4064 1.2192)
			(layers "F.Cu" "F.Mask" "F.Paste")
			(net "GND")
		)
		(pad "4" smd rect
			(at -0.65024 0.8255 90)
			(size 0.4064 1.2192)
			(layers "F.Cu" "F.Mask" "F.Paste")
			(net "U120_EN")
		)
		(pad "5" smd rect
			(at 0.65024 0.8255 90)
			(size 0.4064 1.2192)
			(layers "F.Cu" "F.Mask" "F.Paste")
			(net "P3V3")
		)
	)
	(footprint ""
		(layer "F.Cu")
		(at 97.536 -87.0585)
		(property "Reference" "R562"
			(at 0 0 0)
			(layer "F.SilkS")
			(hide yes)
			(effects
				(font
					(size 1.27 1.27)
				)
			)
		)
		(property "Value" "10KR2F-2-GP"
			(at 0.064008 -3.993896 0)
			(unlocked yes)
			(layer "F.Fab")
			(hide yes)
			(effects
				(font
					(size 1.016 1.016)
					(thickness 0.1524)
				)
			)
		)
		(property "Device Type" "R402H16"
			(at 0.064008 -5.517896 0)
			(unlocked yes)
			(layer "F.Fab")
			(hide yes)
			(effects
				(font
					(size 1.016 1.016)
					(thickness 0.1524)
				)
			)
		)
		(duplicate_pad_numbers_are_jumpers no)
		(fp_line
			(start -0.508 -0.9398)
			(end -0.508 0.9398)
			(stroke
				(width 0.1524)
				(type default)
			)
			(layer "F.SilkS")
		)
		(fp_line
			(start 0.508 -0.9398)
			(end -0.508 -0.9398)
			(stroke
				(width 0.1524)
				(type default)
			)
			(layer "F.SilkS")
		)
		(fp_rect
			(start -0.508 0.9398)
			(end 0.508 -0.9398)
			(stroke
				(width 0)
				(type default)
			)
			(fill no)
			(layer "F.CrtYd")
		)
		(fp_rect
			(start -0.508 0.9398)
			(end 0.508 -0.9398)
			(stroke
				(width 0)
				(type default)
			)
			(fill no)
			(layer "F.Fab")
		)
		(pad "1" smd custom
			(at 0 -0.4445)
			(size 0.1397 0.1397)
			(layers "F.Cu" "F.Mask" "F.Paste")
			(net "BMC_RMT_HEARTBEAT_LS")
			(options
				(clearance outline)
				(anchor circle)
			)
			(primitives
				(gr_poly
					(pts
						(arc
							(start -0.1778 -0.2794)
							(mid -0.249642 -0.249642)
							(end -0.2794 -0.1778)
						)
						(arc
							(start -0.2794 0.1778)
							(mid -0.249642 0.249642)
							(end -0.1778 0.2794)
						)
						(arc
							(start 0.1778 0.2794)
							(mid 0.249642 0.249642)
							(end 0.2794 0.1778)
						)
						(arc
							(start 0.2794 -0.1778)
							(mid 0.249642 -0.249642)
							(end 0.1778 -0.2794)
						)
					)
					(width 0)
					(fill yes)
				)
			)
		)
		(pad "2" smd custom
			(at 0 0.4445)
			(size 0.1397 0.1397)
			(layers "F.Cu" "F.Mask" "F.Paste")
			(net "P1V8_E")
			(options
				(clearance outline)
				(anchor circle)
			)
			(primitives
				(gr_poly
					(pts
						(arc
							(start -0.1778 -0.2794)
							(mid -0.249642 -0.249642)
							(end -0.2794 -0.1778)
						)
						(arc
							(start -0.2794 0.1778)
							(mid -0.249642 0.249642)
							(end -0.1778 0.2794)
						)
						(arc
							(start 0.1778 0.2794)
							(mid 0.249642 0.249642)
							(end 0.2794 0.1778)
						)
						(arc
							(start 0.2794 -0.1778)
							(mid 0.249642 -0.249642)
							(end 0.1778 -0.2794)
						)
					)
					(width 0)
					(fill yes)
				)
			)
		)
	)
	(footprint ""
		(layer "F.Cu")
		(at 161.973768 -23.935944 -90)
		(property "Reference" "R170"
			(at 0 0 270)
			(layer "F.SilkS")
			(hide yes)
			(effects
				(font
					(size 1.27 1.27)
				)
			)
		)
		(property "Value" "51R2F-2-GP"
			(at 0.064008 -3.993896 270)
			(unlocked yes)
			(layer "F.Fab")
			(hide yes)
			(effects
				(font
					(size 1.016 1.016)
					(thickness 0.1524)
				)
			)
		)
		(property "Device Type" "R402H16"
			(at 0.064008 -5.517896 270)
			(unlocked yes)
			(layer "F.Fab")
			(hide yes)
			(effects
				(font
					(size 1.016 1.016)
					(thickness 0.1524)
				)
			)
		)
		(duplicate_pad_numbers_are_jumpers no)
		(fp_line
			(start -0.508 -0.9398)
			(end -0.508 0.9398)
			(stroke
				(width 0.1524)
				(type default)
			)
			(layer "F.SilkS")
		)
		(fp_line
			(start 0.508 -0.9398)
			(end -0.508 -0.9398)
			(stroke
				(width 0.1524)
				(type default)
			)
			(layer "F.SilkS")
		)
		(fp_rect
			(start -0.508 0.9398)
			(end 0.508 -0.9398)
			(stroke
				(width 0)
				(type default)
			)
			(fill no)
			(layer "F.CrtYd")
		)
		(fp_rect
			(start -0.508 0.9398)
			(end 0.508 -0.9398)
			(stroke
				(width 0)
				(type default)
			)
			(fill no)
			(layer "F.Fab")
		)
		(pad "1" smd custom
			(at 0 -0.4445 270)
			(size 0.1397 0.1397)
			(layers "F.Cu" "F.Mask" "F.Paste")
			(net "PCIE_CLK_R_P")
			(options
				(clearance outline)
				(anchor circle)
			)
			(primitives
				(gr_poly
					(pts
						(arc
							(start -0.1778 -0.2794)
							(mid -0.249642 -0.249642)
							(end -0.2794 -0.1778)
						)
						(arc
							(start -0.2794 0.1778)
							(mid -0.249642 0.249642)
							(end -0.1778 0.2794)
						)
						(arc
							(start 0.1778 0.2794)
							(mid 0.249642 0.249642)
							(end 0.2794 0.1778)
						)
						(arc
							(start 0.2794 -0.1778)
							(mid 0.249642 -0.249642)
							(end 0.1778 -0.2794)
						)
					)
					(width 0)
					(fill yes)
				)
			)
		)
		(pad "2" smd custom
			(at 0 0.4445 270)
			(size 0.1397 0.1397)
			(layers "F.Cu" "F.Mask" "F.Paste")
			(net "GND")
			(options
				(clearance outline)
				(anchor circle)
			)
			(primitives
				(gr_poly
					(pts
						(arc
							(start -0.1778 -0.2794)
							(mid -0.249642 -0.249642)
							(end -0.2794 -0.1778)
						)
						(arc
							(start -0.2794 0.1778)
							(mid -0.249642 0.249642)
							(end -0.1778 0.2794)
						)
						(arc
							(start 0.1778 0.2794)
							(mid 0.249642 0.249642)
							(end 0.2794 0.1778)
						)
						(arc
							(start 0.2794 -0.1778)
							(mid 0.249642 -0.249642)
							(end 0.1778 -0.2794)
						)
					)
					(width 0)
					(fill yes)
				)
			)
		)
	)
	(footprint ""
		(layer "F.Cu")
		(at 70.0024 -72.6948)
		(property "Reference" "R433"
			(at 0 0 0)
			(layer "F.SilkS")
			(hide yes)
			(effects
				(font
					(size 1.27 1.27)
				)
			)
		)
		(property "Value" "0R2J-2-GP"
			(at 0.064008 -3.993896 0)
			(unlocked yes)
			(layer "F.Fab")
			(hide yes)
			(effects
				(font
					(size 1.016 1.016)
					(thickness 0.1524)
				)
			)
		)
		(property "Device Type" "R402H16"
			(at 0.064008 -5.517896 0)
			(unlocked yes)
			(layer "F.Fab")
			(hide yes)
			(effects
				(font
					(size 1.016 1.016)
					(thickness 0.1524)
				)
			)
		)
		(duplicate_pad_numbers_are_jumpers no)
		(fp_line
			(start -0.508 -0.9398)
			(end -0.508 0.9398)
			(stroke
				(width 0.1524)
				(type default)
			)
			(layer "F.SilkS")
		)
		(fp_line
			(start 0.508 -0.9398)
			(end -0.508 -0.9398)
			(stroke
				(width 0.1524)
				(type default)
			)
			(layer "F.SilkS")
		)
		(fp_rect
			(start -0.508 0.9398)
			(end 0.508 -0.9398)
			(stroke
				(width 0)
				(type default)
			)
			(fill no)
			(layer "F.CrtYd")
		)
		(fp_rect
			(start -0.508 0.9398)
			(end 0.508 -0.9398)
			(stroke
				(width 0)
				(type default)
			)
			(fill no)
			(layer "F.Fab")
		)
		(pad "1" smd custom
			(at 0 -0.4445)
			(size 0.1397 0.1397)
			(layers "F.Cu" "F.Mask" "F.Paste")
			(net "LS_EN_U39")
			(options
				(clearance outline)
				(anchor circle)
			)
			(primitives
				(gr_poly
					(pts
						(arc
							(start -0.1778 -0.2794)
							(mid -0.249642 -0.249642)
							(end -0.2794 -0.1778)
						)
						(arc
							(start -0.2794 0.1778)
							(mid -0.249642 0.249642)
							(end -0.1778 0.2794)
						)
						(arc
							(start 0.1778 0.2794)
							(mid 0.249642 0.249642)
							(end 0.2794 0.1778)
						)
						(arc
							(start 0.2794 -0.1778)
							(mid 0.249642 -0.249642)
							(end 0.1778 -0.2794)
						)
					)
					(width 0)
					(fill yes)
				)
			)
		)
		(pad "2" smd custom
			(at 0 0.4445)
			(size 0.1397 0.1397)
			(layers "F.Cu" "F.Mask" "F.Paste")
			(net "VREF6")
			(options
				(clearance outline)
				(anchor circle)
			)
			(primitives
				(gr_poly
					(pts
						(arc
							(start -0.1778 -0.2794)
							(mid -0.249642 -0.249642)
							(end -0.2794 -0.1778)
						)
						(arc
							(start -0.2794 0.1778)
							(mid -0.249642 0.249642)
							(end -0.1778 0.2794)
						)
						(arc
							(start 0.1778 0.2794)
							(mid 0.249642 0.249642)
							(end 0.2794 0.1778)
						)
						(arc
							(start 0.2794 -0.1778)
							(mid 0.249642 -0.249642)
							(end 0.1778 -0.2794)
						)
					)
					(width 0)
					(fill yes)
				)
			)
		)
	)
	(footprint ""
		(layer "F.Cu")
		(at 184.3405 -55.695088)
		(property "Reference" "R213"
			(at 0 0 0)
			(layer "F.SilkS")
			(hide yes)
			(effects
				(font
					(size 1.27 1.27)
				)
			)
		)
		(property "Value" "10KR2F-2-GP"
			(at 0.064008 -3.993896 0)
			(unlocked yes)
			(layer "F.Fab")
			(hide yes)
			(effects
				(font
					(size 1.016 1.016)
					(thickness 0.1524)
				)
			)
		)
		(property "Device Type" "R402H16"
			(at 0.064008 -5.517896 0)
			(unlocked yes)
			(layer "F.Fab")
			(hide yes)
			(effects
				(font
					(size 1.016 1.016)
					(thickness 0.1524)
				)
			)
		)
		(duplicate_pad_numbers_are_jumpers no)
		(fp_line
			(start -0.508 -0.9398)
			(end -0.508 0.9398)
			(stroke
				(width 0.1524)
				(type default)
			)
			(layer "F.SilkS")
		)
		(fp_line
			(start 0.508 -0.9398)
			(end -0.508 -0.9398)
			(stroke
				(width 0.1524)
				(type default)
			)
			(layer "F.SilkS")
		)
		(fp_rect
			(start -0.508 0.9398)
			(end 0.508 -0.9398)
			(stroke
				(width 0)
				(type default)
			)
			(fill no)
			(layer "F.CrtYd")
		)
		(fp_rect
			(start -0.508 0.9398)
			(end 0.508 -0.9398)
			(stroke
				(width 0)
				(type default)
			)
			(fill no)
			(layer "F.Fab")
		)
		(pad "1" smd custom
			(at 0 -0.4445)
			(size 0.1397 0.1397)
			(layers "F.Cu" "F.Mask" "F.Paste")
			(net "P1V8_C")
			(options
				(clearance outline)
				(anchor circle)
			)
			(primitives
				(gr_poly
					(pts
						(arc
							(start -0.1778 -0.2794)
							(mid -0.249642 -0.249642)
							(end -0.2794 -0.1778)
						)
						(arc
							(start -0.2794 0.1778)
							(mid -0.249642 0.249642)
							(end -0.1778 0.2794)
						)
						(arc
							(start 0.1778 0.2794)
							(mid 0.249642 0.249642)
							(end 0.2794 0.1778)
						)
						(arc
							(start 0.2794 -0.1778)
							(mid 0.249642 -0.249642)
							(end 0.1778 -0.2794)
						)
					)
					(width 0)
					(fill yes)
				)
			)
		)
		(pad "2" smd custom
			(at 0 0.4445)
			(size 0.1397 0.1397)
			(layers "F.Cu" "F.Mask" "F.Paste")
			(net "XM_ADDR_0")
			(options
				(clearance outline)
				(anchor circle)
			)
			(primitives
				(gr_poly
					(pts
						(arc
							(start -0.1778 -0.2794)
							(mid -0.249642 -0.249642)
							(end -0.2794 -0.1778)
						)
						(arc
							(start -0.2794 0.1778)
							(mid -0.249642 0.249642)
							(end -0.1778 0.2794)
						)
						(arc
							(start 0.1778 0.2794)
							(mid 0.249642 0.249642)
							(end 0.2794 0.1778)
						)
						(arc
							(start 0.2794 -0.1778)
							(mid 0.249642 -0.249642)
							(end 0.1778 -0.2794)
						)
					)
					(width 0)
					(fill yes)
				)
			)
		)
	)
	(footprint ""
		(layer "F.Cu")
		(at 70.485 -46.482 90)
		(property "Reference" "R164"
			(at 0 0 90)
			(layer "F.SilkS")
			(hide yes)
			(effects
				(font
					(size 1.27 1.27)
				)
			)
		)
		(property "Value" "D51R3F-2-GP"
			(at -0.0254 -2.5146 90)
			(unlocked yes)
			(layer "F.Fab")
			(hide yes)
			(effects
				(font
					(size 1.016 1.016)
					(thickness 0.1524)
				)
			)
		)
		(property "Device Type" "R603H22"
			(at -0.0254 -4.0386 90)
			(unlocked yes)
			(layer "F.Fab")
			(hide yes)
			(effects
				(font
					(size 1.016 1.016)
					(thickness 0.1524)
				)
			)
		)
		(duplicate_pad_numbers_are_jumpers no)
		(fp_line
			(start 0.2032 0)
			(end 0.4826 0)
			(stroke
				(width 0.2032)
				(type default)
			)
			(layer "F.SilkS")
		)
		(fp_line
			(start -0.4826 0)
			(end -0.2032 0)
			(stroke
				(width 0.2032)
				(type default)
			)
			(layer "F.SilkS")
		)
		(fp_rect
			(start -0.5842 1.3335)
			(end 0.5842 -1.3335)
			(stroke
				(width 0)
				(type default)
			)
			(fill no)
			(layer "F.CrtYd")
		)
		(fp_rect
			(start -0.5842 1.3335)
			(end 0.5842 -1.3335)
			(stroke
				(width 0)
				(type default)
			)
			(fill no)
			(layer "F.Fab")
		)
		(pad "1" smd custom
			(at 0 -0.762 90)
			(size 0.2159 0.2159)
			(layers "F.Cu" "F.Mask" "F.Paste")
			(net "P0V9")
			(options
				(clearance outline)
				(anchor circle)
			)
			(primitives
				(gr_poly
					(pts
						(arc
							(start -0.3302 -0.4318)
							(mid -0.402042 -0.402042)
							(end -0.4318 -0.3302)
						)
						(arc
							(start -0.4318 0.3302)
							(mid -0.402042 0.402042)
							(end -0.3302 0.4318)
						)
						(arc
							(start 0.3302 0.4318)
							(mid 0.402042 0.402042)
							(end 0.4318 0.3302)
						)
						(arc
							(start 0.4318 -0.3302)
							(mid 0.402042 -0.402042)
							(end 0.3302 -0.4318)
						)
					)
					(width 0)
					(fill yes)
				)
			)
		)
		(pad "2" smd custom
			(at 0 0.762 90)
			(size 0.2159 0.2159)
			(layers "F.Cu" "F.Mask" "F.Paste")
			(net "GB_VDDA")
			(options
				(clearance outline)
				(anchor circle)
			)
			(primitives
				(gr_poly
					(pts
						(arc
							(start -0.3302 -0.4318)
							(mid -0.402042 -0.402042)
							(end -0.4318 -0.3302)
						)
						(arc
							(start -0.4318 0.3302)
							(mid -0.402042 0.402042)
							(end -0.3302 0.4318)
						)
						(arc
							(start 0.3302 0.4318)
							(mid 0.402042 0.402042)
							(end 0.4318 0.3302)
						)
						(arc
							(start 0.4318 -0.3302)
							(mid 0.402042 -0.402042)
							(end 0.3302 -0.4318)
						)
					)
					(width 0)
					(fill yes)
				)
			)
		)
	)
	(footprint ""
		(layer "F.Cu")
		(at 75.438 -57.2389)
		(property "Reference" "C295"
			(at 0 0 0)
			(layer "F.SilkS")
			(hide yes)
			(effects
				(font
					(size 1.27 1.27)
				)
			)
		)
		(property "Value" "SC22U6D3V3MX-9-GP-U"
			(at 0 -2.8194 0)
			(unlocked yes)
			(layer "F.Fab")
			(hide yes)
			(effects
				(font
					(size 1.016 1.016)
					(thickness 0.1524)
				)
			)
		)
		(property "Device Type" "C603H40"
			(at 0 -4.3434 0)
			(unlocked yes)
			(layer "F.Fab")
			(hide yes)
			(effects
				(font
					(size 1.016 1.016)
					(thickness 0.1524)
				)
			)
		)
		(duplicate_pad_numbers_are_jumpers no)
		(fp_line
			(start 0.508 0)
			(end -0.508 0)
			(stroke
				(width 0.2032)
				(type default)
			)
			(layer "F.SilkS")
		)
		(fp_rect
			(start -0.5842 1.3335)
			(end 0.5842 -1.3335)
			(stroke
				(width 0)
				(type default)
			)
			(fill no)
			(layer "F.CrtYd")
		)
		(fp_rect
			(start -0.5842 1.3335)
			(end 0.5842 -1.3335)
			(stroke
				(width 0)
				(type default)
			)
			(fill no)
			(layer "F.Fab")
		)
		(pad "1" smd custom
			(at 0 -0.762)
			(size 0.2159 0.2159)
			(layers "F.Cu" "F.Mask" "F.Paste")
			(net "GB_VDDA")
			(options
				(clearance outline)
				(anchor circle)
			)
			(primitives
				(gr_poly
					(pts
						(arc
							(start -0.3302 -0.4318)
							(mid -0.402042 -0.402042)
							(end -0.4318 -0.3302)
						)
						(arc
							(start -0.4318 0.3302)
							(mid -0.402042 0.402042)
							(end -0.3302 0.4318)
						)
						(arc
							(start 0.3302 0.4318)
							(mid 0.402042 0.402042)
							(end 0.4318 0.3302)
						)
						(arc
							(start 0.4318 -0.3302)
							(mid 0.402042 -0.402042)
							(end 0.3302 -0.4318)
						)
					)
					(width 0)
					(fill yes)
				)
			)
		)
		(pad "2" smd custom
			(at 0 0.762)
			(size 0.2159 0.2159)
			(layers "F.Cu" "F.Mask" "F.Paste")
			(net "GND")
			(options
				(clearance outline)
				(anchor circle)
			)
			(primitives
				(gr_poly
					(pts
						(arc
							(start -0.3302 -0.4318)
							(mid -0.402042 -0.402042)
							(end -0.4318 -0.3302)
						)
						(arc
							(start -0.4318 0.3302)
							(mid -0.402042 0.402042)
							(end -0.3302 0.4318)
						)
						(arc
							(start 0.3302 0.4318)
							(mid 0.402042 0.402042)
							(end 0.4318 0.3302)
						)
						(arc
							(start 0.4318 -0.3302)
							(mid 0.402042 -0.402042)
							(end 0.3302 -0.4318)
						)
					)
					(width 0)
					(fill yes)
				)
			)
		)
	)
	(footprint ""
		(layer "F.Cu")
		(at 147.425918 -47.00524 -78)
		(property "Reference" "VIA22"
			(at 0 0 282)
			(layer "F.SilkS")
			(hide yes)
			(effects
				(font
					(size 1.27 1.27)
				)
			)
		)
		(property "Value" "100OHM-8L-1D6MM-L13-GP"
			(at 3.289386 0.0506 282)
			(unlocked yes)
			(layer "F.Fab")
			(hide yes)
			(effects
				(font
					(size 1.016 1.016)
					(thickness 0.1524)
				)
			)
		)
		(property "Device Type" "VIA-PCIE-4P-409091"
			(at 3.289207 -1.473208 282)
			(unlocked yes)
			(layer "F.Fab")
			(hide yes)
			(effects
				(font
					(size 1.016 1.016)
					(thickness 0.1524)
				)
			)
		)
		(duplicate_pad_numbers_are_jumpers no)
		(fp_poly
			(pts
				(xy -2.044719 -0.457296) (xy 2.04468 -0.457296) (xy 2.044681 0.457104) (xy -2.044719 0.457104)
			)
			(stroke
				(width 0)
				(type default)
			)
			(fill no)
			(layer "F.CrtYd")
		)
		(fp_poly
			(pts
				(xy -2.044719 -0.457296) (xy 2.04468 -0.457296) (xy 2.044681 0.457104) (xy -2.044719 0.457104)
			)
			(stroke
				(width 0)
				(type default)
			)
			(fill no)
			(layer "F.Fab")
		)
		(pad "1" thru_hole circle
			(at -1.5875 0 282)
			(size 0.508 0.508)
			(drill 0.254)
			(layers "*.Cu" "*.Mask")
			(remove_unused_layers no)
			(net "GND")
			(clearance 0.2032)
			(thermal_gap 0.2032)
		)
		(pad "2" thru_hole circle
			(at -0.5715 0.000001 282)
			(size 0.508 0.508)
			(drill 0.254)
			(layers "*.Cu" "*.Mask")
			(remove_unused_layers no)
			(net "PHY_SCC_TO_IOC_C_45_DP")
			(clearance 0.2032)
			(thermal_gap 0.2032)
		)
		(pad "3" thru_hole circle
			(at 0.5715 -0.000001 282)
			(size 0.508 0.508)
			(drill 0.254)
			(layers "*.Cu" "*.Mask")
			(remove_unused_layers no)
			(net "PHY_SCC_TO_IOC_C_45_DN")
			(clearance 0.2032)
			(thermal_gap 0.2032)
		)
		(pad "4" thru_hole circle
			(at 1.5875 0 282)
			(size 0.508 0.508)
			(drill 0.254)
			(layers "*.Cu" "*.Mask")
			(remove_unused_layers no)
			(net "GND")
			(clearance 0.2032)
			(thermal_gap 0.2032)
		)
	)
	(footprint ""
		(layer "F.Cu")
		(at 189.2808 -22.9616 -90)
		(property "Reference" "R248"
			(at 0 0 270)
			(layer "F.SilkS")
			(hide yes)
			(effects
				(font
					(size 1.27 1.27)
				)
			)
		)
		(property "Value" "4K7R2F-GP"
			(at 0.064008 -3.993896 270)
			(unlocked yes)
			(layer "F.Fab")
			(hide yes)
			(effects
				(font
					(size 1.016 1.016)
					(thickness 0.1524)
				)
			)
		)
		(property "Device Type" "R402H16"
			(at 0.064008 -5.517896 270)
			(unlocked yes)
			(layer "F.Fab")
			(hide yes)
			(effects
				(font
					(size 1.016 1.016)
					(thickness 0.1524)
				)
			)
		)
		(duplicate_pad_numbers_are_jumpers no)
		(fp_line
			(start -0.508 -0.9398)
			(end -0.508 0.9398)
			(stroke
				(width 0.1524)
				(type default)
			)
			(layer "F.SilkS")
		)
		(fp_line
			(start 0.508 -0.9398)
			(end -0.508 -0.9398)
			(stroke
				(width 0.1524)
				(type default)
			)
			(layer "F.SilkS")
		)
		(fp_rect
			(start -0.508 0.9398)
			(end 0.508 -0.9398)
			(stroke
				(width 0)
				(type default)
			)
			(fill no)
			(layer "F.CrtYd")
		)
		(fp_rect
			(start -0.508 0.9398)
			(end 0.508 -0.9398)
			(stroke
				(width 0)
				(type default)
			)
			(fill no)
			(layer "F.Fab")
		)
		(pad "1" smd custom
			(at 0 -0.4445 270)
			(size 0.1397 0.1397)
			(layers "F.Cu" "F.Mask" "F.Paste")
			(net "P1V8_C")
			(options
				(clearance outline)
				(anchor circle)
			)
			(primitives
				(gr_poly
					(pts
						(arc
							(start -0.1778 -0.2794)
							(mid -0.249642 -0.249642)
							(end -0.2794 -0.1778)
						)
						(arc
							(start -0.2794 0.1778)
							(mid -0.249642 0.249642)
							(end -0.1778 0.2794)
						)
						(arc
							(start 0.1778 0.2794)
							(mid 0.249642 0.249642)
							(end 0.2794 0.1778)
						)
						(arc
							(start 0.2794 -0.1778)
							(mid 0.249642 -0.249642)
							(end 0.1778 -0.2794)
						)
					)
					(width 0)
					(fill yes)
				)
			)
		)
		(pad "2" smd custom
			(at 0 0.4445 270)
			(size 0.1397 0.1397)
			(layers "F.Cu" "F.Mask" "F.Paste")
			(net "SYS_DBMODE3")
			(options
				(clearance outline)
				(anchor circle)
			)
			(primitives
				(gr_poly
					(pts
						(arc
							(start -0.1778 -0.2794)
							(mid -0.249642 -0.249642)
							(end -0.2794 -0.1778)
						)
						(arc
							(start -0.2794 0.1778)
							(mid -0.249642 0.249642)
							(end -0.1778 0.2794)
						)
						(arc
							(start 0.1778 0.2794)
							(mid 0.249642 0.249642)
							(end 0.2794 0.1778)
						)
						(arc
							(start 0.2794 -0.1778)
							(mid 0.249642 -0.249642)
							(end 0.1778 -0.2794)
						)
					)
					(width 0)
					(fill yes)
				)
			)
		)
	)
	(footprint ""
		(layer "F.Cu")
		(at 18.5674 -94.9452 180)
		(property "Reference" "R407"
			(at 0 0 180)
			(layer "F.SilkS")
			(hide yes)
			(effects
				(font
					(size 1.27 1.27)
				)
			)
		)
		(property "Value" "200KR2F-L-GP"
			(at 0.064008 -3.993896 180)
			(unlocked yes)
			(layer "F.Fab")
			(hide yes)
			(effects
				(font
					(size 1.016 1.016)
					(thickness 0.1524)
				)
			)
		)
		(property "Device Type" "R402H16"
			(at 0.064008 -5.517896 180)
			(unlocked yes)
			(layer "F.Fab")
			(hide yes)
			(effects
				(font
					(size 1.016 1.016)
					(thickness 0.1524)
				)
			)
		)
		(duplicate_pad_numbers_are_jumpers no)
		(fp_line
			(start 0.508 -0.9398)
			(end -0.508 -0.9398)
			(stroke
				(width 0.1524)
				(type default)
			)
			(layer "F.SilkS")
		)
		(fp_line
			(start -0.508 -0.9398)
			(end -0.508 0.9398)
			(stroke
				(width 0.1524)
				(type default)
			)
			(layer "F.SilkS")
		)
		(fp_rect
			(start -0.508 0.9398)
			(end 0.508 -0.9398)
			(stroke
				(width 0)
				(type default)
			)
			(fill no)
			(layer "F.CrtYd")
		)
		(fp_rect
			(start -0.508 0.9398)
			(end 0.508 -0.9398)
			(stroke
				(width 0)
				(type default)
			)
			(fill no)
			(layer "F.Fab")
		)
		(pad "1" smd custom
			(at 0 -0.4445 180)
			(size 0.1397 0.1397)
			(layers "F.Cu" "F.Mask" "F.Paste")
			(net "VREF0")
			(options
				(clearance outline)
				(anchor circle)
			)
			(primitives
				(gr_poly
					(pts
						(arc
							(start -0.1778 -0.2794)
							(mid -0.249642 -0.249642)
							(end -0.2794 -0.1778)
						)
						(arc
							(start -0.2794 0.1778)
							(mid -0.249642 0.249642)
							(end -0.1778 0.2794)
						)
						(arc
							(start 0.1778 0.2794)
							(mid 0.249642 0.249642)
							(end 0.2794 0.1778)
						)
						(arc
							(start 0.2794 -0.1778)
							(mid 0.249642 -0.249642)
							(end 0.1778 -0.2794)
						)
					)
					(width 0)
					(fill yes)
				)
			)
		)
		(pad "2" smd custom
			(at 0 0.4445 180)
			(size 0.1397 0.1397)
			(layers "F.Cu" "F.Mask" "F.Paste")
			(net "P3V3")
			(options
				(clearance outline)
				(anchor circle)
			)
			(primitives
				(gr_poly
					(pts
						(arc
							(start -0.1778 -0.2794)
							(mid -0.249642 -0.249642)
							(end -0.2794 -0.1778)
						)
						(arc
							(start -0.2794 0.1778)
							(mid -0.249642 0.249642)
							(end -0.1778 0.2794)
						)
						(arc
							(start 0.1778 0.2794)
							(mid 0.249642 0.249642)
							(end 0.2794 0.1778)
						)
						(arc
							(start 0.2794 -0.1778)
							(mid 0.249642 -0.249642)
							(end 0.1778 -0.2794)
						)
					)
					(width 0)
					(fill yes)
				)
			)
		)
	)
	(footprint ""
		(layer "F.Cu")
		(at 76.12634 -71.404988 90)
		(property "Reference" "R540"
			(at 0 0 90)
			(layer "F.SilkS")
			(hide yes)
			(effects
				(font
					(size 1.27 1.27)
				)
			)
		)
		(property "Value" "0R2J-2-GP"
			(at 0.064008 -3.993896 90)
			(unlocked yes)
			(layer "F.Fab")
			(hide yes)
			(effects
				(font
					(size 1.016 1.016)
					(thickness 0.1524)
				)
			)
		)
		(property "Device Type" "R402H16"
			(at 0.064008 -5.517896 90)
			(unlocked yes)
			(layer "F.Fab")
			(hide yes)
			(effects
				(font
					(size 1.016 1.016)
					(thickness 0.1524)
				)
			)
		)
		(duplicate_pad_numbers_are_jumpers no)
		(fp_line
			(start 0.508 -0.9398)
			(end -0.508 -0.9398)
			(stroke
				(width 0.1524)
				(type default)
			)
			(layer "F.SilkS")
		)
		(fp_line
			(start -0.508 -0.9398)
			(end -0.508 0.9398)
			(stroke
				(width 0.1524)
				(type default)
			)
			(layer "F.SilkS")
		)
		(fp_rect
			(start -0.508 0.9398)
			(end 0.508 -0.9398)
			(stroke
				(width 0)
				(type default)
			)
			(fill no)
			(layer "F.CrtYd")
		)
		(fp_rect
			(start -0.508 0.9398)
			(end 0.508 -0.9398)
			(stroke
				(width 0)
				(type default)
			)
			(fill no)
			(layer "F.Fab")
		)
		(pad "1" smd custom
			(at 0 -0.4445 90)
			(size 0.1397 0.1397)
			(layers "F.Cu" "F.Mask" "F.Paste")
			(net "I2C_IOC_4_R_SCL")
			(options
				(clearance outline)
				(anchor circle)
			)
			(primitives
				(gr_poly
					(pts
						(arc
							(start -0.1778 -0.2794)
							(mid -0.249642 -0.249642)
							(end -0.2794 -0.1778)
						)
						(arc
							(start -0.2794 0.1778)
							(mid -0.249642 0.249642)
							(end -0.1778 0.2794)
						)
						(arc
							(start 0.1778 0.2794)
							(mid 0.249642 0.249642)
							(end 0.2794 0.1778)
						)
						(arc
							(start 0.2794 -0.1778)
							(mid 0.249642 -0.249642)
							(end 0.1778 -0.2794)
						)
					)
					(width 0)
					(fill yes)
				)
			)
		)
		(pad "2" smd custom
			(at 0 0.4445 90)
			(size 0.1397 0.1397)
			(layers "F.Cu" "F.Mask" "F.Paste")
			(net "I2C_IOC_4_SCL")
			(options
				(clearance outline)
				(anchor circle)
			)
			(primitives
				(gr_poly
					(pts
						(arc
							(start -0.1778 -0.2794)
							(mid -0.249642 -0.249642)
							(end -0.2794 -0.1778)
						)
						(arc
							(start -0.2794 0.1778)
							(mid -0.249642 0.249642)
							(end -0.1778 0.2794)
						)
						(arc
							(start 0.1778 0.2794)
							(mid 0.249642 0.249642)
							(end 0.2794 0.1778)
						)
						(arc
							(start 0.2794 -0.1778)
							(mid 0.249642 -0.249642)
							(end 0.1778 -0.2794)
						)
					)
					(width 0)
					(fill yes)
				)
			)
		)
	)
	(footprint ""
		(layer "F.Cu")
		(at 123.317 -108.59008)
		(property "Reference" "TP153"
			(at 0 0 0)
			(layer "F.SilkS")
			(hide yes)
			(effects
				(font
					(size 1.27 1.27)
				)
			)
		)
		(property "Value" "TPAD28-2-GP"
			(at -0.0127 -1.6637 0)
			(unlocked yes)
			(layer "F.Fab")
			(hide yes)
			(effects
				(font
					(size 1.016 1.016)
					(thickness 0.1524)
				)
			)
		)
		(property "Device Type" "TPAD28"
			(at -0.0127 -3.1877 0)
			(unlocked yes)
			(layer "F.Fab")
			(hide yes)
			(effects
				(font
					(size 1.016 1.016)
					(thickness 0.1524)
				)
			)
		)
		(duplicate_pad_numbers_are_jumpers no)
		(fp_poly
			(pts
				(arc
					(start 0.3556 0)
					(mid -0.3556 0)
					(end 0.3556 0)
				)
			)
			(stroke
				(width 0)
				(type default)
			)
			(fill no)
			(layer "F.CrtYd")
		)
		(fp_poly
			(pts
				(arc
					(start 0.6096 0)
					(mid -0.6096 0)
					(end 0.6096 0)
				)
			)
			(stroke
				(width 0)
				(type default)
			)
			(fill no)
			(layer "F.Fab")
		)
		(pad "1" smd circle
			(at 0 0)
			(size 0.7112 0.7112)
			(layers "F.Cu" "F.Mask" "F.Paste")
			(net "INT_D1_CONN1")
		)
	)
	(footprint ""
		(layer "F.Cu")
		(at 18.4912 -46.9646 180)
		(property "Reference" "R550"
			(at 0 0 180)
			(layer "F.SilkS")
			(hide yes)
			(effects
				(font
					(size 1.27 1.27)
				)
			)
		)
		(property "Value" "49K9R2F-L-GP"
			(at 0.064008 -3.993896 180)
			(unlocked yes)
			(layer "F.Fab")
			(hide yes)
			(effects
				(font
					(size 1.016 1.016)
					(thickness 0.1524)
				)
			)
		)
		(property "Device Type" "R402H16"
			(at 0.064008 -5.517896 180)
			(unlocked yes)
			(layer "F.Fab")
			(hide yes)
			(effects
				(font
					(size 1.016 1.016)
					(thickness 0.1524)
				)
			)
		)
		(duplicate_pad_numbers_are_jumpers no)
		(fp_line
			(start 0.508 -0.9398)
			(end -0.508 -0.9398)
			(stroke
				(width 0.1524)
				(type default)
			)
			(layer "F.SilkS")
		)
		(fp_line
			(start -0.508 -0.9398)
			(end -0.508 0.9398)
			(stroke
				(width 0.1524)
				(type default)
			)
			(layer "F.SilkS")
		)
		(fp_rect
			(start -0.508 0.9398)
			(end 0.508 -0.9398)
			(stroke
				(width 0)
				(type default)
			)
			(fill no)
			(layer "F.CrtYd")
		)
		(fp_rect
			(start -0.508 0.9398)
			(end 0.508 -0.9398)
			(stroke
				(width 0)
				(type default)
			)
			(fill no)
			(layer "F.Fab")
		)
		(pad "1" smd custom
			(at 0 -0.4445 180)
			(size 0.1397 0.1397)
			(layers "F.Cu" "F.Mask" "F.Paste")
			(net "P12V_MAIN")
			(options
				(clearance outline)
				(anchor circle)
			)
			(primitives
				(gr_poly
					(pts
						(arc
							(start -0.1778 -0.2794)
							(mid -0.249642 -0.249642)
							(end -0.2794 -0.1778)
						)
						(arc
							(start -0.2794 0.1778)
							(mid -0.249642 0.249642)
							(end -0.1778 0.2794)
						)
						(arc
							(start 0.1778 0.2794)
							(mid 0.249642 0.249642)
							(end 0.2794 0.1778)
						)
						(arc
							(start 0.2794 -0.1778)
							(mid 0.249642 -0.249642)
							(end 0.1778 -0.2794)
						)
					)
					(width 0)
					(fill yes)
				)
			)
		)
		(pad "2" smd custom
			(at 0 0.4445 180)
			(size 0.1397 0.1397)
			(layers "F.Cu" "F.Mask" "F.Paste")
			(net "MB0_CM_UV_R")
			(options
				(clearance outline)
				(anchor circle)
			)
			(primitives
				(gr_poly
					(pts
						(arc
							(start -0.1778 -0.2794)
							(mid -0.249642 -0.249642)
							(end -0.2794 -0.1778)
						)
						(arc
							(start -0.2794 0.1778)
							(mid -0.249642 0.249642)
							(end -0.1778 0.2794)
						)
						(arc
							(start 0.1778 0.2794)
							(mid 0.249642 0.249642)
							(end 0.2794 0.1778)
						)
						(arc
							(start 0.2794 -0.1778)
							(mid 0.249642 -0.249642)
							(end 0.1778 -0.2794)
						)
					)
					(width 0)
					(fill yes)
				)
			)
		)
	)
	(footprint ""
		(layer "F.Cu")
		(at 181.1401 -114.80673)
		(property "Reference" "C605"
			(at 0 0 0)
			(layer "F.SilkS")
			(hide yes)
			(effects
				(font
					(size 1.27 1.27)
				)
			)
		)
		(property "Value" "SC1KP50V2KX-1GP"
			(at 1.1811 -2.7051 0)
			(unlocked yes)
			(layer "F.Fab")
			(hide yes)
			(effects
				(font
					(size 1.016 1.016)
					(thickness 0.1524)
				)
			)
		)
		(property "Device Type" "C402H22"
			(at 1.1811 -4.2291 0)
			(unlocked yes)
			(layer "F.Fab")
			(hide yes)
			(effects
				(font
					(size 1.016 1.016)
					(thickness 0.1524)
				)
			)
		)
		(duplicate_pad_numbers_are_jumpers no)
		(fp_rect
			(start -0.4318 0.9525)
			(end 0.4318 -0.9525)
			(stroke
				(width 0)
				(type default)
			)
			(fill no)
			(layer "F.CrtYd")
		)
		(fp_rect
			(start -0.4318 0.9525)
			(end 0.4318 -0.9525)
			(stroke
				(width 0)
				(type default)
			)
			(fill no)
			(layer "F.Fab")
		)
		(pad "1" smd custom
			(at 0 -0.4445)
			(size 0.1524 0.1524)
			(layers "F.Cu" "F.Mask" "F.Paste")
			(net "P1V8_E_OUT")
			(options
				(clearance outline)
				(anchor circle)
			)
			(primitives
				(gr_poly
					(pts
						(arc
							(start 0.3048 -0.2032)
							(mid 0.275042 -0.275042)
							(end 0.2032 -0.3048)
						)
						(arc
							(start -0.2032 -0.3048)
							(mid -0.275042 -0.275042)
							(end -0.3048 -0.2032)
						)
						(arc
							(start -0.3048 0.2032)
							(mid -0.275042 0.275042)
							(end -0.2032 0.3048)
						)
						(arc
							(start 0.2032 0.3048)
							(mid 0.275042 0.275042)
							(end 0.3048 0.2032)
						)
					)
					(width 0)
					(fill yes)
				)
			)
		)
		(pad "2" smd custom
			(at 0 0.4445)
			(size 0.1524 0.1524)
			(layers "F.Cu" "F.Mask" "F.Paste")
			(net "P1V8_E_FB")
			(options
				(clearance outline)
				(anchor circle)
			)
			(primitives
				(gr_poly
					(pts
						(arc
							(start 0.3048 -0.2032)
							(mid 0.275042 -0.275042)
							(end 0.2032 -0.3048)
						)
						(arc
							(start -0.2032 -0.3048)
							(mid -0.275042 -0.275042)
							(end -0.3048 -0.2032)
						)
						(arc
							(start -0.3048 0.2032)
							(mid -0.275042 0.275042)
							(end -0.2032 0.3048)
						)
						(arc
							(start 0.2032 0.3048)
							(mid 0.275042 0.275042)
							(end 0.3048 0.2032)
						)
					)
					(width 0)
					(fill yes)
				)
			)
		)
	)
	(footprint ""
		(layer "F.Cu")
		(at 58.928 -17.272 90)
		(property "Reference" "R544"
			(at 0 0 90)
			(layer "F.SilkS")
			(hide yes)
			(effects
				(font
					(size 1.27 1.27)
				)
			)
		)
		(property "Value" "0R2J-2-GP"
			(at 0.064008 -3.993896 90)
			(unlocked yes)
			(layer "F.Fab")
			(hide yes)
			(effects
				(font
					(size 1.016 1.016)
					(thickness 0.1524)
				)
			)
		)
		(property "Device Type" "R402H16"
			(at 0.064008 -5.517896 90)
			(unlocked yes)
			(layer "F.Fab")
			(hide yes)
			(effects
				(font
					(size 1.016 1.016)
					(thickness 0.1524)
				)
			)
		)
		(duplicate_pad_numbers_are_jumpers no)
		(fp_line
			(start 0.508 -0.9398)
			(end -0.508 -0.9398)
			(stroke
				(width 0.1524)
				(type default)
			)
			(layer "F.SilkS")
		)
		(fp_line
			(start -0.508 -0.9398)
			(end -0.508 0.9398)
			(stroke
				(width 0.1524)
				(type default)
			)
			(layer "F.SilkS")
		)
		(fp_rect
			(start -0.508 0.9398)
			(end 0.508 -0.9398)
			(stroke
				(width 0)
				(type default)
			)
			(fill no)
			(layer "F.CrtYd")
		)
		(fp_rect
			(start -0.508 0.9398)
			(end 0.508 -0.9398)
			(stroke
				(width 0)
				(type default)
			)
			(fill no)
			(layer "F.Fab")
		)
		(pad "1" smd custom
			(at 0 -0.4445 90)
			(size 0.1397 0.1397)
			(layers "F.Cu" "F.Mask" "F.Paste")
			(net "SCC_STBY_PWR_EN")
			(options
				(clearance outline)
				(anchor circle)
			)
			(primitives
				(gr_poly
					(pts
						(arc
							(start -0.1778 -0.2794)
							(mid -0.249642 -0.249642)
							(end -0.2794 -0.1778)
						)
						(arc
							(start -0.2794 0.1778)
							(mid -0.249642 0.249642)
							(end -0.1778 0.2794)
						)
						(arc
							(start 0.1778 0.2794)
							(mid 0.249642 0.249642)
							(end 0.2794 0.1778)
						)
						(arc
							(start 0.2794 -0.1778)
							(mid 0.249642 -0.249642)
							(end 0.1778 -0.2794)
						)
					)
					(width 0)
					(fill yes)
				)
			)
		)
		(pad "2" smd custom
			(at 0 0.4445 90)
			(size 0.1397 0.1397)
			(layers "F.Cu" "F.Mask" "F.Paste")
			(net "SCC_STBY_PWR_BUF_EN")
			(options
				(clearance outline)
				(anchor circle)
			)
			(primitives
				(gr_poly
					(pts
						(arc
							(start -0.1778 -0.2794)
							(mid -0.249642 -0.249642)
							(end -0.2794 -0.1778)
						)
						(arc
							(start -0.2794 0.1778)
							(mid -0.249642 0.249642)
							(end -0.1778 0.2794)
						)
						(arc
							(start 0.1778 0.2794)
							(mid 0.249642 0.249642)
							(end 0.2794 0.1778)
						)
						(arc
							(start 0.2794 -0.1778)
							(mid 0.249642 -0.249642)
							(end 0.1778 -0.2794)
						)
					)
					(width 0)
					(fill yes)
				)
			)
		)
	)
	(footprint ""
		(layer "F.Cu")
		(at 163.298378 -96.847406 180)
		(property "Reference" "C619"
			(at 0 0 180)
			(layer "F.SilkS")
			(hide yes)
			(effects
				(font
					(size 1.27 1.27)
				)
			)
		)
		(property "Value" "SC1U25V3KX-GP"
			(at 0 -2.8194 180)
			(unlocked yes)
			(layer "F.Fab")
			(hide yes)
			(effects
				(font
					(size 1.016 1.016)
					(thickness 0.1524)
				)
			)
		)
		(property "Device Type" "C603H36"
			(at 0 -4.3434 180)
			(unlocked yes)
			(layer "F.Fab")
			(hide yes)
			(effects
				(font
					(size 1.016 1.016)
					(thickness 0.1524)
				)
			)
		)
		(duplicate_pad_numbers_are_jumpers no)
		(fp_line
			(start 0.508 0)
			(end -0.508 0)
			(stroke
				(width 0.2032)
				(type default)
			)
			(layer "F.SilkS")
		)
		(fp_rect
			(start -0.5842 1.3335)
			(end 0.5842 -1.3335)
			(stroke
				(width 0)
				(type default)
			)
			(fill no)
			(layer "F.CrtYd")
		)
		(fp_rect
			(start -0.5842 1.3335)
			(end 0.5842 -1.3335)
			(stroke
				(width 0)
				(type default)
			)
			(fill no)
			(layer "F.Fab")
		)
		(pad "1" smd custom
			(at 0 -0.762 180)
			(size 0.2159 0.2159)
			(layers "F.Cu" "F.Mask" "F.Paste")
			(net "VT235_AVDD")
			(options
				(clearance outline)
				(anchor circle)
			)
			(primitives
				(gr_poly
					(pts
						(arc
							(start -0.3302 -0.4318)
							(mid -0.402042 -0.402042)
							(end -0.4318 -0.3302)
						)
						(arc
							(start -0.4318 0.3302)
							(mid -0.402042 0.402042)
							(end -0.3302 0.4318)
						)
						(arc
							(start 0.3302 0.4318)
							(mid 0.402042 0.402042)
							(end 0.4318 0.3302)
						)
						(arc
							(start 0.4318 -0.3302)
							(mid 0.402042 -0.402042)
							(end 0.3302 -0.4318)
						)
					)
					(width 0)
					(fill yes)
				)
			)
		)
		(pad "2" smd custom
			(at 0 0.762 180)
			(size 0.2159 0.2159)
			(layers "F.Cu" "F.Mask" "F.Paste")
			(net "AGND_P0V975")
			(options
				(clearance outline)
				(anchor circle)
			)
			(primitives
				(gr_poly
					(pts
						(arc
							(start -0.3302 -0.4318)
							(mid -0.402042 -0.402042)
							(end -0.4318 -0.3302)
						)
						(arc
							(start -0.4318 0.3302)
							(mid -0.402042 0.402042)
							(end -0.3302 0.4318)
						)
						(arc
							(start 0.3302 0.4318)
							(mid 0.402042 0.402042)
							(end 0.4318 0.3302)
						)
						(arc
							(start 0.4318 -0.3302)
							(mid 0.402042 -0.402042)
							(end 0.3302 -0.4318)
						)
					)
					(width 0)
					(fill yes)
				)
			)
		)
	)
	(footprint ""
		(layer "F.Cu")
		(at 191.994282 -80.564736 -90)
		(property "Reference" "R369"
			(at 0 0 270)
			(layer "F.SilkS")
			(hide yes)
			(effects
				(font
					(size 1.27 1.27)
				)
			)
		)
		(property "Value" "4K7R2F-GP"
			(at 0.064008 -3.993896 270)
			(unlocked yes)
			(layer "F.Fab")
			(hide yes)
			(effects
				(font
					(size 1.016 1.016)
					(thickness 0.1524)
				)
			)
		)
		(property "Device Type" "R402H16"
			(at 0.064008 -5.517896 270)
			(unlocked yes)
			(layer "F.Fab")
			(hide yes)
			(effects
				(font
					(size 1.016 1.016)
					(thickness 0.1524)
				)
			)
		)
		(duplicate_pad_numbers_are_jumpers no)
		(fp_line
			(start -0.508 -0.9398)
			(end -0.508 0.9398)
			(stroke
				(width 0.1524)
				(type default)
			)
			(layer "F.SilkS")
		)
		(fp_line
			(start 0.508 -0.9398)
			(end -0.508 -0.9398)
			(stroke
				(width 0.1524)
				(type default)
			)
			(layer "F.SilkS")
		)
		(fp_rect
			(start -0.508 0.9398)
			(end 0.508 -0.9398)
			(stroke
				(width 0)
				(type default)
			)
			(fill no)
			(layer "F.CrtYd")
		)
		(fp_rect
			(start -0.508 0.9398)
			(end 0.508 -0.9398)
			(stroke
				(width 0)
				(type default)
			)
			(fill no)
			(layer "F.Fab")
		)
		(pad "1" smd custom
			(at 0 -0.4445 270)
			(size 0.1397 0.1397)
			(layers "F.Cu" "F.Mask" "F.Paste")
			(net "TEMP2_A2")
			(options
				(clearance outline)
				(anchor circle)
			)
			(primitives
				(gr_poly
					(pts
						(arc
							(start -0.1778 -0.2794)
							(mid -0.249642 -0.249642)
							(end -0.2794 -0.1778)
						)
						(arc
							(start -0.2794 0.1778)
							(mid -0.249642 0.249642)
							(end -0.1778 0.2794)
						)
						(arc
							(start 0.1778 0.2794)
							(mid 0.249642 0.249642)
							(end 0.2794 0.1778)
						)
						(arc
							(start 0.2794 -0.1778)
							(mid 0.249642 -0.249642)
							(end 0.1778 -0.2794)
						)
					)
					(width 0)
					(fill yes)
				)
			)
		)
		(pad "2" smd custom
			(at 0 0.4445 270)
			(size 0.1397 0.1397)
			(layers "F.Cu" "F.Mask" "F.Paste")
			(net "GND")
			(options
				(clearance outline)
				(anchor circle)
			)
			(primitives
				(gr_poly
					(pts
						(arc
							(start -0.1778 -0.2794)
							(mid -0.249642 -0.249642)
							(end -0.2794 -0.1778)
						)
						(arc
							(start -0.2794 0.1778)
							(mid -0.249642 0.249642)
							(end -0.1778 0.2794)
						)
						(arc
							(start 0.1778 0.2794)
							(mid 0.249642 0.249642)
							(end 0.2794 0.1778)
						)
						(arc
							(start 0.2794 -0.1778)
							(mid 0.249642 -0.249642)
							(end 0.1778 -0.2794)
						)
					)
					(width 0)
					(fill yes)
				)
			)
		)
	)
	(footprint ""
		(layer "F.Cu")
		(at 6.731 -40.259)
		(property "Reference" "C737"
			(at 0 0 0)
			(layer "F.SilkS")
			(hide yes)
			(effects
				(font
					(size 1.27 1.27)
				)
			)
		)
		(property "Value" "SCD022U25V2KX-GP"
			(at 1.1811 -2.7051 0)
			(unlocked yes)
			(layer "F.Fab")
			(hide yes)
			(effects
				(font
					(size 1.016 1.016)
					(thickness 0.1524)
				)
			)
		)
		(property "Device Type" "C402H22"
			(at 1.1811 -4.2291 0)
			(unlocked yes)
			(layer "F.Fab")
			(hide yes)
			(effects
				(font
					(size 1.016 1.016)
					(thickness 0.1524)
				)
			)
		)
		(duplicate_pad_numbers_are_jumpers no)
		(fp_rect
			(start -0.4318 0.9525)
			(end 0.4318 -0.9525)
			(stroke
				(width 0)
				(type default)
			)
			(fill no)
			(layer "F.CrtYd")
		)
		(fp_rect
			(start -0.4318 0.9525)
			(end 0.4318 -0.9525)
			(stroke
				(width 0)
				(type default)
			)
			(fill no)
			(layer "F.Fab")
		)
		(pad "1" smd custom
			(at 0 -0.4445)
			(size 0.1524 0.1524)
			(layers "F.Cu" "F.Mask" "F.Paste")
			(net "MB0_12V_CTRL_GATE1_R")
			(options
				(clearance outline)
				(anchor circle)
			)
			(primitives
				(gr_poly
					(pts
						(arc
							(start 0.3048 -0.2032)
							(mid 0.275042 -0.275042)
							(end 0.2032 -0.3048)
						)
						(arc
							(start -0.2032 -0.3048)
							(mid -0.275042 -0.275042)
							(end -0.3048 -0.2032)
						)
						(arc
							(start -0.3048 0.2032)
							(mid -0.275042 0.275042)
							(end -0.2032 0.3048)
						)
						(arc
							(start 0.2032 0.3048)
							(mid 0.275042 0.275042)
							(end 0.3048 0.2032)
						)
					)
					(width 0)
					(fill yes)
				)
			)
		)
		(pad "2" smd custom
			(at 0 0.4445)
			(size 0.1524 0.1524)
			(layers "F.Cu" "F.Mask" "F.Paste")
			(net "GND")
			(options
				(clearance outline)
				(anchor circle)
			)
			(primitives
				(gr_poly
					(pts
						(arc
							(start 0.3048 -0.2032)
							(mid 0.275042 -0.275042)
							(end 0.2032 -0.3048)
						)
						(arc
							(start -0.2032 -0.3048)
							(mid -0.275042 -0.275042)
							(end -0.3048 -0.2032)
						)
						(arc
							(start -0.3048 0.2032)
							(mid -0.275042 0.275042)
							(end -0.2032 0.3048)
						)
						(arc
							(start 0.2032 0.3048)
							(mid 0.275042 0.275042)
							(end 0.3048 0.2032)
						)
					)
					(width 0)
					(fill yes)
				)
			)
		)
	)
	(footprint ""
		(layer "F.Cu")
		(at 158.88081 -44.823634 -90)
		(property "Reference" "X2"
			(at 0 0 270)
			(layer "F.SilkS")
			(hide yes)
			(effects
				(font
					(size 1.27 1.27)
				)
			)
		)
		(property "Value" "XTAL-25MHZ-295-GP"
			(at -4.4958 -3.3782 270)
			(unlocked yes)
			(layer "F.Fab")
			(hide yes)
			(effects
				(font
					(size 1.016 1.016)
					(thickness 0.1524)
				)
			)
		)
		(property "Device Type" "SMD-OSC38H20"
			(at -4.4958 -4.9022 270)
			(unlocked yes)
			(layer "F.Fab")
			(hide yes)
			(effects
				(font
					(size 1.016 1.016)
					(thickness 0.1524)
				)
			)
		)
		(duplicate_pad_numbers_are_jumpers no)
		(fp_line
			(start -1.668272 1.2065)
			(end -1.668272 0.462788)
			(stroke
				(width 0.3302)
				(type default)
			)
			(layer "F.SilkS")
		)
		(fp_line
			(start -0.659384 1.2065)
			(end -1.668272 1.2065)
			(stroke
				(width 0.3302)
				(type default)
			)
			(layer "F.SilkS")
		)
		(fp_line
			(start -1.5748 1.1176)
			(end -1.5748 -1.1176)
			(stroke
				(width 0.1524)
				(type default)
			)
			(layer "F.SilkS")
		)
		(fp_line
			(start 1.5748 1.1176)
			(end -1.5748 1.1176)
			(stroke
				(width 0.1524)
				(type default)
			)
			(layer "F.SilkS")
		)
		(fp_line
			(start -1.5748 -1.1176)
			(end 1.5748 -1.1176)
			(stroke
				(width 0.1524)
				(type default)
			)
			(layer "F.SilkS")
		)
		(fp_line
			(start 1.5748 -1.1176)
			(end 1.5748 1.1176)
			(stroke
				(width 0.1524)
				(type default)
			)
			(layer "F.SilkS")
		)
		(fp_poly
			(pts
				(xy -2.286 1.1557) (xy -2.286 -0.1143) (xy -1.651 0.5207)
			)
			(stroke
				(width 0)
				(type default)
			)
			(fill yes)
			(layer "F.SilkS")
		)
		(fp_rect
			(start -1.0033 0.8001)
			(end 1.0033 -0.8001)
			(stroke
				(width 0)
				(type default)
			)
			(fill no)
			(layer "F.CrtYd")
		)
		(fp_poly
			(pts
				(xy -1.8288 1.3716) (xy -1.8288 -1.3716) (xy 1.8288 -1.3716) (xy 1.8288 -0.0127) (xy 1.0033 -0.0127)
				(xy 1.0033 -0.8001) (xy -1.0033 -0.8001) (xy -1.0033 0.8001) (xy 1.0033 0.8001) (xy 1.0033 0) (xy 1.8288 0)
				(xy 1.8288 1.3716)
			)
			(stroke
				(width 0)
				(type default)
			)
			(fill no)
			(layer "F.CrtYd")
		)
		(fp_rect
			(start -1.8288 1.3716)
			(end 1.8288 -1.3716)
			(stroke
				(width 0)
				(type default)
			)
			(fill no)
			(layer "F.Fab")
		)
		(pad "1" smd rect
			(at -0.769112 0.495046 270)
			(size 1.0922 0.7366)
			(layers "F.Cu" "F.Mask" "F.Paste")
			(net "REF_CLK")
		)
		(pad "2" smd rect
			(at 0.769112 0.495046 270)
			(size 1.0922 0.7366)
			(layers "F.Cu" "F.Mask" "F.Paste")
			(net "GND")
		)
		(pad "3" smd rect
			(at 0.769112 -0.495046 270)
			(size 1.0922 0.7366)
			(layers "F.Cu" "F.Mask" "F.Paste")
			(net "IOC_REF_CLK_P")
		)
		(pad "4" smd rect
			(at -0.769112 -0.495046 270)
			(size 1.0922 0.7366)
			(layers "F.Cu" "F.Mask" "F.Paste")
			(net "GND")
		)
		(zone
			(layer "F.Cu")
			(hatch none 0.5)
			(connect_pads
				(clearance 0)
			)
			(min_thickness 0.25)
			(keepout
				(tracks not_allowed)
				(vias allowed)
				(pads allowed)
				(copperpour not_allowed)
				(footprints allowed)
			)
			(placement
				(enabled no)
				(sheetname "")
			)
			(fill
				(thermal_gap 0.5)
				(thermal_bridge_width 0.5)
				(island_removal_mode 0)
			)
			(polygon
				(pts
					(xy 158.017464 -45.046646) (xy 158.754064 -45.046646) (xy 158.754064 -46.138846) (xy 159.007556 -46.138846)
					(xy 159.007556 -45.046646) (xy 159.744156 -45.046646) (xy 159.744156 -44.600622) (xy 159.007556 -44.600622)
					(xy 159.007556 -43.508422) (xy 158.754064 -43.508422) (xy 158.754064 -44.600622) (xy 158.017464 -44.600622)
				)
			)
		)
		(zone
			(layer "F.Cu")
			(hatch none 0.5)
			(connect_pads
				(clearance 0)
			)
			(min_thickness 0.25)
			(keepout
				(tracks allowed)
				(vias not_allowed)
				(pads allowed)
				(copperpour not_allowed)
				(footprints allowed)
			)
			(placement
				(enabled no)
				(sheetname "")
			)
			(fill
				(thermal_gap 0.5)
				(thermal_bridge_width 0.5)
				(island_removal_mode 0)
			)
			(polygon
				(pts
					(xy 158.017464 -45.046646) (xy 158.754064 -45.046646) (xy 158.754064 -46.138846) (xy 159.007556 -46.138846)
					(xy 159.007556 -45.046646) (xy 159.744156 -45.046646) (xy 159.744156 -44.600622) (xy 159.007556 -44.600622)
					(xy 159.007556 -43.508422) (xy 158.754064 -43.508422) (xy 158.754064 -44.600622) (xy 158.017464 -44.600622)
				)
			)
		)
	)
	(footprint ""
		(layer "F.Cu")
		(at 71.9074 -107.0356)
		(property "Reference" "R512"
			(at 0 0 0)
			(layer "F.SilkS")
			(hide yes)
			(effects
				(font
					(size 1.27 1.27)
				)
			)
		)
		(property "Value" "10R3F-GP"
			(at -0.0254 -2.5146 0)
			(unlocked yes)
			(layer "F.Fab")
			(hide yes)
			(effects
				(font
					(size 1.016 1.016)
					(thickness 0.1524)
				)
			)
		)
		(property "Device Type" "R603H22"
			(at -0.0254 -4.0386 0)
			(unlocked yes)
			(layer "F.Fab")
			(hide yes)
			(effects
				(font
					(size 1.016 1.016)
					(thickness 0.1524)
				)
			)
		)
		(duplicate_pad_numbers_are_jumpers no)
		(fp_line
			(start -0.4826 0)
			(end -0.2032 0)
			(stroke
				(width 0.2032)
				(type default)
			)
			(layer "F.SilkS")
		)
		(fp_line
			(start 0.2032 0)
			(end 0.4826 0)
			(stroke
				(width 0.2032)
				(type default)
			)
			(layer "F.SilkS")
		)
		(fp_rect
			(start -0.5842 1.3335)
			(end 0.5842 -1.3335)
			(stroke
				(width 0)
				(type default)
			)
			(fill no)
			(layer "F.CrtYd")
		)
		(fp_rect
			(start -0.5842 1.3335)
			(end 0.5842 -1.3335)
			(stroke
				(width 0)
				(type default)
			)
			(fill no)
			(layer "F.Fab")
		)
		(pad "1" smd custom
			(at 0 -0.762)
			(size 0.2159 0.2159)
			(layers "F.Cu" "F.Mask" "F.Paste")
			(net "P3V3_OUT")
			(options
				(clearance outline)
				(anchor circle)
			)
			(primitives
				(gr_poly
					(pts
						(arc
							(start -0.3302 -0.4318)
							(mid -0.402042 -0.402042)
							(end -0.4318 -0.3302)
						)
						(arc
							(start -0.4318 0.3302)
							(mid -0.402042 0.402042)
							(end -0.3302 0.4318)
						)
						(arc
							(start 0.3302 0.4318)
							(mid 0.402042 0.402042)
							(end 0.4318 0.3302)
						)
						(arc
							(start 0.4318 -0.3302)
							(mid 0.402042 -0.402042)
							(end 0.3302 -0.4318)
						)
					)
					(width 0)
					(fill yes)
				)
			)
		)
		(pad "2" smd custom
			(at 0 0.762)
			(size 0.2159 0.2159)
			(layers "F.Cu" "F.Mask" "F.Paste")
			(net "P3V3_VFB_R")
			(options
				(clearance outline)
				(anchor circle)
			)
			(primitives
				(gr_poly
					(pts
						(arc
							(start -0.3302 -0.4318)
							(mid -0.402042 -0.402042)
							(end -0.4318 -0.3302)
						)
						(arc
							(start -0.4318 0.3302)
							(mid -0.402042 0.402042)
							(end -0.3302 0.4318)
						)
						(arc
							(start 0.3302 0.4318)
							(mid 0.402042 0.402042)
							(end 0.4318 0.3302)
						)
						(arc
							(start 0.4318 -0.3302)
							(mid 0.402042 -0.402042)
							(end 0.3302 -0.4318)
						)
					)
					(width 0)
					(fill yes)
				)
			)
		)
	)
	(footprint ""
		(layer "F.Cu")
		(at 8.5598 -57.2008)
		(property "Reference" "R688"
			(at 0 0 0)
			(layer "F.SilkS")
			(hide yes)
			(effects
				(font
					(size 1.27 1.27)
				)
			)
		)
		(property "Value" "10KR2F-2-GP"
			(at 0.064008 -3.993896 0)
			(unlocked yes)
			(layer "F.Fab")
			(hide yes)
			(effects
				(font
					(size 1.016 1.016)
					(thickness 0.1524)
				)
			)
		)
		(property "Device Type" "R402H16"
			(at 0.064008 -5.517896 0)
			(unlocked yes)
			(layer "F.Fab")
			(hide yes)
			(effects
				(font
					(size 1.016 1.016)
					(thickness 0.1524)
				)
			)
		)
		(duplicate_pad_numbers_are_jumpers no)
		(fp_line
			(start -0.508 -0.9398)
			(end -0.508 0.9398)
			(stroke
				(width 0.1524)
				(type default)
			)
			(layer "F.SilkS")
		)
		(fp_line
			(start 0.508 -0.9398)
			(end -0.508 -0.9398)
			(stroke
				(width 0.1524)
				(type default)
			)
			(layer "F.SilkS")
		)
		(fp_rect
			(start -0.508 0.9398)
			(end 0.508 -0.9398)
			(stroke
				(width 0)
				(type default)
			)
			(fill no)
			(layer "F.CrtYd")
		)
		(fp_rect
			(start -0.508 0.9398)
			(end 0.508 -0.9398)
			(stroke
				(width 0)
				(type default)
			)
			(fill no)
			(layer "F.Fab")
		)
		(pad "1" smd custom
			(at 0 -0.4445)
			(size 0.1397 0.1397)
			(layers "F.Cu" "F.Mask" "F.Paste")
			(net "GND")
			(options
				(clearance outline)
				(anchor circle)
			)
			(primitives
				(gr_poly
					(pts
						(arc
							(start -0.1778 -0.2794)
							(mid -0.249642 -0.249642)
							(end -0.2794 -0.1778)
						)
						(arc
							(start -0.2794 0.1778)
							(mid -0.249642 0.249642)
							(end -0.1778 0.2794)
						)
						(arc
							(start 0.1778 0.2794)
							(mid 0.249642 0.249642)
							(end 0.2794 0.1778)
						)
						(arc
							(start 0.2794 -0.1778)
							(mid 0.249642 -0.249642)
							(end 0.1778 -0.2794)
						)
					)
					(width 0)
					(fill yes)
				)
			)
		)
		(pad "2" smd custom
			(at 0 0.4445)
			(size 0.1397 0.1397)
			(layers "F.Cu" "F.Mask" "F.Paste")
			(net "MB0_RETRY_R")
			(options
				(clearance outline)
				(anchor circle)
			)
			(primitives
				(gr_poly
					(pts
						(arc
							(start -0.1778 -0.2794)
							(mid -0.249642 -0.249642)
							(end -0.2794 -0.1778)
						)
						(arc
							(start -0.2794 0.1778)
							(mid -0.249642 0.249642)
							(end -0.1778 0.2794)
						)
						(arc
							(start 0.1778 0.2794)
							(mid 0.249642 0.249642)
							(end 0.2794 0.1778)
						)
						(arc
							(start 0.2794 -0.1778)
							(mid 0.249642 -0.249642)
							(end 0.1778 -0.2794)
						)
					)
					(width 0)
					(fill yes)
				)
			)
		)
	)
	(footprint ""
		(layer "F.Cu")
		(at 70.485 -39.751 90)
		(property "Reference" "L14"
			(at 0 0 90)
			(layer "F.SilkS")
			(hide yes)
			(effects
				(font
					(size 1.27 1.27)
				)
			)
		)
		(property "Value" "MPZ2012S300AT-GP"
			(at 0 -4.2418 90)
			(unlocked yes)
			(layer "F.Fab")
			(hide yes)
			(effects
				(font
					(size 1.016 1.016)
					(thickness 0.1524)
				)
			)
		)
		(property "Device Type" "L805H42"
			(at 0 -5.7912 90)
			(unlocked yes)
			(layer "F.Fab")
			(hide yes)
			(effects
				(font
					(size 1.016 1.016)
					(thickness 0.1524)
				)
			)
		)
		(duplicate_pad_numbers_are_jumpers no)
		(fp_line
			(start 0.889 -1.7018)
			(end 0.889 1.7018)
			(stroke
				(width 0.1524)
				(type default)
			)
			(layer "F.SilkS")
		)
		(fp_line
			(start -0.889 -1.7018)
			(end 0.889 -1.7018)
			(stroke
				(width 0.1524)
				(type default)
			)
			(layer "F.SilkS")
		)
		(fp_line
			(start 0.889 1.7018)
			(end -0.889 1.7018)
			(stroke
				(width 0.1524)
				(type default)
			)
			(layer "F.SilkS")
		)
		(fp_line
			(start -0.889 1.7018)
			(end -0.889 -1.7018)
			(stroke
				(width 0.1524)
				(type default)
			)
			(layer "F.SilkS")
		)
		(fp_rect
			(start -0.9652 1.778)
			(end 0.9652 -1.778)
			(stroke
				(width 0)
				(type default)
			)
			(fill no)
			(layer "F.CrtYd")
		)
		(fp_rect
			(start -0.9652 1.778)
			(end 0.9652 -1.778)
			(stroke
				(width 0)
				(type default)
			)
			(fill no)
			(layer "F.Fab")
		)
		(pad "1" smd rect
			(at 0 -0.9652 90)
			(size 1.397 1.143)
			(layers "F.Cu" "F.Mask" "F.Paste")
			(net "P0V9")
		)
		(pad "2" smd rect
			(at 0 0.9652 90)
			(size 1.397 1.143)
			(layers "F.Cu" "F.Mask" "F.Paste")
			(net "GB_VDDA")
		)
	)
	(footprint ""
		(layer "F.Cu")
		(at 173.4058 -59.817 180)
		(property "Reference" "R275"
			(at 0 0 180)
			(layer "F.SilkS")
			(hide yes)
			(effects
				(font
					(size 1.27 1.27)
				)
			)
		)
		(property "Value" "4K7R2F-GP"
			(at 0.064008 -3.993896 180)
			(unlocked yes)
			(layer "F.Fab")
			(hide yes)
			(effects
				(font
					(size 1.016 1.016)
					(thickness 0.1524)
				)
			)
		)
		(property "Device Type" "R402H16"
			(at 0.064008 -5.517896 180)
			(unlocked yes)
			(layer "F.Fab")
			(hide yes)
			(effects
				(font
					(size 1.016 1.016)
					(thickness 0.1524)
				)
			)
		)
		(duplicate_pad_numbers_are_jumpers no)
		(fp_line
			(start 0.508 -0.9398)
			(end -0.508 -0.9398)
			(stroke
				(width 0.1524)
				(type default)
			)
			(layer "F.SilkS")
		)
		(fp_line
			(start -0.508 -0.9398)
			(end -0.508 0.9398)
			(stroke
				(width 0.1524)
				(type default)
			)
			(layer "F.SilkS")
		)
		(fp_rect
			(start -0.508 0.9398)
			(end 0.508 -0.9398)
			(stroke
				(width 0)
				(type default)
			)
			(fill no)
			(layer "F.CrtYd")
		)
		(fp_rect
			(start -0.508 0.9398)
			(end 0.508 -0.9398)
			(stroke
				(width 0)
				(type default)
			)
			(fill no)
			(layer "F.Fab")
		)
		(pad "1" smd custom
			(at 0 -0.4445 180)
			(size 0.1397 0.1397)
			(layers "F.Cu" "F.Mask" "F.Paste")
			(net "IOC_TRST_N")
			(options
				(clearance outline)
				(anchor circle)
			)
			(primitives
				(gr_poly
					(pts
						(arc
							(start -0.1778 -0.2794)
							(mid -0.249642 -0.249642)
							(end -0.2794 -0.1778)
						)
						(arc
							(start -0.2794 0.1778)
							(mid -0.249642 0.249642)
							(end -0.1778 0.2794)
						)
						(arc
							(start 0.1778 0.2794)
							(mid 0.249642 0.249642)
							(end 0.2794 0.1778)
						)
						(arc
							(start 0.2794 -0.1778)
							(mid 0.249642 -0.249642)
							(end 0.1778 -0.2794)
						)
					)
					(width 0)
					(fill yes)
				)
			)
		)
		(pad "2" smd custom
			(at 0 0.4445 180)
			(size 0.1397 0.1397)
			(layers "F.Cu" "F.Mask" "F.Paste")
			(net "GND")
			(options
				(clearance outline)
				(anchor circle)
			)
			(primitives
				(gr_poly
					(pts
						(arc
							(start -0.1778 -0.2794)
							(mid -0.249642 -0.249642)
							(end -0.2794 -0.1778)
						)
						(arc
							(start -0.2794 0.1778)
							(mid -0.249642 0.249642)
							(end -0.1778 0.2794)
						)
						(arc
							(start 0.1778 0.2794)
							(mid 0.249642 0.249642)
							(end 0.2794 0.1778)
						)
						(arc
							(start 0.2794 -0.1778)
							(mid 0.249642 -0.249642)
							(end 0.1778 -0.2794)
						)
					)
					(width 0)
					(fill yes)
				)
			)
		)
	)
	(footprint ""
		(layer "F.Cu")
		(at 157.2006 -81.5594 180)
		(property "Reference" "R322"
			(at 0 0 180)
			(layer "F.SilkS")
			(hide yes)
			(effects
				(font
					(size 1.27 1.27)
				)
			)
		)
		(property "Value" "1KR2F-3-GP"
			(at 0.064008 -3.993896 180)
			(unlocked yes)
			(layer "F.Fab")
			(hide yes)
			(effects
				(font
					(size 1.016 1.016)
					(thickness 0.1524)
				)
			)
		)
		(property "Device Type" "R402H16"
			(at 0.064008 -5.517896 180)
			(unlocked yes)
			(layer "F.Fab")
			(hide yes)
			(effects
				(font
					(size 1.016 1.016)
					(thickness 0.1524)
				)
			)
		)
		(duplicate_pad_numbers_are_jumpers no)
		(fp_line
			(start 0.508 -0.9398)
			(end -0.508 -0.9398)
			(stroke
				(width 0.1524)
				(type default)
			)
			(layer "F.SilkS")
		)
		(fp_line
			(start -0.508 -0.9398)
			(end -0.508 0.9398)
			(stroke
				(width 0.1524)
				(type default)
			)
			(layer "F.SilkS")
		)
		(fp_rect
			(start -0.508 0.9398)
			(end 0.508 -0.9398)
			(stroke
				(width 0)
				(type default)
			)
			(fill no)
			(layer "F.CrtYd")
		)
		(fp_rect
			(start -0.508 0.9398)
			(end 0.508 -0.9398)
			(stroke
				(width 0)
				(type default)
			)
			(fill no)
			(layer "F.Fab")
		)
		(pad "1" smd custom
			(at 0 -0.4445 180)
			(size 0.1397 0.1397)
			(layers "F.Cu" "F.Mask" "F.Paste")
			(net "P1V5_E")
			(options
				(clearance outline)
				(anchor circle)
			)
			(primitives
				(gr_poly
					(pts
						(arc
							(start -0.1778 -0.2794)
							(mid -0.249642 -0.249642)
							(end -0.2794 -0.1778)
						)
						(arc
							(start -0.2794 0.1778)
							(mid -0.249642 0.249642)
							(end -0.1778 0.2794)
						)
						(arc
							(start 0.1778 0.2794)
							(mid 0.249642 0.249642)
							(end 0.2794 0.1778)
						)
						(arc
							(start 0.2794 -0.1778)
							(mid 0.249642 -0.249642)
							(end 0.1778 -0.2794)
						)
					)
					(width 0)
					(fill yes)
				)
			)
		)
		(pad "2" smd custom
			(at 0 0.4445 180)
			(size 0.1397 0.1397)
			(layers "F.Cu" "F.Mask" "F.Paste")
			(net "P1V5_E_SENSE")
			(options
				(clearance outline)
				(anchor circle)
			)
			(primitives
				(gr_poly
					(pts
						(arc
							(start -0.1778 -0.2794)
							(mid -0.249642 -0.249642)
							(end -0.2794 -0.1778)
						)
						(arc
							(start -0.2794 0.1778)
							(mid -0.249642 0.249642)
							(end -0.1778 0.2794)
						)
						(arc
							(start 0.1778 0.2794)
							(mid 0.249642 0.249642)
							(end 0.2794 0.1778)
						)
						(arc
							(start 0.2794 -0.1778)
							(mid 0.249642 -0.249642)
							(end 0.1778 -0.2794)
						)
					)
					(width 0)
					(fill yes)
				)
			)
		)
	)
	(footprint ""
		(layer "F.Cu")
		(at 186.820048 -100.00361 180)
		(property "Reference" "L27"
			(at 0 0 180)
			(layer "F.SilkS")
			(hide yes)
			(effects
				(font
					(size 1.27 1.27)
				)
			)
		)
		(property "Value" "28F0181-1SR-10-GP"
			(at -4.064 -3.5052 180)
			(unlocked yes)
			(layer "F.Fab")
			(hide yes)
			(effects
				(font
					(size 1.016 1.016)
					(thickness 0.1524)
				)
			)
		)
		(property "Device Type" "L9546-152127H121"
			(at -4.064 -5.0292 180)
			(unlocked yes)
			(layer "F.Fab")
			(hide yes)
			(effects
				(font
					(size 1.016 1.016)
					(thickness 0.1524)
				)
			)
		)
		(duplicate_pad_numbers_are_jumpers no)
		(fp_line
			(start 2.54 5.6642)
			(end 2.54 -5.6642)
			(stroke
				(width 0.1524)
				(type default)
			)
			(layer "F.SilkS")
		)
		(fp_line
			(start 2.54 -5.6642)
			(end -2.54 -5.6642)
			(stroke
				(width 0.1524)
				(type default)
			)
			(layer "F.SilkS")
		)
		(fp_line
			(start -2.54 5.6642)
			(end 2.54 5.6642)
			(stroke
				(width 0.1524)
				(type default)
			)
			(layer "F.SilkS")
		)
		(fp_line
			(start -2.54 -5.6642)
			(end -2.54 5.6642)
			(stroke
				(width 0.1524)
				(type default)
			)
			(layer "F.SilkS")
		)
		(fp_rect
			(start -2.286 4.7625)
			(end 2.286 -4.7625)
			(stroke
				(width 0)
				(type default)
			)
			(fill no)
			(layer "F.CrtYd")
		)
		(fp_poly
			(pts
				(xy -2.794 5.7404) (xy -2.794 -5.7404) (xy 2.794 -5.7404) (xy 2.794 5.7404) (xy 0.00254 5.7404)
				(xy 0.00254 4.7625) (xy 2.286 4.7625) (xy 2.286 -4.7625) (xy -2.286 -4.7625) (xy -2.286 4.7625)
				(xy -0.00254 4.7625) (xy -0.00254 5.7404)
			)
			(stroke
				(width 0)
				(type default)
			)
			(fill no)
			(layer "F.CrtYd")
		)
		(fp_rect
			(start -2.794 5.7404)
			(end 2.794 -5.7404)
			(stroke
				(width 0)
				(type default)
			)
			(fill no)
			(layer "F.Fab")
		)
		(pad "1" smd rect
			(at 0 -4.197604 180)
			(size 1.524 2.413)
			(layers "F.Cu" "F.Mask" "F.Paste")
			(net "P0V975")
		)
		(pad "2" smd rect
			(at 0 4.197604 180)
			(size 1.524 2.413)
			(layers "F.Cu" "F.Mask" "F.Paste")
			(net "SAS0_AVDD")
		)
	)
	(footprint ""
		(layer "F.Cu")
		(at 56.896 -115.951 -90)
		(property "Reference" "TC4"
			(at 0 0 270)
			(layer "F.SilkS")
			(hide yes)
			(effects
				(font
					(size 1.27 1.27)
				)
			)
		)
		(property "Value" "ST150U6D3VDM-28-GP"
			(at 0 -9.6012 270)
			(unlocked yes)
			(layer "F.Fab")
			(hide yes)
			(effects
				(font
					(size 1.016 1.016)
					(thickness 0.1524)
				)
			)
		)
		(property "Device Type" "CT7343H83"
			(at 0 -11.1252 270)
			(unlocked yes)
			(layer "F.Fab")
			(hide yes)
			(effects
				(font
					(size 1.016 1.016)
					(thickness 0.1524)
				)
			)
		)
		(duplicate_pad_numbers_are_jumpers no)
		(fp_line
			(start -2.286 4.8768)
			(end -2.286 2.032)
			(stroke
				(width 0.1524)
				(type default)
			)
			(layer "F.SilkS")
		)
		(fp_line
			(start 2.286 4.8768)
			(end -2.286 4.8768)
			(stroke
				(width 0.1524)
				(type default)
			)
			(layer "F.SilkS")
		)
		(fp_line
			(start 2.286 2.032)
			(end 2.286 4.8768)
			(stroke
				(width 0.1524)
				(type default)
			)
			(layer "F.SilkS")
		)
		(fp_line
			(start 2.286 -2.032)
			(end 2.286 -4.8768)
			(stroke
				(width 0.1524)
				(type default)
			)
			(layer "F.SilkS")
		)
		(fp_line
			(start 2.1082 -4.699)
			(end -2.1082 -4.699)
			(stroke
				(width 0.508)
				(type default)
			)
			(layer "F.SilkS")
		)
		(fp_line
			(start -2.286 -4.8768)
			(end -2.286 -2.032)
			(stroke
				(width 0.1524)
				(type default)
			)
			(layer "F.SilkS")
		)
		(fp_line
			(start 2.286 -4.8768)
			(end -2.286 -4.8768)
			(stroke
				(width 0.1524)
				(type default)
			)
			(layer "F.SilkS")
		)
		(fp_rect
			(start -2.1463 3.6449)
			(end 2.1463 -3.6449)
			(stroke
				(width 0)
				(type default)
			)
			(fill no)
			(layer "F.CrtYd")
		)
		(fp_poly
			(pts
				(xy -2.54 4.953) (xy -2.54 4.2926) (xy -3.81 4.2926) (xy -3.81 -4.2926) (xy -2.54 -4.2926) (xy -2.54 -4.953)
				(xy 2.54 -4.953) (xy 2.54 -4.2926) (xy 3.81 -4.2926) (xy 3.81 -1.6256) (xy 2.1463 -1.6256) (xy 2.1463 -3.6449)
				(xy -2.1463 -3.6449) (xy -2.1463 3.6449) (xy 2.1463 3.6449) (xy 2.1463 -1.6129) (xy 3.81 -1.6129)
				(xy 3.81 4.2926) (xy 2.54 4.2926) (xy 2.54 4.953)
			)
			(stroke
				(width 0)
				(type default)
			)
			(fill no)
			(layer "F.CrtYd")
		)
		(fp_rect
			(start -2.54 4.953)
			(end 2.54 -4.953)
			(stroke
				(width 0)
				(type default)
			)
			(fill no)
			(layer "F.Fab")
		)
		(fp_rect
			(start -3.81 4.2926)
			(end -2.54 -4.2926)
			(stroke
				(width 0)
				(type default)
			)
			(fill no)
			(layer "F.Fab")
		)
		(fp_rect
			(start 2.54 4.2926)
			(end 3.81 -4.2926)
			(stroke
				(width 0)
				(type default)
			)
			(fill no)
			(layer "F.Fab")
		)
		(pad "1" smd rect
			(at 0 -3.1496 270)
			(size 2.413 2.286)
			(layers "F.Cu" "F.Mask" "F.Paste")
			(net "P3V3_OUT")
		)
		(pad "2" smd rect
			(at 0 3.1496 270)
			(size 2.413 2.286)
			(layers "F.Cu" "F.Mask" "F.Paste")
			(net "GND")
		)
		(zone
			(layer "F.Cu")
			(hatch none 0.5)
			(connect_pads
				(clearance 0)
			)
			(min_thickness 0.25)
			(keepout
				(tracks allowed)
				(vias not_allowed)
				(pads allowed)
				(copperpour not_allowed)
				(footprints allowed)
			)
			(placement
				(enabled no)
				(sheetname "")
			)
			(fill
				(thermal_gap 0.5)
				(thermal_bridge_width 0.5)
				(island_removal_mode 0)
			)
			(polygon
				(pts
					(xy 52.2986 -117.4623) (xy 52.2986 -114.4397) (xy 55.1942 -114.4397) (xy 55.5244 -114.4397) (xy 55.5244 -117.4623)
					(xy 55.1942 -117.4623)
				)
			)
		)
		(zone
			(layer "F.Cu")
			(hatch none 0.5)
			(connect_pads
				(clearance 0)
			)
			(min_thickness 0.25)
			(keepout
				(tracks allowed)
				(vias not_allowed)
				(pads allowed)
				(copperpour not_allowed)
				(footprints allowed)
			)
			(placement
				(enabled no)
				(sheetname "")
			)
			(fill
				(thermal_gap 0.5)
				(thermal_bridge_width 0.5)
				(island_removal_mode 0)
			)
			(polygon
				(pts
					(xy 58.5851 -114.4397) (xy 61.4934 -114.4397) (xy 61.4934 -117.4623) (xy 58.5978 -117.4623) (xy 58.2676 -117.4623)
					(xy 58.2676 -114.4397)
				)
			)
		)
	)
	(footprint ""
		(layer "F.Cu")
		(at 41.0972 -28.8036 -90)
		(property "Reference" "R397"
			(at 0 0 270)
			(layer "F.SilkS")
			(hide yes)
			(effects
				(font
					(size 1.27 1.27)
				)
			)
		)
		(property "Value" "4K7R2F-GP"
			(at 0.064008 -3.993896 270)
			(unlocked yes)
			(layer "F.Fab")
			(hide yes)
			(effects
				(font
					(size 1.016 1.016)
					(thickness 0.1524)
				)
			)
		)
		(property "Device Type" "R402H16"
			(at 0.064008 -5.517896 270)
			(unlocked yes)
			(layer "F.Fab")
			(hide yes)
			(effects
				(font
					(size 1.016 1.016)
					(thickness 0.1524)
				)
			)
		)
		(duplicate_pad_numbers_are_jumpers no)
		(fp_line
			(start -0.508 -0.9398)
			(end -0.508 0.9398)
			(stroke
				(width 0.1524)
				(type default)
			)
			(layer "F.SilkS")
		)
		(fp_line
			(start 0.508 -0.9398)
			(end -0.508 -0.9398)
			(stroke
				(width 0.1524)
				(type default)
			)
			(layer "F.SilkS")
		)
		(fp_rect
			(start -0.508 0.9398)
			(end 0.508 -0.9398)
			(stroke
				(width 0)
				(type default)
			)
			(fill no)
			(layer "F.CrtYd")
		)
		(fp_rect
			(start -0.508 0.9398)
			(end 0.508 -0.9398)
			(stroke
				(width 0)
				(type default)
			)
			(fill no)
			(layer "F.Fab")
		)
		(pad "1" smd custom
			(at 0 -0.4445 270)
			(size 0.1397 0.1397)
			(layers "F.Cu" "F.Mask" "F.Paste")
			(net "P0V9_U8_PG")
			(options
				(clearance outline)
				(anchor circle)
			)
			(primitives
				(gr_poly
					(pts
						(arc
							(start -0.1778 -0.2794)
							(mid -0.249642 -0.249642)
							(end -0.2794 -0.1778)
						)
						(arc
							(start -0.2794 0.1778)
							(mid -0.249642 0.249642)
							(end -0.1778 0.2794)
						)
						(arc
							(start 0.1778 0.2794)
							(mid 0.249642 0.249642)
							(end 0.2794 0.1778)
						)
						(arc
							(start 0.2794 -0.1778)
							(mid 0.249642 -0.249642)
							(end 0.1778 -0.2794)
						)
					)
					(width 0)
					(fill yes)
				)
			)
		)
		(pad "2" smd custom
			(at 0 0.4445 270)
			(size 0.1397 0.1397)
			(layers "F.Cu" "F.Mask" "F.Paste")
			(net "P3V3")
			(options
				(clearance outline)
				(anchor circle)
			)
			(primitives
				(gr_poly
					(pts
						(arc
							(start -0.1778 -0.2794)
							(mid -0.249642 -0.249642)
							(end -0.2794 -0.1778)
						)
						(arc
							(start -0.2794 0.1778)
							(mid -0.249642 0.249642)
							(end -0.1778 0.2794)
						)
						(arc
							(start 0.1778 0.2794)
							(mid 0.249642 0.249642)
							(end 0.2794 0.1778)
						)
						(arc
							(start 0.2794 -0.1778)
							(mid 0.249642 -0.249642)
							(end 0.1778 -0.2794)
						)
					)
					(width 0)
					(fill yes)
				)
			)
		)
	)
	(footprint ""
		(layer "F.Cu")
		(at 65.786 -109.474 90)
		(property "Reference" "C713"
			(at 0 0 90)
			(layer "F.SilkS")
			(hide yes)
			(effects
				(font
					(size 1.27 1.27)
				)
			)
		)
		(property "Value" "SCD1U50V3KX-GP"
			(at 0 -2.8194 90)
			(unlocked yes)
			(layer "F.Fab")
			(hide yes)
			(effects
				(font
					(size 1.016 1.016)
					(thickness 0.1524)
				)
			)
		)
		(property "Device Type" "C603H36"
			(at 0 -4.3434 90)
			(unlocked yes)
			(layer "F.Fab")
			(hide yes)
			(effects
				(font
					(size 1.016 1.016)
					(thickness 0.1524)
				)
			)
		)
		(duplicate_pad_numbers_are_jumpers no)
		(fp_line
			(start 0.508 0)
			(end -0.508 0)
			(stroke
				(width 0.2032)
				(type default)
			)
			(layer "F.SilkS")
		)
		(fp_rect
			(start -0.5842 1.3335)
			(end 0.5842 -1.3335)
			(stroke
				(width 0)
				(type default)
			)
			(fill no)
			(layer "F.CrtYd")
		)
		(fp_rect
			(start -0.5842 1.3335)
			(end 0.5842 -1.3335)
			(stroke
				(width 0)
				(type default)
			)
			(fill no)
			(layer "F.Fab")
		)
		(pad "1" smd custom
			(at 0 -0.762 90)
			(size 0.2159 0.2159)
			(layers "F.Cu" "F.Mask" "F.Paste")
			(net "P3V3_OUT")
			(options
				(clearance outline)
				(anchor circle)
			)
			(primitives
				(gr_poly
					(pts
						(arc
							(start -0.3302 -0.4318)
							(mid -0.402042 -0.402042)
							(end -0.4318 -0.3302)
						)
						(arc
							(start -0.4318 0.3302)
							(mid -0.402042 0.402042)
							(end -0.3302 0.4318)
						)
						(arc
							(start 0.3302 0.4318)
							(mid 0.402042 0.402042)
							(end 0.4318 0.3302)
						)
						(arc
							(start 0.4318 -0.3302)
							(mid 0.402042 -0.402042)
							(end 0.3302 -0.4318)
						)
					)
					(width 0)
					(fill yes)
				)
			)
		)
		(pad "2" smd custom
			(at 0 0.762 90)
			(size 0.2159 0.2159)
			(layers "F.Cu" "F.Mask" "F.Paste")
			(net "P3V3_LL_R")
			(options
				(clearance outline)
				(anchor circle)
			)
			(primitives
				(gr_poly
					(pts
						(arc
							(start -0.3302 -0.4318)
							(mid -0.402042 -0.402042)
							(end -0.4318 -0.3302)
						)
						(arc
							(start -0.4318 0.3302)
							(mid -0.402042 0.402042)
							(end -0.3302 0.4318)
						)
						(arc
							(start 0.3302 0.4318)
							(mid 0.402042 0.402042)
							(end 0.4318 0.3302)
						)
						(arc
							(start 0.4318 -0.3302)
							(mid 0.402042 -0.402042)
							(end 0.3302 -0.4318)
						)
					)
					(width 0)
					(fill yes)
				)
			)
		)
	)
	(footprint ""
		(layer "F.Cu")
		(at 85.471 -74.41692 -90)
		(property "Reference" "Q2"
			(at 0 0 270)
			(layer "F.SilkS")
			(hide yes)
			(effects
				(font
					(size 1.27 1.27)
				)
			)
		)
		(property "Value" "SSM3K324R-GP"
			(at 0.127 -8.9662 270)
			(unlocked yes)
			(layer "F.Fab")
			(hide yes)
			(effects
				(font
					(size 1.016 1.016)
					(thickness 0.1524)
				)
			)
		)
		(property "Device Type" "SOT23DGS2D4H35"
			(at 0.127 -10.4902 270)
			(unlocked yes)
			(layer "F.Fab")
			(hide yes)
			(effects
				(font
					(size 1.016 1.016)
					(thickness 0.1524)
				)
			)
		)
		(duplicate_pad_numbers_are_jumpers no)
		(fp_line
			(start -1.651 1.778)
			(end 1.651 1.778)
			(stroke
				(width 0.1524)
				(type default)
			)
			(layer "F.SilkS")
		)
		(fp_line
			(start 1.651 1.778)
			(end 1.651 -1.778)
			(stroke
				(width 0.1524)
				(type default)
			)
			(layer "F.SilkS")
		)
		(fp_line
			(start -1.651 -1.778)
			(end -1.651 1.778)
			(stroke
				(width 0.1524)
				(type default)
			)
			(layer "F.SilkS")
		)
		(fp_line
			(start 1.651 -1.778)
			(end -1.651 -1.778)
			(stroke
				(width 0.1524)
				(type default)
			)
			(layer "F.SilkS")
		)
		(fp_poly
			(pts
				(xy -1.778 1.8796) (xy -1.778 -1.8796) (xy 1.778 -1.8796) (xy 1.778 1.8796)
			)
			(stroke
				(width 0)
				(type default)
			)
			(fill no)
			(layer "F.CrtYd")
		)
		(fp_poly
			(pts
				(xy -1.778 1.8796) (xy -1.778 -1.8796) (xy 1.778 -1.8796) (xy 1.778 1.8796)
			)
			(stroke
				(width 0)
				(type default)
			)
			(fill no)
			(layer "F.Fab")
		)
		(pad "D" smd custom
			(at 0 -0.9525 270)
			(size 0.1905 0.1905)
			(layers "F.Cu" "F.Mask" "F.Paste")
			(net "EXP_HW_LED_D")
			(options
				(clearance outline)
				(anchor circle)
			)
			(primitives
				(gr_poly
					(pts
						(arc
							(start -0.1778 0.5715)
							(mid -0.321484 0.511984)
							(end -0.381 0.3683)
						)
						(arc
							(start -0.381 -0.3683)
							(mid -0.321484 -0.511984)
							(end -0.1778 -0.5715)
						)
						(arc
							(start 0.1778 -0.5715)
							(mid 0.321484 -0.511984)
							(end 0.381 -0.3683)
						)
						(arc
							(start 0.381 0.3683)
							(mid 0.321484 0.511984)
							(end 0.1778 0.5715)
						)
					)
					(width 0)
					(fill yes)
				)
			)
		)
		(pad "G" smd custom
			(at -0.98425 0.9525 270)
			(size 0.1905 0.1905)
			(layers "F.Cu" "F.Mask" "F.Paste")
			(net "EXP_BLINK_OUT")
			(options
				(clearance outline)
				(anchor circle)
			)
			(primitives
				(gr_poly
					(pts
						(arc
							(start -0.1778 0.5715)
							(mid -0.321484 0.511984)
							(end -0.381 0.3683)
						)
						(arc
							(start -0.381 -0.3683)
							(mid -0.321484 -0.511984)
							(end -0.1778 -0.5715)
						)
						(arc
							(start 0.1778 -0.5715)
							(mid 0.321484 -0.511984)
							(end 0.381 -0.3683)
						)
						(arc
							(start 0.381 0.3683)
							(mid 0.321484 0.511984)
							(end 0.1778 0.5715)
						)
					)
					(width 0)
					(fill yes)
				)
			)
		)
		(pad "S" smd custom
			(at 0.98425 0.9525 270)
			(size 0.1905 0.1905)
			(layers "F.Cu" "F.Mask" "F.Paste")
			(net "GND")
			(options
				(clearance outline)
				(anchor circle)
			)
			(primitives
				(gr_poly
					(pts
						(arc
							(start -0.1778 0.5715)
							(mid -0.321484 0.511984)
							(end -0.381 0.3683)
						)
						(arc
							(start -0.381 -0.3683)
							(mid -0.321484 -0.511984)
							(end -0.1778 -0.5715)
						)
						(arc
							(start 0.1778 -0.5715)
							(mid 0.321484 -0.511984)
							(end 0.381 -0.3683)
						)
						(arc
							(start 0.381 0.3683)
							(mid 0.321484 0.511984)
							(end 0.1778 0.5715)
						)
					)
					(width 0)
					(fill yes)
				)
			)
		)
	)
	(footprint ""
		(layer "F.Cu")
		(at 7.9756 -77.089)
		(property "Reference" "R346"
			(at 0 0 0)
			(layer "F.SilkS")
			(hide yes)
			(effects
				(font
					(size 1.27 1.27)
				)
			)
		)
		(property "Value" "4K7R2F-GP"
			(at 0.064008 -3.993896 0)
			(unlocked yes)
			(layer "F.Fab")
			(hide yes)
			(effects
				(font
					(size 1.016 1.016)
					(thickness 0.1524)
				)
			)
		)
		(property "Device Type" "R402H16"
			(at 0.064008 -5.517896 0)
			(unlocked yes)
			(layer "F.Fab")
			(hide yes)
			(effects
				(font
					(size 1.016 1.016)
					(thickness 0.1524)
				)
			)
		)
		(duplicate_pad_numbers_are_jumpers no)
		(fp_line
			(start -0.508 -0.9398)
			(end -0.508 0.9398)
			(stroke
				(width 0.1524)
				(type default)
			)
			(layer "F.SilkS")
		)
		(fp_line
			(start 0.508 -0.9398)
			(end -0.508 -0.9398)
			(stroke
				(width 0.1524)
				(type default)
			)
			(layer "F.SilkS")
		)
		(fp_rect
			(start -0.508 0.9398)
			(end 0.508 -0.9398)
			(stroke
				(width 0)
				(type default)
			)
			(fill no)
			(layer "F.CrtYd")
		)
		(fp_rect
			(start -0.508 0.9398)
			(end 0.508 -0.9398)
			(stroke
				(width 0)
				(type default)
			)
			(fill no)
			(layer "F.Fab")
		)
		(pad "1" smd custom
			(at 0 -0.4445)
			(size 0.1397 0.1397)
			(layers "F.Cu" "F.Mask" "F.Paste")
			(net "EXP_EEPROM_A2")
			(options
				(clearance outline)
				(anchor circle)
			)
			(primitives
				(gr_poly
					(pts
						(arc
							(start -0.1778 -0.2794)
							(mid -0.249642 -0.249642)
							(end -0.2794 -0.1778)
						)
						(arc
							(start -0.2794 0.1778)
							(mid -0.249642 0.249642)
							(end -0.1778 0.2794)
						)
						(arc
							(start 0.1778 0.2794)
							(mid 0.249642 0.249642)
							(end 0.2794 0.1778)
						)
						(arc
							(start 0.2794 -0.1778)
							(mid 0.249642 -0.249642)
							(end 0.1778 -0.2794)
						)
					)
					(width 0)
					(fill yes)
				)
			)
		)
		(pad "2" smd custom
			(at 0 0.4445)
			(size 0.1397 0.1397)
			(layers "F.Cu" "F.Mask" "F.Paste")
			(net "GND")
			(options
				(clearance outline)
				(anchor circle)
			)
			(primitives
				(gr_poly
					(pts
						(arc
							(start -0.1778 -0.2794)
							(mid -0.249642 -0.249642)
							(end -0.2794 -0.1778)
						)
						(arc
							(start -0.2794 0.1778)
							(mid -0.249642 0.249642)
							(end -0.1778 0.2794)
						)
						(arc
							(start 0.1778 0.2794)
							(mid 0.249642 0.249642)
							(end 0.2794 0.1778)
						)
						(arc
							(start 0.2794 -0.1778)
							(mid 0.249642 -0.249642)
							(end 0.1778 -0.2794)
						)
					)
					(width 0)
					(fill yes)
				)
			)
		)
	)
	(footprint ""
		(layer "F.Cu")
		(at 122.0978 -86.995 180)
		(property "Reference" "R131"
			(at 0 0 180)
			(layer "F.SilkS")
			(hide yes)
			(effects
				(font
					(size 1.27 1.27)
				)
			)
		)
		(property "Value" "4K7R2F-GP"
			(at 0.064008 -3.993896 180)
			(unlocked yes)
			(layer "F.Fab")
			(hide yes)
			(effects
				(font
					(size 1.016 1.016)
					(thickness 0.1524)
				)
			)
		)
		(property "Device Type" "R402H16"
			(at 0.064008 -5.517896 180)
			(unlocked yes)
			(layer "F.Fab")
			(hide yes)
			(effects
				(font
					(size 1.016 1.016)
					(thickness 0.1524)
				)
			)
		)
		(duplicate_pad_numbers_are_jumpers no)
		(fp_line
			(start 0.508 -0.9398)
			(end -0.508 -0.9398)
			(stroke
				(width 0.1524)
				(type default)
			)
			(layer "F.SilkS")
		)
		(fp_line
			(start -0.508 -0.9398)
			(end -0.508 0.9398)
			(stroke
				(width 0.1524)
				(type default)
			)
			(layer "F.SilkS")
		)
		(fp_rect
			(start -0.508 0.9398)
			(end 0.508 -0.9398)
			(stroke
				(width 0)
				(type default)
			)
			(fill no)
			(layer "F.CrtYd")
		)
		(fp_rect
			(start -0.508 0.9398)
			(end 0.508 -0.9398)
			(stroke
				(width 0)
				(type default)
			)
			(fill no)
			(layer "F.Fab")
		)
		(pad "1" smd custom
			(at 0 -0.4445 180)
			(size 0.1397 0.1397)
			(layers "F.Cu" "F.Mask" "F.Paste")
			(net "SCC_TYPE_3_LS")
			(options
				(clearance outline)
				(anchor circle)
			)
			(primitives
				(gr_poly
					(pts
						(arc
							(start -0.1778 -0.2794)
							(mid -0.249642 -0.249642)
							(end -0.2794 -0.1778)
						)
						(arc
							(start -0.2794 0.1778)
							(mid -0.249642 0.249642)
							(end -0.1778 0.2794)
						)
						(arc
							(start 0.1778 0.2794)
							(mid 0.249642 0.249642)
							(end 0.2794 0.1778)
						)
						(arc
							(start 0.2794 -0.1778)
							(mid 0.249642 -0.249642)
							(end 0.1778 -0.2794)
						)
					)
					(width 0)
					(fill yes)
				)
			)
		)
		(pad "2" smd custom
			(at 0 0.4445 180)
			(size 0.1397 0.1397)
			(layers "F.Cu" "F.Mask" "F.Paste")
			(net "GND")
			(options
				(clearance outline)
				(anchor circle)
			)
			(primitives
				(gr_poly
					(pts
						(arc
							(start -0.1778 -0.2794)
							(mid -0.249642 -0.249642)
							(end -0.2794 -0.1778)
						)
						(arc
							(start -0.2794 0.1778)
							(mid -0.249642 0.249642)
							(end -0.1778 0.2794)
						)
						(arc
							(start 0.1778 0.2794)
							(mid 0.249642 0.249642)
							(end 0.2794 0.1778)
						)
						(arc
							(start 0.2794 -0.1778)
							(mid 0.249642 -0.249642)
							(end 0.1778 -0.2794)
						)
					)
					(width 0)
					(fill yes)
				)
			)
		)
	)
	(footprint ""
		(layer "F.Cu")
		(at 56.388 -77.47 180)
		(property "Reference" "R441"
			(at 0 0 180)
			(layer "F.SilkS")
			(hide yes)
			(effects
				(font
					(size 1.27 1.27)
				)
			)
		)
		(property "Value" "200KR2F-L-GP"
			(at 0.064008 -3.993896 180)
			(unlocked yes)
			(layer "F.Fab")
			(hide yes)
			(effects
				(font
					(size 1.016 1.016)
					(thickness 0.1524)
				)
			)
		)
		(property "Device Type" "R402H16"
			(at 0.064008 -5.517896 180)
			(unlocked yes)
			(layer "F.Fab")
			(hide yes)
			(effects
				(font
					(size 1.016 1.016)
					(thickness 0.1524)
				)
			)
		)
		(duplicate_pad_numbers_are_jumpers no)
		(fp_line
			(start 0.508 -0.9398)
			(end -0.508 -0.9398)
			(stroke
				(width 0.1524)
				(type default)
			)
			(layer "F.SilkS")
		)
		(fp_line
			(start -0.508 -0.9398)
			(end -0.508 0.9398)
			(stroke
				(width 0.1524)
				(type default)
			)
			(layer "F.SilkS")
		)
		(fp_rect
			(start -0.508 0.9398)
			(end 0.508 -0.9398)
			(stroke
				(width 0)
				(type default)
			)
			(fill no)
			(layer "F.CrtYd")
		)
		(fp_rect
			(start -0.508 0.9398)
			(end 0.508 -0.9398)
			(stroke
				(width 0)
				(type default)
			)
			(fill no)
			(layer "F.Fab")
		)
		(pad "1" smd custom
			(at 0 -0.4445 180)
			(size 0.1397 0.1397)
			(layers "F.Cu" "F.Mask" "F.Paste")
			(net "LS_EN_U41")
			(options
				(clearance outline)
				(anchor circle)
			)
			(primitives
				(gr_poly
					(pts
						(arc
							(start -0.1778 -0.2794)
							(mid -0.249642 -0.249642)
							(end -0.2794 -0.1778)
						)
						(arc
							(start -0.2794 0.1778)
							(mid -0.249642 0.249642)
							(end -0.1778 0.2794)
						)
						(arc
							(start 0.1778 0.2794)
							(mid 0.249642 0.249642)
							(end 0.2794 0.1778)
						)
						(arc
							(start 0.2794 -0.1778)
							(mid 0.249642 -0.249642)
							(end 0.1778 -0.2794)
						)
					)
					(width 0)
					(fill yes)
				)
			)
		)
		(pad "2" smd custom
			(at 0 0.4445 180)
			(size 0.1397 0.1397)
			(layers "F.Cu" "F.Mask" "F.Paste")
			(net "P0V9_PG")
			(options
				(clearance outline)
				(anchor circle)
			)
			(primitives
				(gr_poly
					(pts
						(arc
							(start -0.1778 -0.2794)
							(mid -0.249642 -0.249642)
							(end -0.2794 -0.1778)
						)
						(arc
							(start -0.2794 0.1778)
							(mid -0.249642 0.249642)
							(end -0.1778 0.2794)
						)
						(arc
							(start 0.1778 0.2794)
							(mid 0.249642 0.249642)
							(end 0.2794 0.1778)
						)
						(arc
							(start 0.2794 -0.1778)
							(mid 0.249642 -0.249642)
							(end 0.1778 -0.2794)
						)
					)
					(width 0)
					(fill yes)
				)
			)
		)
	)
	(footprint ""
		(layer "F.Cu")
		(at 62.9666 -37.465 -90)
		(property "Reference" "TC3"
			(at 0 0 270)
			(layer "F.SilkS")
			(hide yes)
			(effects
				(font
					(size 1.27 1.27)
				)
			)
		)
		(property "Value" "SE470UF2VDM-GP"
			(at 0 -9.6012 270)
			(unlocked yes)
			(layer "F.Fab")
			(hide yes)
			(effects
				(font
					(size 1.016 1.016)
					(thickness 0.1524)
				)
			)
		)
		(property "Device Type" "CT7343H83"
			(at 0 -11.1252 270)
			(unlocked yes)
			(layer "F.Fab")
			(hide yes)
			(effects
				(font
					(size 1.016 1.016)
					(thickness 0.1524)
				)
			)
		)
		(duplicate_pad_numbers_are_jumpers no)
		(fp_line
			(start -2.286 4.8768)
			(end -2.286 2.032)
			(stroke
				(width 0.1524)
				(type default)
			)
			(layer "F.SilkS")
		)
		(fp_line
			(start 2.286 4.8768)
			(end -2.286 4.8768)
			(stroke
				(width 0.1524)
				(type default)
			)
			(layer "F.SilkS")
		)
		(fp_line
			(start 2.286 2.032)
			(end 2.286 4.8768)
			(stroke
				(width 0.1524)
				(type default)
			)
			(layer "F.SilkS")
		)
		(fp_line
			(start 2.286 -2.032)
			(end 2.286 -4.8768)
			(stroke
				(width 0.1524)
				(type default)
			)
			(layer "F.SilkS")
		)
		(fp_line
			(start 2.1082 -4.699)
			(end -2.1082 -4.699)
			(stroke
				(width 0.508)
				(type default)
			)
			(layer "F.SilkS")
		)
		(fp_line
			(start -2.286 -4.8768)
			(end -2.286 -2.032)
			(stroke
				(width 0.1524)
				(type default)
			)
			(layer "F.SilkS")
		)
		(fp_line
			(start 2.286 -4.8768)
			(end -2.286 -4.8768)
			(stroke
				(width 0.1524)
				(type default)
			)
			(layer "F.SilkS")
		)
		(fp_rect
			(start -2.1463 3.6449)
			(end 2.1463 -3.6449)
			(stroke
				(width 0)
				(type default)
			)
			(fill no)
			(layer "F.CrtYd")
		)
		(fp_poly
			(pts
				(xy -2.54 4.953) (xy -2.54 4.2926) (xy -3.81 4.2926) (xy -3.81 -4.2926) (xy -2.54 -4.2926) (xy -2.54 -4.953)
				(xy 2.54 -4.953) (xy 2.54 -4.2926) (xy 3.81 -4.2926) (xy 3.81 -1.6256) (xy 2.1463 -1.6256) (xy 2.1463 -3.6449)
				(xy -2.1463 -3.6449) (xy -2.1463 3.6449) (xy 2.1463 3.6449) (xy 2.1463 -1.6129) (xy 3.81 -1.6129)
				(xy 3.81 4.2926) (xy 2.54 4.2926) (xy 2.54 4.953)
			)
			(stroke
				(width 0)
				(type default)
			)
			(fill no)
			(layer "F.CrtYd")
		)
		(fp_rect
			(start -2.54 4.953)
			(end 2.54 -4.953)
			(stroke
				(width 0)
				(type default)
			)
			(fill no)
			(layer "F.Fab")
		)
		(fp_rect
			(start -3.81 4.2926)
			(end -2.54 -4.2926)
			(stroke
				(width 0)
				(type default)
			)
			(fill no)
			(layer "F.Fab")
		)
		(fp_rect
			(start 2.54 4.2926)
			(end 3.81 -4.2926)
			(stroke
				(width 0)
				(type default)
			)
			(fill no)
			(layer "F.Fab")
		)
		(pad "1" smd rect
			(at 0 -3.1496 270)
			(size 2.413 2.286)
			(layers "F.Cu" "F.Mask" "F.Paste")
			(net "P0V9")
		)
		(pad "2" smd rect
			(at 0 3.1496 270)
			(size 2.413 2.286)
			(layers "F.Cu" "F.Mask" "F.Paste")
			(net "GND")
		)
		(zone
			(layer "F.Cu")
			(hatch none 0.5)
			(connect_pads
				(clearance 0)
			)
			(min_thickness 0.25)
			(keepout
				(tracks allowed)
				(vias not_allowed)
				(pads allowed)
				(copperpour not_allowed)
				(footprints allowed)
			)
			(placement
				(enabled no)
				(sheetname "")
			)
			(fill
				(thermal_gap 0.5)
				(thermal_bridge_width 0.5)
				(island_removal_mode 0)
			)
			(polygon
				(pts
					(xy 58.3692 -38.9763) (xy 58.3692 -35.9537) (xy 61.2648 -35.9537) (xy 61.595 -35.9537) (xy 61.595 -38.9763)
					(xy 61.2648 -38.9763)
				)
			)
		)
		(zone
			(layer "F.Cu")
			(hatch none 0.5)
			(connect_pads
				(clearance 0)
			)
			(min_thickness 0.25)
			(keepout
				(tracks allowed)
				(vias not_allowed)
				(pads allowed)
				(copperpour not_allowed)
				(footprints allowed)
			)
			(placement
				(enabled no)
				(sheetname "")
			)
			(fill
				(thermal_gap 0.5)
				(thermal_bridge_width 0.5)
				(island_removal_mode 0)
			)
			(polygon
				(pts
					(xy 64.6557 -35.9537) (xy 67.564 -35.9537) (xy 67.564 -38.9763) (xy 64.6684 -38.9763) (xy 64.3382 -38.9763)
					(xy 64.3382 -35.9537)
				)
			)
		)
	)
	(footprint ""
		(layer "F.Cu")
		(at 175.387 -97.4852 180)
		(property "Reference" "C661"
			(at 0 0 180)
			(layer "F.SilkS")
			(hide yes)
			(effects
				(font
					(size 1.27 1.27)
				)
			)
		)
		(property "Value" "SC6K8P50V2KX-GP"
			(at 1.1811 -2.7051 180)
			(unlocked yes)
			(layer "F.Fab")
			(hide yes)
			(effects
				(font
					(size 1.016 1.016)
					(thickness 0.1524)
				)
			)
		)
		(property "Device Type" "C402H22"
			(at 1.1811 -4.2291 180)
			(unlocked yes)
			(layer "F.Fab")
			(hide yes)
			(effects
				(font
					(size 1.016 1.016)
					(thickness 0.1524)
				)
			)
		)
		(duplicate_pad_numbers_are_jumpers no)
		(fp_rect
			(start -0.4318 0.9525)
			(end 0.4318 -0.9525)
			(stroke
				(width 0)
				(type default)
			)
			(fill no)
			(layer "F.CrtYd")
		)
		(fp_rect
			(start -0.4318 0.9525)
			(end 0.4318 -0.9525)
			(stroke
				(width 0)
				(type default)
			)
			(fill no)
			(layer "F.Fab")
		)
		(pad "1" smd custom
			(at 0 -0.4445 180)
			(size 0.1524 0.1524)
			(layers "F.Cu" "F.Mask" "F.Paste")
			(net "VT235_VFB")
			(options
				(clearance outline)
				(anchor circle)
			)
			(primitives
				(gr_poly
					(pts
						(arc
							(start 0.3048 -0.2032)
							(mid 0.275042 -0.275042)
							(end 0.2032 -0.3048)
						)
						(arc
							(start -0.2032 -0.3048)
							(mid -0.275042 -0.275042)
							(end -0.3048 -0.2032)
						)
						(arc
							(start -0.3048 0.2032)
							(mid -0.275042 0.275042)
							(end -0.2032 0.3048)
						)
						(arc
							(start 0.2032 0.3048)
							(mid 0.275042 0.275042)
							(end 0.3048 0.2032)
						)
					)
					(width 0)
					(fill yes)
				)
			)
		)
		(pad "2" smd custom
			(at 0 0.4445 180)
			(size 0.1524 0.1524)
			(layers "F.Cu" "F.Mask" "F.Paste")
			(net "VT235_VDES")
			(options
				(clearance outline)
				(anchor circle)
			)
			(primitives
				(gr_poly
					(pts
						(arc
							(start 0.3048 -0.2032)
							(mid 0.275042 -0.275042)
							(end 0.2032 -0.3048)
						)
						(arc
							(start -0.2032 -0.3048)
							(mid -0.275042 -0.275042)
							(end -0.3048 -0.2032)
						)
						(arc
							(start -0.3048 0.2032)
							(mid -0.275042 0.275042)
							(end -0.2032 0.3048)
						)
						(arc
							(start 0.2032 0.3048)
							(mid 0.275042 0.275042)
							(end 0.3048 0.2032)
						)
					)
					(width 0)
					(fill yes)
				)
			)
		)
	)
	(footprint ""
		(layer "F.Cu")
		(at 87.602314 -52.79136)
		(property "Reference" "C111"
			(at 0 0 0)
			(layer "F.SilkS")
			(hide yes)
			(effects
				(font
					(size 1.27 1.27)
				)
			)
		)
		(property "Value" "SC15P50V2JN-2-GP"
			(at 1.1811 -2.7051 0)
			(unlocked yes)
			(layer "F.Fab")
			(hide yes)
			(effects
				(font
					(size 1.016 1.016)
					(thickness 0.1524)
				)
			)
		)
		(property "Device Type" "C402H22"
			(at 1.1811 -4.2291 0)
			(unlocked yes)
			(layer "F.Fab")
			(hide yes)
			(effects
				(font
					(size 1.016 1.016)
					(thickness 0.1524)
				)
			)
		)
		(duplicate_pad_numbers_are_jumpers no)
		(fp_rect
			(start -0.4318 0.9525)
			(end 0.4318 -0.9525)
			(stroke
				(width 0)
				(type default)
			)
			(fill no)
			(layer "F.CrtYd")
		)
		(fp_rect
			(start -0.4318 0.9525)
			(end 0.4318 -0.9525)
			(stroke
				(width 0)
				(type default)
			)
			(fill no)
			(layer "F.Fab")
		)
		(pad "1" smd custom
			(at 0 -0.4445)
			(size 0.1524 0.1524)
			(layers "F.Cu" "F.Mask" "F.Paste")
			(net "EXP_REF_CLK_R_N")
			(options
				(clearance outline)
				(anchor circle)
			)
			(primitives
				(gr_poly
					(pts
						(arc
							(start 0.3048 -0.2032)
							(mid 0.275042 -0.275042)
							(end 0.2032 -0.3048)
						)
						(arc
							(start -0.2032 -0.3048)
							(mid -0.275042 -0.275042)
							(end -0.3048 -0.2032)
						)
						(arc
							(start -0.3048 0.2032)
							(mid -0.275042 0.275042)
							(end -0.2032 0.3048)
						)
						(arc
							(start 0.2032 0.3048)
							(mid 0.275042 0.275042)
							(end 0.3048 0.2032)
						)
					)
					(width 0)
					(fill yes)
				)
			)
		)
		(pad "2" smd custom
			(at 0 0.4445)
			(size 0.1524 0.1524)
			(layers "F.Cu" "F.Mask" "F.Paste")
			(net "GND")
			(options
				(clearance outline)
				(anchor circle)
			)
			(primitives
				(gr_poly
					(pts
						(arc
							(start 0.3048 -0.2032)
							(mid 0.275042 -0.275042)
							(end 0.2032 -0.3048)
						)
						(arc
							(start -0.2032 -0.3048)
							(mid -0.275042 -0.275042)
							(end -0.3048 -0.2032)
						)
						(arc
							(start -0.3048 0.2032)
							(mid -0.275042 0.275042)
							(end -0.2032 0.3048)
						)
						(arc
							(start 0.2032 0.3048)
							(mid 0.275042 0.275042)
							(end 0.3048 0.2032)
						)
					)
					(width 0)
					(fill yes)
				)
			)
		)
	)
	(footprint ""
		(layer "F.Cu")
		(at 151.113236 -38.55212 -78)
		(property "Reference" "VIA19"
			(at 0 0 282)
			(layer "F.SilkS")
			(hide yes)
			(effects
				(font
					(size 1.27 1.27)
				)
			)
		)
		(property "Value" "100OHM-8L-1D6MM-L13-GP"
			(at 3.289333 0.050849 282)
			(unlocked yes)
			(layer "F.Fab")
			(hide yes)
			(effects
				(font
					(size 1.016 1.016)
					(thickness 0.1524)
				)
			)
		)
		(property "Device Type" "VIA-PCIE-4P-409091"
			(at 3.289207 -1.473208 282)
			(unlocked yes)
			(layer "F.Fab")
			(hide yes)
			(effects
				(font
					(size 1.016 1.016)
					(thickness 0.1524)
				)
			)
		)
		(duplicate_pad_numbers_are_jumpers no)
		(fp_poly
			(pts
				(xy -2.044719 -0.457296) (xy 2.04468 -0.457296) (xy 2.044681 0.457104) (xy -2.044719 0.457104)
			)
			(stroke
				(width 0)
				(type default)
			)
			(fill no)
			(layer "F.CrtYd")
		)
		(fp_poly
			(pts
				(xy -2.044719 -0.457296) (xy 2.04468 -0.457296) (xy 2.044681 0.457104) (xy -2.044719 0.457104)
			)
			(stroke
				(width 0)
				(type default)
			)
			(fill no)
			(layer "F.Fab")
		)
		(pad "1" thru_hole circle
			(at -1.5875 0 282)
			(size 0.508 0.508)
			(drill 0.254)
			(layers "*.Cu" "*.Mask")
			(remove_unused_layers no)
			(net "GND")
			(clearance 0.2032)
			(thermal_gap 0.2032)
		)
		(pad "2" thru_hole circle
			(at -0.5715 0.000001 282)
			(size 0.508 0.508)
			(drill 0.254)
			(layers "*.Cu" "*.Mask")
			(remove_unused_layers no)
			(net "PHY_SCC_TO_IOC_C_42_DP")
			(clearance 0.2032)
			(thermal_gap 0.2032)
		)
		(pad "3" thru_hole circle
			(at 0.5715 -0.000001 282)
			(size 0.508 0.508)
			(drill 0.254)
			(layers "*.Cu" "*.Mask")
			(remove_unused_layers no)
			(net "PHY_SCC_TO_IOC_C_42_DN")
			(clearance 0.2032)
			(thermal_gap 0.2032)
		)
		(pad "4" thru_hole circle
			(at 1.5875 0 282)
			(size 0.508 0.508)
			(drill 0.254)
			(layers "*.Cu" "*.Mask")
			(remove_unused_layers no)
			(net "GND")
			(clearance 0.2032)
			(thermal_gap 0.2032)
		)
	)
	(footprint ""
		(layer "F.Cu")
		(at 185.9026 -22.9362)
		(property "Reference" "R276"
			(at 0 0 0)
			(layer "F.SilkS")
			(hide yes)
			(effects
				(font
					(size 1.27 1.27)
				)
			)
		)
		(property "Value" "4K7R2F-GP"
			(at 0.064008 -3.993896 0)
			(unlocked yes)
			(layer "F.Fab")
			(hide yes)
			(effects
				(font
					(size 1.016 1.016)
					(thickness 0.1524)
				)
			)
		)
		(property "Device Type" "R402H16"
			(at 0.064008 -5.517896 0)
			(unlocked yes)
			(layer "F.Fab")
			(hide yes)
			(effects
				(font
					(size 1.016 1.016)
					(thickness 0.1524)
				)
			)
		)
		(duplicate_pad_numbers_are_jumpers no)
		(fp_line
			(start -0.508 -0.9398)
			(end -0.508 0.9398)
			(stroke
				(width 0.1524)
				(type default)
			)
			(layer "F.SilkS")
		)
		(fp_line
			(start 0.508 -0.9398)
			(end -0.508 -0.9398)
			(stroke
				(width 0.1524)
				(type default)
			)
			(layer "F.SilkS")
		)
		(fp_rect
			(start -0.508 0.9398)
			(end 0.508 -0.9398)
			(stroke
				(width 0)
				(type default)
			)
			(fill no)
			(layer "F.CrtYd")
		)
		(fp_rect
			(start -0.508 0.9398)
			(end 0.508 -0.9398)
			(stroke
				(width 0)
				(type default)
			)
			(fill no)
			(layer "F.Fab")
		)
		(pad "1" smd custom
			(at 0 -0.4445)
			(size 0.1397 0.1397)
			(layers "F.Cu" "F.Mask" "F.Paste")
			(net "SYS_DBMODE4")
			(options
				(clearance outline)
				(anchor circle)
			)
			(primitives
				(gr_poly
					(pts
						(arc
							(start -0.1778 -0.2794)
							(mid -0.249642 -0.249642)
							(end -0.2794 -0.1778)
						)
						(arc
							(start -0.2794 0.1778)
							(mid -0.249642 0.249642)
							(end -0.1778 0.2794)
						)
						(arc
							(start 0.1778 0.2794)
							(mid 0.249642 0.249642)
							(end 0.2794 0.1778)
						)
						(arc
							(start 0.2794 -0.1778)
							(mid 0.249642 -0.249642)
							(end 0.1778 -0.2794)
						)
					)
					(width 0)
					(fill yes)
				)
			)
		)
		(pad "2" smd custom
			(at 0 0.4445)
			(size 0.1397 0.1397)
			(layers "F.Cu" "F.Mask" "F.Paste")
			(net "GND")
			(options
				(clearance outline)
				(anchor circle)
			)
			(primitives
				(gr_poly
					(pts
						(arc
							(start -0.1778 -0.2794)
							(mid -0.249642 -0.249642)
							(end -0.2794 -0.1778)
						)
						(arc
							(start -0.2794 0.1778)
							(mid -0.249642 0.249642)
							(end -0.1778 0.2794)
						)
						(arc
							(start 0.1778 0.2794)
							(mid 0.249642 0.249642)
							(end 0.2794 0.1778)
						)
						(arc
							(start 0.2794 -0.1778)
							(mid 0.249642 -0.249642)
							(end 0.1778 -0.2794)
						)
					)
					(width 0)
					(fill yes)
				)
			)
		)
	)
	(footprint ""
		(layer "F.Cu")
		(at 157.48 -42.291 -90)
		(property "Reference" "C335"
			(at 0 0 270)
			(layer "F.SilkS")
			(hide yes)
			(effects
				(font
					(size 1.27 1.27)
				)
			)
		)
		(property "Value" "SC15P50V2JN-2-GP"
			(at 1.1811 -2.7051 270)
			(unlocked yes)
			(layer "F.Fab")
			(hide yes)
			(effects
				(font
					(size 1.016 1.016)
					(thickness 0.1524)
				)
			)
		)
		(property "Device Type" "C402H22"
			(at 1.1811 -4.2291 270)
			(unlocked yes)
			(layer "F.Fab")
			(hide yes)
			(effects
				(font
					(size 1.016 1.016)
					(thickness 0.1524)
				)
			)
		)
		(duplicate_pad_numbers_are_jumpers no)
		(fp_rect
			(start -0.4318 0.9525)
			(end 0.4318 -0.9525)
			(stroke
				(width 0)
				(type default)
			)
			(fill no)
			(layer "F.CrtYd")
		)
		(fp_rect
			(start -0.4318 0.9525)
			(end 0.4318 -0.9525)
			(stroke
				(width 0)
				(type default)
			)
			(fill no)
			(layer "F.Fab")
		)
		(pad "1" smd custom
			(at 0 -0.4445 270)
			(size 0.1524 0.1524)
			(layers "F.Cu" "F.Mask" "F.Paste")
			(net "REF_CLK")
			(options
				(clearance outline)
				(anchor circle)
			)
			(primitives
				(gr_poly
					(pts
						(arc
							(start 0.3048 -0.2032)
							(mid 0.275042 -0.275042)
							(end 0.2032 -0.3048)
						)
						(arc
							(start -0.2032 -0.3048)
							(mid -0.275042 -0.275042)
							(end -0.3048 -0.2032)
						)
						(arc
							(start -0.3048 0.2032)
							(mid -0.275042 0.275042)
							(end -0.2032 0.3048)
						)
						(arc
							(start 0.2032 0.3048)
							(mid 0.275042 0.275042)
							(end 0.3048 0.2032)
						)
					)
					(width 0)
					(fill yes)
				)
			)
		)
		(pad "2" smd custom
			(at 0 0.4445 270)
			(size 0.1524 0.1524)
			(layers "F.Cu" "F.Mask" "F.Paste")
			(net "GND")
			(options
				(clearance outline)
				(anchor circle)
			)
			(primitives
				(gr_poly
					(pts
						(arc
							(start 0.3048 -0.2032)
							(mid 0.275042 -0.275042)
							(end 0.2032 -0.3048)
						)
						(arc
							(start -0.2032 -0.3048)
							(mid -0.275042 -0.275042)
							(end -0.3048 -0.2032)
						)
						(arc
							(start -0.3048 0.2032)
							(mid -0.275042 0.275042)
							(end -0.2032 0.3048)
						)
						(arc
							(start 0.2032 0.3048)
							(mid 0.275042 0.275042)
							(end 0.3048 0.2032)
						)
					)
					(width 0)
					(fill yes)
				)
			)
		)
	)
	(footprint ""
		(layer "F.Cu")
		(at 53.213 -72.136 -90)
		(property "Reference" "R470"
			(at 0 0 270)
			(layer "F.SilkS")
			(hide yes)
			(effects
				(font
					(size 1.27 1.27)
				)
			)
		)
		(property "Value" "200KR2F-L-GP"
			(at 0.064008 -3.993896 270)
			(unlocked yes)
			(layer "F.Fab")
			(hide yes)
			(effects
				(font
					(size 1.016 1.016)
					(thickness 0.1524)
				)
			)
		)
		(property "Device Type" "R402H16"
			(at 0.064008 -5.517896 270)
			(unlocked yes)
			(layer "F.Fab")
			(hide yes)
			(effects
				(font
					(size 1.016 1.016)
					(thickness 0.1524)
				)
			)
		)
		(duplicate_pad_numbers_are_jumpers no)
		(fp_line
			(start -0.508 -0.9398)
			(end -0.508 0.9398)
			(stroke
				(width 0.1524)
				(type default)
			)
			(layer "F.SilkS")
		)
		(fp_line
			(start 0.508 -0.9398)
			(end -0.508 -0.9398)
			(stroke
				(width 0.1524)
				(type default)
			)
			(layer "F.SilkS")
		)
		(fp_rect
			(start -0.508 0.9398)
			(end 0.508 -0.9398)
			(stroke
				(width 0)
				(type default)
			)
			(fill no)
			(layer "F.CrtYd")
		)
		(fp_rect
			(start -0.508 0.9398)
			(end 0.508 -0.9398)
			(stroke
				(width 0)
				(type default)
			)
			(fill no)
			(layer "F.Fab")
		)
		(pad "1" smd custom
			(at 0 -0.4445 270)
			(size 0.1397 0.1397)
			(layers "F.Cu" "F.Mask" "F.Paste")
			(net "VREF7")
			(options
				(clearance outline)
				(anchor circle)
			)
			(primitives
				(gr_poly
					(pts
						(arc
							(start -0.1778 -0.2794)
							(mid -0.249642 -0.249642)
							(end -0.2794 -0.1778)
						)
						(arc
							(start -0.2794 0.1778)
							(mid -0.249642 0.249642)
							(end -0.1778 0.2794)
						)
						(arc
							(start 0.1778 0.2794)
							(mid 0.249642 0.249642)
							(end 0.2794 0.1778)
						)
						(arc
							(start 0.2794 -0.1778)
							(mid 0.249642 -0.249642)
							(end 0.1778 -0.2794)
						)
					)
					(width 0)
					(fill yes)
				)
			)
		)
		(pad "2" smd custom
			(at 0 0.4445 270)
			(size 0.1397 0.1397)
			(layers "F.Cu" "F.Mask" "F.Paste")
			(net "P3V3")
			(options
				(clearance outline)
				(anchor circle)
			)
			(primitives
				(gr_poly
					(pts
						(arc
							(start -0.1778 -0.2794)
							(mid -0.249642 -0.249642)
							(end -0.2794 -0.1778)
						)
						(arc
							(start -0.2794 0.1778)
							(mid -0.249642 0.249642)
							(end -0.1778 0.2794)
						)
						(arc
							(start 0.1778 0.2794)
							(mid 0.249642 0.249642)
							(end 0.2794 0.1778)
						)
						(arc
							(start 0.2794 -0.1778)
							(mid 0.249642 -0.249642)
							(end 0.1778 -0.2794)
						)
					)
					(width 0)
					(fill yes)
				)
			)
		)
	)
	(footprint ""
		(layer "F.Cu")
		(at 35.8648 -49.7332 180)
		(property "Reference" "C527"
			(at 0 0 180)
			(layer "F.SilkS")
			(hide yes)
			(effects
				(font
					(size 1.27 1.27)
				)
			)
		)
		(property "Value" "SC10U16V5KX-7-GP-U"
			(at -0.0762 -6.1214 180)
			(unlocked yes)
			(layer "F.Fab")
			(hide yes)
			(effects
				(font
					(size 1.016 1.016)
					(thickness 0.1524)
				)
			)
		)
		(property "Device Type" "C805H58"
			(at -0.0762 -8.1534 180)
			(unlocked yes)
			(layer "F.Fab")
			(hide yes)
			(effects
				(font
					(size 1.016 1.016)
					(thickness 0.1524)
				)
			)
		)
		(duplicate_pad_numbers_are_jumpers no)
		(fp_line
			(start 0.635 0)
			(end -0.635 0)
			(stroke
				(width 0.508)
				(type default)
			)
			(layer "F.SilkS")
		)
		(fp_rect
			(start -0.9652 1.778)
			(end 0.9652 -1.778)
			(stroke
				(width 0)
				(type default)
			)
			(fill no)
			(layer "F.CrtYd")
		)
		(fp_poly
			(pts
				(xy -0.9652 -1.778) (xy 0.9652 -1.778) (xy 0.9652 1.778) (xy -0.9652 1.778)
			)
			(stroke
				(width 0)
				(type default)
			)
			(fill no)
			(layer "F.Fab")
		)
		(pad "1" smd rect
			(at 0 -0.9652 180)
			(size 1.397 1.143)
			(layers "F.Cu" "F.Mask" "F.Paste")
			(net "P12V_STBY_VIN_Q7")
		)
		(pad "2" smd rect
			(at 0 0.9652 180)
			(size 1.397 1.143)
			(layers "F.Cu" "F.Mask" "F.Paste")
			(net "GND")
		)
	)
	(footprint ""
		(layer "F.Cu")
		(at 194.437 -30.353 -90)
		(property "Reference" "TP71"
			(at 0 0 270)
			(layer "F.SilkS")
			(hide yes)
			(effects
				(font
					(size 1.27 1.27)
				)
			)
		)
		(property "Value" "TPAD28-2-GP"
			(at -0.0127 -1.6637 270)
			(unlocked yes)
			(layer "F.Fab")
			(hide yes)
			(effects
				(font
					(size 1.016 1.016)
					(thickness 0.1524)
				)
			)
		)
		(property "Device Type" "TPAD28"
			(at -0.0127 -3.1877 270)
			(unlocked yes)
			(layer "F.Fab")
			(hide yes)
			(effects
				(font
					(size 1.016 1.016)
					(thickness 0.1524)
				)
			)
		)
		(duplicate_pad_numbers_are_jumpers no)
		(fp_poly
			(pts
				(arc
					(start 0 -0.3556)
					(mid 0 0.3556)
					(end 0 -0.3556)
				)
			)
			(stroke
				(width 0)
				(type default)
			)
			(fill no)
			(layer "F.CrtYd")
		)
		(fp_poly
			(pts
				(arc
					(start 0 -0.6096)
					(mid 0 0.6096)
					(end 0 -0.6096)
				)
			)
			(stroke
				(width 0)
				(type default)
			)
			(fill no)
			(layer "F.Fab")
		)
		(pad "1" smd circle
			(at 0 0 270)
			(size 0.7112 0.7112)
			(layers "F.Cu" "F.Mask" "F.Paste")
			(net "IOC_GPIO_18")
		)
	)
	(footprint ""
		(layer "F.Cu")
		(at 8.4074 -53.8226 -90)
		(property "Reference" "C647"
			(at 0 0 270)
			(layer "F.SilkS")
			(hide yes)
			(effects
				(font
					(size 1.27 1.27)
				)
			)
		)
		(property "Value" "SCD1U16V2KX-3GP"
			(at 1.1811 -2.7051 270)
			(unlocked yes)
			(layer "F.Fab")
			(hide yes)
			(effects
				(font
					(size 1.016 1.016)
					(thickness 0.1524)
				)
			)
		)
		(property "Device Type" "C402H22"
			(at 1.1811 -4.2291 270)
			(unlocked yes)
			(layer "F.Fab")
			(hide yes)
			(effects
				(font
					(size 1.016 1.016)
					(thickness 0.1524)
				)
			)
		)
		(duplicate_pad_numbers_are_jumpers no)
		(fp_rect
			(start -0.4318 0.9525)
			(end 0.4318 -0.9525)
			(stroke
				(width 0)
				(type default)
			)
			(fill no)
			(layer "F.CrtYd")
		)
		(fp_rect
			(start -0.4318 0.9525)
			(end 0.4318 -0.9525)
			(stroke
				(width 0)
				(type default)
			)
			(fill no)
			(layer "F.Fab")
		)
		(pad "1" smd custom
			(at 0 -0.4445 270)
			(size 0.1524 0.1524)
			(layers "F.Cu" "F.Mask" "F.Paste")
			(net "MB0_CM_VOUT_R")
			(options
				(clearance outline)
				(anchor circle)
			)
			(primitives
				(gr_poly
					(pts
						(arc
							(start 0.3048 -0.2032)
							(mid 0.275042 -0.275042)
							(end 0.2032 -0.3048)
						)
						(arc
							(start -0.2032 -0.3048)
							(mid -0.275042 -0.275042)
							(end -0.3048 -0.2032)
						)
						(arc
							(start -0.3048 0.2032)
							(mid -0.275042 0.275042)
							(end -0.2032 0.3048)
						)
						(arc
							(start 0.2032 0.3048)
							(mid 0.275042 0.275042)
							(end 0.3048 0.2032)
						)
					)
					(width 0)
					(fill yes)
				)
			)
		)
		(pad "2" smd custom
			(at 0 0.4445 270)
			(size 0.1524 0.1524)
			(layers "F.Cu" "F.Mask" "F.Paste")
			(net "AGND_CURRENT_MON")
			(options
				(clearance outline)
				(anchor circle)
			)
			(primitives
				(gr_poly
					(pts
						(arc
							(start 0.3048 -0.2032)
							(mid 0.275042 -0.275042)
							(end 0.2032 -0.3048)
						)
						(arc
							(start -0.2032 -0.3048)
							(mid -0.275042 -0.275042)
							(end -0.3048 -0.2032)
						)
						(arc
							(start -0.3048 0.2032)
							(mid -0.275042 0.275042)
							(end -0.2032 0.3048)
						)
						(arc
							(start 0.2032 0.3048)
							(mid 0.275042 0.275042)
							(end 0.3048 0.2032)
						)
					)
					(width 0)
					(fill yes)
				)
			)
		)
	)
	(footprint ""
		(layer "F.Cu")
		(at 174.625 -95.885 90)
		(property "Reference" "C622"
			(at 0 0 90)
			(layer "F.SilkS")
			(hide yes)
			(effects
				(font
					(size 1.27 1.27)
				)
			)
		)
		(property "Value" "SC1U25V3KX-GP"
			(at 0 -2.8194 90)
			(unlocked yes)
			(layer "F.Fab")
			(hide yes)
			(effects
				(font
					(size 1.016 1.016)
					(thickness 0.1524)
				)
			)
		)
		(property "Device Type" "C603H36"
			(at 0 -4.3434 90)
			(unlocked yes)
			(layer "F.Fab")
			(hide yes)
			(effects
				(font
					(size 1.016 1.016)
					(thickness 0.1524)
				)
			)
		)
		(duplicate_pad_numbers_are_jumpers no)
		(fp_line
			(start 0.508 0)
			(end -0.508 0)
			(stroke
				(width 0.2032)
				(type default)
			)
			(layer "F.SilkS")
		)
		(fp_rect
			(start -0.5842 1.3335)
			(end 0.5842 -1.3335)
			(stroke
				(width 0)
				(type default)
			)
			(fill no)
			(layer "F.CrtYd")
		)
		(fp_rect
			(start -0.5842 1.3335)
			(end 0.5842 -1.3335)
			(stroke
				(width 0)
				(type default)
			)
			(fill no)
			(layer "F.Fab")
		)
		(pad "1" smd custom
			(at 0 -0.762 90)
			(size 0.2159 0.2159)
			(layers "F.Cu" "F.Mask" "F.Paste")
			(net "VT235_VDDL")
			(options
				(clearance outline)
				(anchor circle)
			)
			(primitives
				(gr_poly
					(pts
						(arc
							(start -0.3302 -0.4318)
							(mid -0.402042 -0.402042)
							(end -0.4318 -0.3302)
						)
						(arc
							(start -0.4318 0.3302)
							(mid -0.402042 0.402042)
							(end -0.3302 0.4318)
						)
						(arc
							(start 0.3302 0.4318)
							(mid 0.402042 0.402042)
							(end 0.4318 0.3302)
						)
						(arc
							(start 0.4318 -0.3302)
							(mid 0.402042 -0.402042)
							(end 0.3302 -0.4318)
						)
					)
					(width 0)
					(fill yes)
				)
			)
		)
		(pad "2" smd custom
			(at 0 0.762 90)
			(size 0.2159 0.2159)
			(layers "F.Cu" "F.Mask" "F.Paste")
			(net "GND")
			(options
				(clearance outline)
				(anchor circle)
			)
			(primitives
				(gr_poly
					(pts
						(arc
							(start -0.3302 -0.4318)
							(mid -0.402042 -0.402042)
							(end -0.4318 -0.3302)
						)
						(arc
							(start -0.4318 0.3302)
							(mid -0.402042 0.402042)
							(end -0.3302 0.4318)
						)
						(arc
							(start 0.3302 0.4318)
							(mid 0.402042 0.402042)
							(end 0.4318 0.3302)
						)
						(arc
							(start 0.4318 -0.3302)
							(mid 0.402042 -0.402042)
							(end 0.3302 -0.4318)
						)
					)
					(width 0)
					(fill yes)
				)
			)
		)
	)
	(footprint ""
		(layer "F.Cu")
		(at 72.451214 -70.758304 90)
		(property "Reference" "R439"
			(at 0 0 90)
			(layer "F.SilkS")
			(hide yes)
			(effects
				(font
					(size 1.27 1.27)
				)
			)
		)
		(property "Value" "200KR2F-L-GP"
			(at 0.064008 -3.993896 90)
			(unlocked yes)
			(layer "F.Fab")
			(hide yes)
			(effects
				(font
					(size 1.016 1.016)
					(thickness 0.1524)
				)
			)
		)
		(property "Device Type" "R402H16"
			(at 0.064008 -5.517896 90)
			(unlocked yes)
			(layer "F.Fab")
			(hide yes)
			(effects
				(font
					(size 1.016 1.016)
					(thickness 0.1524)
				)
			)
		)
		(duplicate_pad_numbers_are_jumpers no)
		(fp_line
			(start 0.508 -0.9398)
			(end -0.508 -0.9398)
			(stroke
				(width 0.1524)
				(type default)
			)
			(layer "F.SilkS")
		)
		(fp_line
			(start -0.508 -0.9398)
			(end -0.508 0.9398)
			(stroke
				(width 0.1524)
				(type default)
			)
			(layer "F.SilkS")
		)
		(fp_rect
			(start -0.508 0.9398)
			(end 0.508 -0.9398)
			(stroke
				(width 0)
				(type default)
			)
			(fill no)
			(layer "F.CrtYd")
		)
		(fp_rect
			(start -0.508 0.9398)
			(end 0.508 -0.9398)
			(stroke
				(width 0)
				(type default)
			)
			(fill no)
			(layer "F.Fab")
		)
		(pad "1" smd custom
			(at 0 -0.4445 90)
			(size 0.1397 0.1397)
			(layers "F.Cu" "F.Mask" "F.Paste")
			(net "LS_EN_U39")
			(options
				(clearance outline)
				(anchor circle)
			)
			(primitives
				(gr_poly
					(pts
						(arc
							(start -0.1778 -0.2794)
							(mid -0.249642 -0.249642)
							(end -0.2794 -0.1778)
						)
						(arc
							(start -0.2794 0.1778)
							(mid -0.249642 0.249642)
							(end -0.1778 0.2794)
						)
						(arc
							(start 0.1778 0.2794)
							(mid 0.249642 0.249642)
							(end 0.2794 0.1778)
						)
						(arc
							(start 0.2794 -0.1778)
							(mid 0.249642 -0.249642)
							(end 0.1778 -0.2794)
						)
					)
					(width 0)
					(fill yes)
				)
			)
		)
		(pad "2" smd custom
			(at 0 0.4445 90)
			(size 0.1397 0.1397)
			(layers "F.Cu" "F.Mask" "F.Paste")
			(net "P0V9_PG")
			(options
				(clearance outline)
				(anchor circle)
			)
			(primitives
				(gr_poly
					(pts
						(arc
							(start -0.1778 -0.2794)
							(mid -0.249642 -0.249642)
							(end -0.2794 -0.1778)
						)
						(arc
							(start -0.2794 0.1778)
							(mid -0.249642 0.249642)
							(end -0.1778 0.2794)
						)
						(arc
							(start 0.1778 0.2794)
							(mid 0.249642 0.249642)
							(end 0.2794 0.1778)
						)
						(arc
							(start 0.2794 -0.1778)
							(mid 0.249642 -0.249642)
							(end 0.1778 -0.2794)
						)
					)
					(width 0)
					(fill yes)
				)
			)
		)
	)
	(footprint ""
		(layer "F.Cu")
		(at 75.311 -51.5874 180)
		(property "Reference" "C275"
			(at 0 0 180)
			(layer "F.SilkS")
			(hide yes)
			(effects
				(font
					(size 1.27 1.27)
				)
			)
		)
		(property "Value" "SC22U6D3V3MX-9-GP-U"
			(at 0 -2.8194 180)
			(unlocked yes)
			(layer "F.Fab")
			(hide yes)
			(effects
				(font
					(size 1.016 1.016)
					(thickness 0.1524)
				)
			)
		)
		(property "Device Type" "C603H40"
			(at 0 -4.3434 180)
			(unlocked yes)
			(layer "F.Fab")
			(hide yes)
			(effects
				(font
					(size 1.016 1.016)
					(thickness 0.1524)
				)
			)
		)
		(duplicate_pad_numbers_are_jumpers no)
		(fp_line
			(start 0.508 0)
			(end -0.508 0)
			(stroke
				(width 0.2032)
				(type default)
			)
			(layer "F.SilkS")
		)
		(fp_rect
			(start -0.5842 1.3335)
			(end 0.5842 -1.3335)
			(stroke
				(width 0)
				(type default)
			)
			(fill no)
			(layer "F.CrtYd")
		)
		(fp_rect
			(start -0.5842 1.3335)
			(end 0.5842 -1.3335)
			(stroke
				(width 0)
				(type default)
			)
			(fill no)
			(layer "F.Fab")
		)
		(pad "1" smd custom
			(at 0 -0.762 180)
			(size 0.2159 0.2159)
			(layers "F.Cu" "F.Mask" "F.Paste")
			(net "GB_VDDA")
			(options
				(clearance outline)
				(anchor circle)
			)
			(primitives
				(gr_poly
					(pts
						(arc
							(start -0.3302 -0.4318)
							(mid -0.402042 -0.402042)
							(end -0.4318 -0.3302)
						)
						(arc
							(start -0.4318 0.3302)
							(mid -0.402042 0.402042)
							(end -0.3302 0.4318)
						)
						(arc
							(start 0.3302 0.4318)
							(mid 0.402042 0.402042)
							(end 0.4318 0.3302)
						)
						(arc
							(start 0.4318 -0.3302)
							(mid 0.402042 -0.402042)
							(end 0.3302 -0.4318)
						)
					)
					(width 0)
					(fill yes)
				)
			)
		)
		(pad "2" smd custom
			(at 0 0.762 180)
			(size 0.2159 0.2159)
			(layers "F.Cu" "F.Mask" "F.Paste")
			(net "GND")
			(options
				(clearance outline)
				(anchor circle)
			)
			(primitives
				(gr_poly
					(pts
						(arc
							(start -0.3302 -0.4318)
							(mid -0.402042 -0.402042)
							(end -0.4318 -0.3302)
						)
						(arc
							(start -0.4318 0.3302)
							(mid -0.402042 0.402042)
							(end -0.3302 0.4318)
						)
						(arc
							(start 0.3302 0.4318)
							(mid 0.402042 0.402042)
							(end 0.4318 0.3302)
						)
						(arc
							(start 0.4318 -0.3302)
							(mid 0.402042 -0.402042)
							(end 0.3302 -0.4318)
						)
					)
					(width 0)
					(fill yes)
				)
			)
		)
	)
	(footprint ""
		(layer "F.Cu")
		(at 191.035432 -71.161656 -90)
		(property "Reference" "C508"
			(at 0 0 270)
			(layer "F.SilkS")
			(hide yes)
			(effects
				(font
					(size 1.27 1.27)
				)
			)
		)
		(property "Value" "SCD1U16V2KX-3GP"
			(at 1.1811 -2.7051 270)
			(unlocked yes)
			(layer "F.Fab")
			(hide yes)
			(effects
				(font
					(size 1.016 1.016)
					(thickness 0.1524)
				)
			)
		)
		(property "Device Type" "C402H22"
			(at 1.1811 -4.2291 270)
			(unlocked yes)
			(layer "F.Fab")
			(hide yes)
			(effects
				(font
					(size 1.016 1.016)
					(thickness 0.1524)
				)
			)
		)
		(duplicate_pad_numbers_are_jumpers no)
		(fp_rect
			(start -0.4318 0.9525)
			(end 0.4318 -0.9525)
			(stroke
				(width 0)
				(type default)
			)
			(fill no)
			(layer "F.CrtYd")
		)
		(fp_rect
			(start -0.4318 0.9525)
			(end 0.4318 -0.9525)
			(stroke
				(width 0)
				(type default)
			)
			(fill no)
			(layer "F.Fab")
		)
		(pad "1" smd custom
			(at 0 -0.4445 270)
			(size 0.1524 0.1524)
			(layers "F.Cu" "F.Mask" "F.Paste")
			(net "P3V3")
			(options
				(clearance outline)
				(anchor circle)
			)
			(primitives
				(gr_poly
					(pts
						(arc
							(start 0.3048 -0.2032)
							(mid 0.275042 -0.275042)
							(end 0.2032 -0.3048)
						)
						(arc
							(start -0.2032 -0.3048)
							(mid -0.275042 -0.275042)
							(end -0.3048 -0.2032)
						)
						(arc
							(start -0.3048 0.2032)
							(mid -0.275042 0.275042)
							(end -0.2032 0.3048)
						)
						(arc
							(start 0.2032 0.3048)
							(mid 0.275042 0.275042)
							(end 0.3048 0.2032)
						)
					)
					(width 0)
					(fill yes)
				)
			)
		)
		(pad "2" smd custom
			(at 0 0.4445 270)
			(size 0.1524 0.1524)
			(layers "F.Cu" "F.Mask" "F.Paste")
			(net "GND")
			(options
				(clearance outline)
				(anchor circle)
			)
			(primitives
				(gr_poly
					(pts
						(arc
							(start 0.3048 -0.2032)
							(mid 0.275042 -0.275042)
							(end 0.2032 -0.3048)
						)
						(arc
							(start -0.2032 -0.3048)
							(mid -0.275042 -0.275042)
							(end -0.3048 -0.2032)
						)
						(arc
							(start -0.3048 0.2032)
							(mid -0.275042 0.275042)
							(end -0.2032 0.3048)
						)
						(arc
							(start 0.2032 0.3048)
							(mid 0.275042 0.275042)
							(end 0.3048 0.2032)
						)
					)
					(width 0)
					(fill yes)
				)
			)
		)
	)
	(footprint ""
		(layer "F.Cu")
		(at 18.3896 -85.852 -90)
		(property "Reference" "C541"
			(at 0 0 270)
			(layer "F.SilkS")
			(hide yes)
			(effects
				(font
					(size 1.27 1.27)
				)
			)
		)
		(property "Value" "SCD1U16V2KX-3GP"
			(at 1.1811 -2.7051 270)
			(unlocked yes)
			(layer "F.Fab")
			(hide yes)
			(effects
				(font
					(size 1.016 1.016)
					(thickness 0.1524)
				)
			)
		)
		(property "Device Type" "C402H22"
			(at 1.1811 -4.2291 270)
			(unlocked yes)
			(layer "F.Fab")
			(hide yes)
			(effects
				(font
					(size 1.016 1.016)
					(thickness 0.1524)
				)
			)
		)
		(duplicate_pad_numbers_are_jumpers no)
		(fp_rect
			(start -0.4318 0.9525)
			(end 0.4318 -0.9525)
			(stroke
				(width 0)
				(type default)
			)
			(fill no)
			(layer "F.CrtYd")
		)
		(fp_rect
			(start -0.4318 0.9525)
			(end 0.4318 -0.9525)
			(stroke
				(width 0)
				(type default)
			)
			(fill no)
			(layer "F.Fab")
		)
		(pad "1" smd custom
			(at 0 -0.4445 270)
			(size 0.1524 0.1524)
			(layers "F.Cu" "F.Mask" "F.Paste")
			(net "P1V8_E")
			(options
				(clearance outline)
				(anchor circle)
			)
			(primitives
				(gr_poly
					(pts
						(arc
							(start 0.3048 -0.2032)
							(mid 0.275042 -0.275042)
							(end 0.2032 -0.3048)
						)
						(arc
							(start -0.2032 -0.3048)
							(mid -0.275042 -0.275042)
							(end -0.3048 -0.2032)
						)
						(arc
							(start -0.3048 0.2032)
							(mid -0.275042 0.275042)
							(end -0.2032 0.3048)
						)
						(arc
							(start 0.2032 0.3048)
							(mid 0.275042 0.275042)
							(end 0.3048 0.2032)
						)
					)
					(width 0)
					(fill yes)
				)
			)
		)
		(pad "2" smd custom
			(at 0 0.4445 270)
			(size 0.1524 0.1524)
			(layers "F.Cu" "F.Mask" "F.Paste")
			(net "GND")
			(options
				(clearance outline)
				(anchor circle)
			)
			(primitives
				(gr_poly
					(pts
						(arc
							(start 0.3048 -0.2032)
							(mid 0.275042 -0.275042)
							(end 0.2032 -0.3048)
						)
						(arc
							(start -0.2032 -0.3048)
							(mid -0.275042 -0.275042)
							(end -0.3048 -0.2032)
						)
						(arc
							(start -0.3048 0.2032)
							(mid -0.275042 0.275042)
							(end -0.2032 0.3048)
						)
						(arc
							(start 0.2032 0.3048)
							(mid 0.275042 0.275042)
							(end 0.3048 0.2032)
						)
					)
					(width 0)
					(fill yes)
				)
			)
		)
	)
	(footprint ""
		(layer "F.Cu")
		(at 7.2898 -75.3618 90)
		(property "Reference" "R358"
			(at 0 0 90)
			(layer "F.SilkS")
			(hide yes)
			(effects
				(font
					(size 1.27 1.27)
				)
			)
		)
		(property "Value" "4K7R2F-GP"
			(at 0.064008 -3.993896 90)
			(unlocked yes)
			(layer "F.Fab")
			(hide yes)
			(effects
				(font
					(size 1.016 1.016)
					(thickness 0.1524)
				)
			)
		)
		(property "Device Type" "R402H16"
			(at 0.064008 -5.517896 90)
			(unlocked yes)
			(layer "F.Fab")
			(hide yes)
			(effects
				(font
					(size 1.016 1.016)
					(thickness 0.1524)
				)
			)
		)
		(duplicate_pad_numbers_are_jumpers no)
		(fp_line
			(start 0.508 -0.9398)
			(end -0.508 -0.9398)
			(stroke
				(width 0.1524)
				(type default)
			)
			(layer "F.SilkS")
		)
		(fp_line
			(start -0.508 -0.9398)
			(end -0.508 0.9398)
			(stroke
				(width 0.1524)
				(type default)
			)
			(layer "F.SilkS")
		)
		(fp_rect
			(start -0.508 0.9398)
			(end 0.508 -0.9398)
			(stroke
				(width 0)
				(type default)
			)
			(fill no)
			(layer "F.CrtYd")
		)
		(fp_rect
			(start -0.508 0.9398)
			(end 0.508 -0.9398)
			(stroke
				(width 0)
				(type default)
			)
			(fill no)
			(layer "F.Fab")
		)
		(pad "1" smd custom
			(at 0 -0.4445 90)
			(size 0.1397 0.1397)
			(layers "F.Cu" "F.Mask" "F.Paste")
			(net "P3V3")
			(options
				(clearance outline)
				(anchor circle)
			)
			(primitives
				(gr_poly
					(pts
						(arc
							(start -0.1778 -0.2794)
							(mid -0.249642 -0.249642)
							(end -0.2794 -0.1778)
						)
						(arc
							(start -0.2794 0.1778)
							(mid -0.249642 0.249642)
							(end -0.1778 0.2794)
						)
						(arc
							(start 0.1778 0.2794)
							(mid 0.249642 0.249642)
							(end 0.2794 0.1778)
						)
						(arc
							(start 0.2794 -0.1778)
							(mid 0.249642 -0.249642)
							(end 0.1778 -0.2794)
						)
					)
					(width 0)
					(fill yes)
				)
			)
		)
		(pad "2" smd custom
			(at 0 0.4445 90)
			(size 0.1397 0.1397)
			(layers "F.Cu" "F.Mask" "F.Paste")
			(net "FRU_EEPROM_A0")
			(options
				(clearance outline)
				(anchor circle)
			)
			(primitives
				(gr_poly
					(pts
						(arc
							(start -0.1778 -0.2794)
							(mid -0.249642 -0.249642)
							(end -0.2794 -0.1778)
						)
						(arc
							(start -0.2794 0.1778)
							(mid -0.249642 0.249642)
							(end -0.1778 0.2794)
						)
						(arc
							(start 0.1778 0.2794)
							(mid 0.249642 0.249642)
							(end 0.2794 0.1778)
						)
						(arc
							(start 0.2794 -0.1778)
							(mid 0.249642 -0.249642)
							(end 0.1778 -0.2794)
						)
					)
					(width 0)
					(fill yes)
				)
			)
		)
	)
	(footprint ""
		(layer "F.Cu")
		(at 157.861 -120.523)
		(property "Reference" "R320"
			(at 0 0 0)
			(layer "F.SilkS")
			(hide yes)
			(effects
				(font
					(size 1.27 1.27)
				)
			)
		)
		(property "Value" "69K8R2F-GP"
			(at 0.064008 -3.993896 0)
			(unlocked yes)
			(layer "F.Fab")
			(hide yes)
			(effects
				(font
					(size 1.016 1.016)
					(thickness 0.1524)
				)
			)
		)
		(property "Device Type" "R402H16"
			(at 0.064008 -5.517896 0)
			(unlocked yes)
			(layer "F.Fab")
			(hide yes)
			(effects
				(font
					(size 1.016 1.016)
					(thickness 0.1524)
				)
			)
		)
		(duplicate_pad_numbers_are_jumpers no)
		(fp_line
			(start -0.508 -0.9398)
			(end -0.508 0.9398)
			(stroke
				(width 0.1524)
				(type default)
			)
			(layer "F.SilkS")
		)
		(fp_line
			(start 0.508 -0.9398)
			(end -0.508 -0.9398)
			(stroke
				(width 0.1524)
				(type default)
			)
			(layer "F.SilkS")
		)
		(fp_rect
			(start -0.508 0.9398)
			(end 0.508 -0.9398)
			(stroke
				(width 0)
				(type default)
			)
			(fill no)
			(layer "F.CrtYd")
		)
		(fp_rect
			(start -0.508 0.9398)
			(end 0.508 -0.9398)
			(stroke
				(width 0)
				(type default)
			)
			(fill no)
			(layer "F.Fab")
		)
		(pad "1" smd custom
			(at 0 -0.4445)
			(size 0.1397 0.1397)
			(layers "F.Cu" "F.Mask" "F.Paste")
			(net "AGND_P1V5_E")
			(options
				(clearance outline)
				(anchor circle)
			)
			(primitives
				(gr_poly
					(pts
						(arc
							(start -0.1778 -0.2794)
							(mid -0.249642 -0.249642)
							(end -0.2794 -0.1778)
						)
						(arc
							(start -0.2794 0.1778)
							(mid -0.249642 0.249642)
							(end -0.1778 0.2794)
						)
						(arc
							(start 0.1778 0.2794)
							(mid 0.249642 0.249642)
							(end 0.2794 0.1778)
						)
						(arc
							(start 0.2794 -0.1778)
							(mid 0.249642 -0.249642)
							(end 0.1778 -0.2794)
						)
					)
					(width 0)
					(fill yes)
				)
			)
		)
		(pad "2" smd custom
			(at 0 0.4445)
			(size 0.1397 0.1397)
			(layers "F.Cu" "F.Mask" "F.Paste")
			(net "P1V5_E_TRIP")
			(options
				(clearance outline)
				(anchor circle)
			)
			(primitives
				(gr_poly
					(pts
						(arc
							(start -0.1778 -0.2794)
							(mid -0.249642 -0.249642)
							(end -0.2794 -0.1778)
						)
						(arc
							(start -0.2794 0.1778)
							(mid -0.249642 0.249642)
							(end -0.1778 0.2794)
						)
						(arc
							(start 0.1778 0.2794)
							(mid 0.249642 0.249642)
							(end 0.2794 0.1778)
						)
						(arc
							(start 0.2794 -0.1778)
							(mid 0.249642 -0.249642)
							(end 0.1778 -0.2794)
						)
					)
					(width 0)
					(fill yes)
				)
			)
		)
	)
	(footprint ""
		(layer "F.Cu")
		(at 174.4726 -59.817)
		(property "Reference" "R253"
			(at 0 0 0)
			(layer "F.SilkS")
			(hide yes)
			(effects
				(font
					(size 1.27 1.27)
				)
			)
		)
		(property "Value" "10KR2F-2-GP"
			(at 0.064008 -3.993896 0)
			(unlocked yes)
			(layer "F.Fab")
			(hide yes)
			(effects
				(font
					(size 1.016 1.016)
					(thickness 0.1524)
				)
			)
		)
		(property "Device Type" "R402H16"
			(at 0.064008 -5.517896 0)
			(unlocked yes)
			(layer "F.Fab")
			(hide yes)
			(effects
				(font
					(size 1.016 1.016)
					(thickness 0.1524)
				)
			)
		)
		(duplicate_pad_numbers_are_jumpers no)
		(fp_line
			(start -0.508 -0.9398)
			(end -0.508 0.9398)
			(stroke
				(width 0.1524)
				(type default)
			)
			(layer "F.SilkS")
		)
		(fp_line
			(start 0.508 -0.9398)
			(end -0.508 -0.9398)
			(stroke
				(width 0.1524)
				(type default)
			)
			(layer "F.SilkS")
		)
		(fp_rect
			(start -0.508 0.9398)
			(end 0.508 -0.9398)
			(stroke
				(width 0)
				(type default)
			)
			(fill no)
			(layer "F.CrtYd")
		)
		(fp_rect
			(start -0.508 0.9398)
			(end 0.508 -0.9398)
			(stroke
				(width 0)
				(type default)
			)
			(fill no)
			(layer "F.Fab")
		)
		(pad "1" smd custom
			(at 0 -0.4445)
			(size 0.1397 0.1397)
			(layers "F.Cu" "F.Mask" "F.Paste")
			(net "P1V8_C")
			(options
				(clearance outline)
				(anchor circle)
			)
			(primitives
				(gr_poly
					(pts
						(arc
							(start -0.1778 -0.2794)
							(mid -0.249642 -0.249642)
							(end -0.2794 -0.1778)
						)
						(arc
							(start -0.2794 0.1778)
							(mid -0.249642 0.249642)
							(end -0.1778 0.2794)
						)
						(arc
							(start 0.1778 0.2794)
							(mid 0.249642 0.249642)
							(end 0.2794 0.1778)
						)
						(arc
							(start 0.2794 -0.1778)
							(mid 0.249642 -0.249642)
							(end 0.1778 -0.2794)
						)
					)
					(width 0)
					(fill yes)
				)
			)
		)
		(pad "2" smd custom
			(at 0 0.4445)
			(size 0.1397 0.1397)
			(layers "F.Cu" "F.Mask" "F.Paste")
			(net "LSI_JTAG_EN_N")
			(options
				(clearance outline)
				(anchor circle)
			)
			(primitives
				(gr_poly
					(pts
						(arc
							(start -0.1778 -0.2794)
							(mid -0.249642 -0.249642)
							(end -0.2794 -0.1778)
						)
						(arc
							(start -0.2794 0.1778)
							(mid -0.249642 0.249642)
							(end -0.1778 0.2794)
						)
						(arc
							(start 0.1778 0.2794)
							(mid 0.249642 0.249642)
							(end 0.2794 0.1778)
						)
						(arc
							(start 0.2794 -0.1778)
							(mid 0.249642 -0.249642)
							(end 0.1778 -0.2794)
						)
					)
					(width 0)
					(fill yes)
				)
			)
		)
	)
	(footprint ""
		(layer "F.Cu")
		(at 9.24687 -47.248318)
		(property "Reference" "R436"
			(at 0 0 0)
			(layer "F.SilkS")
			(hide yes)
			(effects
				(font
					(size 1.27 1.27)
				)
			)
		)
		(property "Value" "100R2D-GP"
			(at 0.064008 -3.993896 0)
			(unlocked yes)
			(layer "F.Fab")
			(hide yes)
			(effects
				(font
					(size 1.016 1.016)
					(thickness 0.1524)
				)
			)
		)
		(property "Device Type" "R402H14"
			(at 0.064008 -5.517896 0)
			(unlocked yes)
			(layer "F.Fab")
			(hide yes)
			(effects
				(font
					(size 1.016 1.016)
					(thickness 0.1524)
				)
			)
		)
		(duplicate_pad_numbers_are_jumpers no)
		(fp_line
			(start -0.508 -0.9398)
			(end -0.508 0.9398)
			(stroke
				(width 0.1524)
				(type default)
			)
			(layer "F.SilkS")
		)
		(fp_line
			(start 0.508 -0.9398)
			(end -0.508 -0.9398)
			(stroke
				(width 0.1524)
				(type default)
			)
			(layer "F.SilkS")
		)
		(fp_rect
			(start -0.508 0.9398)
			(end 0.508 -0.9398)
			(stroke
				(width 0)
				(type default)
			)
			(fill no)
			(layer "F.CrtYd")
		)
		(fp_rect
			(start -0.508 0.9398)
			(end 0.508 -0.9398)
			(stroke
				(width 0)
				(type default)
			)
			(fill no)
			(layer "F.Fab")
		)
		(pad "1" smd custom
			(at 0 -0.4445)
			(size 0.1397 0.1397)
			(layers "F.Cu" "F.Mask" "F.Paste")
			(net "MB0_TEMP")
			(options
				(clearance outline)
				(anchor circle)
			)
			(primitives
				(gr_poly
					(pts
						(arc
							(start -0.1778 -0.2794)
							(mid -0.249642 -0.249642)
							(end -0.2794 -0.1778)
						)
						(arc
							(start -0.2794 0.1778)
							(mid -0.249642 0.249642)
							(end -0.1778 0.2794)
						)
						(arc
							(start 0.1778 0.2794)
							(mid 0.249642 0.249642)
							(end 0.2794 0.1778)
						)
						(arc
							(start 0.2794 -0.1778)
							(mid 0.249642 -0.249642)
							(end 0.1778 -0.2794)
						)
					)
					(width 0)
					(fill yes)
				)
			)
		)
		(pad "2" smd custom
			(at 0 0.4445)
			(size 0.1397 0.1397)
			(layers "F.Cu" "F.Mask" "F.Paste")
			(net "MB0_TEMP_C")
			(options
				(clearance outline)
				(anchor circle)
			)
			(primitives
				(gr_poly
					(pts
						(arc
							(start -0.1778 -0.2794)
							(mid -0.249642 -0.249642)
							(end -0.2794 -0.1778)
						)
						(arc
							(start -0.2794 0.1778)
							(mid -0.249642 0.249642)
							(end -0.1778 0.2794)
						)
						(arc
							(start 0.1778 0.2794)
							(mid 0.249642 0.249642)
							(end 0.2794 0.1778)
						)
						(arc
							(start 0.2794 -0.1778)
							(mid 0.249642 -0.249642)
							(end 0.1778 -0.2794)
						)
					)
					(width 0)
					(fill yes)
				)
			)
		)
	)
	(footprint ""
		(layer "F.Cu")
		(at 9.7028 -93.6244)
		(property "Reference" "R413"
			(at 0 0 0)
			(layer "F.SilkS")
			(hide yes)
			(effects
				(font
					(size 1.27 1.27)
				)
			)
		)
		(property "Value" "1KR2F-3-GP"
			(at 0.064008 -3.993896 0)
			(unlocked yes)
			(layer "F.Fab")
			(hide yes)
			(effects
				(font
					(size 1.016 1.016)
					(thickness 0.1524)
				)
			)
		)
		(property "Device Type" "R402H16"
			(at 0.064008 -5.517896 0)
			(unlocked yes)
			(layer "F.Fab")
			(hide yes)
			(effects
				(font
					(size 1.016 1.016)
					(thickness 0.1524)
				)
			)
		)
		(duplicate_pad_numbers_are_jumpers no)
		(fp_line
			(start -0.508 -0.9398)
			(end -0.508 0.9398)
			(stroke
				(width 0.1524)
				(type default)
			)
			(layer "F.SilkS")
		)
		(fp_line
			(start 0.508 -0.9398)
			(end -0.508 -0.9398)
			(stroke
				(width 0.1524)
				(type default)
			)
			(layer "F.SilkS")
		)
		(fp_rect
			(start -0.508 0.9398)
			(end 0.508 -0.9398)
			(stroke
				(width 0)
				(type default)
			)
			(fill no)
			(layer "F.CrtYd")
		)
		(fp_rect
			(start -0.508 0.9398)
			(end 0.508 -0.9398)
			(stroke
				(width 0)
				(type default)
			)
			(fill no)
			(layer "F.Fab")
		)
		(pad "1" smd custom
			(at 0 -0.4445)
			(size 0.1397 0.1397)
			(layers "F.Cu" "F.Mask" "F.Paste")
			(net "P3V3")
			(options
				(clearance outline)
				(anchor circle)
			)
			(primitives
				(gr_poly
					(pts
						(arc
							(start -0.1778 -0.2794)
							(mid -0.249642 -0.249642)
							(end -0.2794 -0.1778)
						)
						(arc
							(start -0.2794 0.1778)
							(mid -0.249642 0.249642)
							(end -0.1778 0.2794)
						)
						(arc
							(start 0.1778 0.2794)
							(mid 0.249642 0.249642)
							(end 0.2794 0.1778)
						)
						(arc
							(start 0.2794 -0.1778)
							(mid 0.249642 -0.249642)
							(end 0.1778 -0.2794)
						)
					)
					(width 0)
					(fill yes)
				)
			)
		)
		(pad "2" smd custom
			(at 0 0.4445)
			(size 0.1397 0.1397)
			(layers "F.Cu" "F.Mask" "F.Paste")
			(net "I2C_SCC_SDA2")
			(options
				(clearance outline)
				(anchor circle)
			)
			(primitives
				(gr_poly
					(pts
						(arc
							(start -0.1778 -0.2794)
							(mid -0.249642 -0.249642)
							(end -0.2794 -0.1778)
						)
						(arc
							(start -0.2794 0.1778)
							(mid -0.249642 0.249642)
							(end -0.1778 0.2794)
						)
						(arc
							(start 0.1778 0.2794)
							(mid 0.249642 0.249642)
							(end 0.2794 0.1778)
						)
						(arc
							(start 0.2794 -0.1778)
							(mid 0.249642 -0.249642)
							(end 0.1778 -0.2794)
						)
					)
					(width 0)
					(fill yes)
				)
			)
		)
	)
	(footprint ""
		(layer "F.Cu")
		(at 158.369 -83.224116 -90)
		(property "Reference" "C525"
			(at 0 0 270)
			(layer "F.SilkS")
			(hide yes)
			(effects
				(font
					(size 1.27 1.27)
				)
			)
		)
		(property "Value" "SCD1U16V2KX-3GP"
			(at 1.1811 -2.7051 270)
			(unlocked yes)
			(layer "F.Fab")
			(hide yes)
			(effects
				(font
					(size 1.016 1.016)
					(thickness 0.1524)
				)
			)
		)
		(property "Device Type" "C402H22"
			(at 1.1811 -4.2291 270)
			(unlocked yes)
			(layer "F.Fab")
			(hide yes)
			(effects
				(font
					(size 1.016 1.016)
					(thickness 0.1524)
				)
			)
		)
		(duplicate_pad_numbers_are_jumpers no)
		(fp_rect
			(start -0.4318 0.9525)
			(end 0.4318 -0.9525)
			(stroke
				(width 0)
				(type default)
			)
			(fill no)
			(layer "F.CrtYd")
		)
		(fp_rect
			(start -0.4318 0.9525)
			(end 0.4318 -0.9525)
			(stroke
				(width 0)
				(type default)
			)
			(fill no)
			(layer "F.Fab")
		)
		(pad "1" smd custom
			(at 0 -0.4445 270)
			(size 0.1524 0.1524)
			(layers "F.Cu" "F.Mask" "F.Paste")
			(net "P1V5_E_SENSE")
			(options
				(clearance outline)
				(anchor circle)
			)
			(primitives
				(gr_poly
					(pts
						(arc
							(start 0.3048 -0.2032)
							(mid 0.275042 -0.275042)
							(end 0.2032 -0.3048)
						)
						(arc
							(start -0.2032 -0.3048)
							(mid -0.275042 -0.275042)
							(end -0.3048 -0.2032)
						)
						(arc
							(start -0.3048 0.2032)
							(mid -0.275042 0.275042)
							(end -0.2032 0.3048)
						)
						(arc
							(start 0.2032 0.3048)
							(mid 0.275042 0.275042)
							(end 0.3048 0.2032)
						)
					)
					(width 0)
					(fill yes)
				)
			)
		)
		(pad "2" smd custom
			(at 0 0.4445 270)
			(size 0.1524 0.1524)
			(layers "F.Cu" "F.Mask" "F.Paste")
			(net "GND")
			(options
				(clearance outline)
				(anchor circle)
			)
			(primitives
				(gr_poly
					(pts
						(arc
							(start 0.3048 -0.2032)
							(mid 0.275042 -0.275042)
							(end 0.2032 -0.3048)
						)
						(arc
							(start -0.2032 -0.3048)
							(mid -0.275042 -0.275042)
							(end -0.3048 -0.2032)
						)
						(arc
							(start -0.3048 0.2032)
							(mid -0.275042 0.275042)
							(end -0.2032 0.3048)
						)
						(arc
							(start 0.2032 0.3048)
							(mid 0.275042 0.275042)
							(end 0.3048 0.2032)
						)
					)
					(width 0)
					(fill yes)
				)
			)
		)
	)
	(footprint ""
		(layer "F.Cu")
		(at 178.08448 -110.64748 180)
		(property "Reference" "C602"
			(at 0 0 180)
			(layer "F.SilkS")
			(hide yes)
			(effects
				(font
					(size 1.27 1.27)
				)
			)
		)
		(property "Value" "SC470P50V2KX-3GP"
			(at 1.1811 -2.7051 180)
			(unlocked yes)
			(layer "F.Fab")
			(hide yes)
			(effects
				(font
					(size 1.016 1.016)
					(thickness 0.1524)
				)
			)
		)
		(property "Device Type" "C402H22"
			(at 1.1811 -4.2291 180)
			(unlocked yes)
			(layer "F.Fab")
			(hide yes)
			(effects
				(font
					(size 1.016 1.016)
					(thickness 0.1524)
				)
			)
		)
		(duplicate_pad_numbers_are_jumpers no)
		(fp_rect
			(start -0.4318 0.9525)
			(end 0.4318 -0.9525)
			(stroke
				(width 0)
				(type default)
			)
			(fill no)
			(layer "F.CrtYd")
		)
		(fp_rect
			(start -0.4318 0.9525)
			(end 0.4318 -0.9525)
			(stroke
				(width 0)
				(type default)
			)
			(fill no)
			(layer "F.Fab")
		)
		(pad "1" smd custom
			(at 0 -0.4445 180)
			(size 0.1524 0.1524)
			(layers "F.Cu" "F.Mask" "F.Paste")
			(net "GND")
			(options
				(clearance outline)
				(anchor circle)
			)
			(primitives
				(gr_poly
					(pts
						(arc
							(start 0.3048 -0.2032)
							(mid 0.275042 -0.275042)
							(end 0.2032 -0.3048)
						)
						(arc
							(start -0.2032 -0.3048)
							(mid -0.275042 -0.275042)
							(end -0.3048 -0.2032)
						)
						(arc
							(start -0.3048 0.2032)
							(mid -0.275042 0.275042)
							(end -0.2032 0.3048)
						)
						(arc
							(start 0.2032 0.3048)
							(mid 0.275042 0.275042)
							(end 0.3048 0.2032)
						)
					)
					(width 0)
					(fill yes)
				)
			)
		)
		(pad "2" smd custom
			(at 0 0.4445 180)
			(size 0.1524 0.1524)
			(layers "F.Cu" "F.Mask" "F.Paste")
			(net "P1V8_E_SS")
			(options
				(clearance outline)
				(anchor circle)
			)
			(primitives
				(gr_poly
					(pts
						(arc
							(start 0.3048 -0.2032)
							(mid 0.275042 -0.275042)
							(end 0.2032 -0.3048)
						)
						(arc
							(start -0.2032 -0.3048)
							(mid -0.275042 -0.275042)
							(end -0.3048 -0.2032)
						)
						(arc
							(start -0.3048 0.2032)
							(mid -0.275042 0.275042)
							(end -0.2032 0.3048)
						)
						(arc
							(start 0.2032 0.3048)
							(mid 0.275042 0.275042)
							(end 0.3048 0.2032)
						)
					)
					(width 0)
					(fill yes)
				)
			)
		)
	)
	(footprint ""
		(layer "F.Cu")
		(at 178.181 -57.277)
		(property "Reference" "TP143"
			(at 0 0 0)
			(layer "F.SilkS")
			(hide yes)
			(effects
				(font
					(size 1.27 1.27)
				)
			)
		)
		(property "Value" "TPAD28-2-GP"
			(at -0.0127 -1.6637 0)
			(unlocked yes)
			(layer "F.Fab")
			(hide yes)
			(effects
				(font
					(size 1.016 1.016)
					(thickness 0.1524)
				)
			)
		)
		(property "Device Type" "TPAD28"
			(at -0.0127 -3.1877 0)
			(unlocked yes)
			(layer "F.Fab")
			(hide yes)
			(effects
				(font
					(size 1.016 1.016)
					(thickness 0.1524)
				)
			)
		)
		(duplicate_pad_numbers_are_jumpers no)
		(fp_poly
			(pts
				(arc
					(start 0.3556 0)
					(mid -0.3556 0)
					(end 0.3556 0)
				)
			)
			(stroke
				(width 0)
				(type default)
			)
			(fill no)
			(layer "F.CrtYd")
		)
		(fp_poly
			(pts
				(arc
					(start 0.6096 0)
					(mid -0.6096 0)
					(end 0.6096 0)
				)
			)
			(stroke
				(width 0)
				(type default)
			)
			(fill no)
			(layer "F.Fab")
		)
		(pad "1" smd circle
			(at 0 0)
			(size 0.7112 0.7112)
			(layers "F.Cu" "F.Mask" "F.Paste")
			(net "LSI_IDDT")
		)
	)
	(footprint ""
		(layer "F.Cu")
		(at 150.79218 -108.38688 -90)
		(property "Reference" "C576"
			(at 0 0 270)
			(layer "F.SilkS")
			(hide yes)
			(effects
				(font
					(size 1.27 1.27)
				)
			)
		)
		(property "Value" "SCD1U16V2KX-3GP"
			(at 1.1811 -2.7051 270)
			(unlocked yes)
			(layer "F.Fab")
			(hide yes)
			(effects
				(font
					(size 1.016 1.016)
					(thickness 0.1524)
				)
			)
		)
		(property "Device Type" "C402H22"
			(at 1.1811 -4.2291 270)
			(unlocked yes)
			(layer "F.Fab")
			(hide yes)
			(effects
				(font
					(size 1.016 1.016)
					(thickness 0.1524)
				)
			)
		)
		(duplicate_pad_numbers_are_jumpers no)
		(fp_rect
			(start -0.4318 0.9525)
			(end 0.4318 -0.9525)
			(stroke
				(width 0)
				(type default)
			)
			(fill no)
			(layer "F.CrtYd")
		)
		(fp_rect
			(start -0.4318 0.9525)
			(end 0.4318 -0.9525)
			(stroke
				(width 0)
				(type default)
			)
			(fill no)
			(layer "F.Fab")
		)
		(pad "1" smd custom
			(at 0 -0.4445 270)
			(size 0.1524 0.1524)
			(layers "F.Cu" "F.Mask" "F.Paste")
			(net "SDB_CONN_PWR_2")
			(options
				(clearance outline)
				(anchor circle)
			)
			(primitives
				(gr_poly
					(pts
						(arc
							(start 0.3048 -0.2032)
							(mid 0.275042 -0.275042)
							(end 0.2032 -0.3048)
						)
						(arc
							(start -0.2032 -0.3048)
							(mid -0.275042 -0.275042)
							(end -0.3048 -0.2032)
						)
						(arc
							(start -0.3048 0.2032)
							(mid -0.275042 0.275042)
							(end -0.2032 0.3048)
						)
						(arc
							(start 0.2032 0.3048)
							(mid 0.275042 0.275042)
							(end 0.3048 0.2032)
						)
					)
					(width 0)
					(fill yes)
				)
			)
		)
		(pad "2" smd custom
			(at 0 0.4445 270)
			(size 0.1524 0.1524)
			(layers "F.Cu" "F.Mask" "F.Paste")
			(net "GND")
			(options
				(clearance outline)
				(anchor circle)
			)
			(primitives
				(gr_poly
					(pts
						(arc
							(start 0.3048 -0.2032)
							(mid 0.275042 -0.275042)
							(end 0.2032 -0.3048)
						)
						(arc
							(start -0.2032 -0.3048)
							(mid -0.275042 -0.275042)
							(end -0.3048 -0.2032)
						)
						(arc
							(start -0.3048 0.2032)
							(mid -0.275042 0.275042)
							(end -0.2032 0.3048)
						)
						(arc
							(start 0.2032 0.3048)
							(mid 0.275042 0.275042)
							(end 0.3048 0.2032)
						)
					)
					(width 0)
					(fill yes)
				)
			)
		)
	)
	(footprint ""
		(layer "F.Cu")
		(at 70.223126 -94.84995 -90)
		(property "Reference" "R505"
			(at 0 0 270)
			(layer "F.SilkS")
			(hide yes)
			(effects
				(font
					(size 1.27 1.27)
				)
			)
		)
		(property "Value" "100KR2F-L1-GP"
			(at 0.064008 -3.993896 270)
			(unlocked yes)
			(layer "F.Fab")
			(hide yes)
			(effects
				(font
					(size 1.016 1.016)
					(thickness 0.1524)
				)
			)
		)
		(property "Device Type" "R402H16"
			(at 0.064008 -5.517896 270)
			(unlocked yes)
			(layer "F.Fab")
			(hide yes)
			(effects
				(font
					(size 1.016 1.016)
					(thickness 0.1524)
				)
			)
		)
		(duplicate_pad_numbers_are_jumpers no)
		(fp_line
			(start -0.508 -0.9398)
			(end -0.508 0.9398)
			(stroke
				(width 0.1524)
				(type default)
			)
			(layer "F.SilkS")
		)
		(fp_line
			(start 0.508 -0.9398)
			(end -0.508 -0.9398)
			(stroke
				(width 0.1524)
				(type default)
			)
			(layer "F.SilkS")
		)
		(fp_rect
			(start -0.508 0.9398)
			(end 0.508 -0.9398)
			(stroke
				(width 0)
				(type default)
			)
			(fill no)
			(layer "F.CrtYd")
		)
		(fp_rect
			(start -0.508 0.9398)
			(end 0.508 -0.9398)
			(stroke
				(width 0)
				(type default)
			)
			(fill no)
			(layer "F.Fab")
		)
		(pad "1" smd custom
			(at 0 -0.4445 270)
			(size 0.1397 0.1397)
			(layers "F.Cu" "F.Mask" "F.Paste")
			(net "AGND_P3V3")
			(options
				(clearance outline)
				(anchor circle)
			)
			(primitives
				(gr_poly
					(pts
						(arc
							(start -0.1778 -0.2794)
							(mid -0.249642 -0.249642)
							(end -0.2794 -0.1778)
						)
						(arc
							(start -0.2794 0.1778)
							(mid -0.249642 0.249642)
							(end -0.1778 0.2794)
						)
						(arc
							(start 0.1778 0.2794)
							(mid 0.249642 0.249642)
							(end 0.2794 0.1778)
						)
						(arc
							(start 0.2794 -0.1778)
							(mid 0.249642 -0.249642)
							(end 0.1778 -0.2794)
						)
					)
					(width 0)
					(fill yes)
				)
			)
		)
		(pad "2" smd custom
			(at 0 0.4445 270)
			(size 0.1397 0.1397)
			(layers "F.Cu" "F.Mask" "F.Paste")
			(net "P3V3_MODE")
			(options
				(clearance outline)
				(anchor circle)
			)
			(primitives
				(gr_poly
					(pts
						(arc
							(start -0.1778 -0.2794)
							(mid -0.249642 -0.249642)
							(end -0.2794 -0.1778)
						)
						(arc
							(start -0.2794 0.1778)
							(mid -0.249642 0.249642)
							(end -0.1778 0.2794)
						)
						(arc
							(start 0.1778 0.2794)
							(mid 0.249642 0.249642)
							(end 0.2794 0.1778)
						)
						(arc
							(start 0.2794 -0.1778)
							(mid 0.249642 -0.249642)
							(end 0.1778 -0.2794)
						)
					)
					(width 0)
					(fill yes)
				)
			)
		)
	)
	(footprint ""
		(layer "F.Cu")
		(at 57.4548 -103.2256)
		(property "Reference" "C711"
			(at 0 0 0)
			(layer "F.SilkS")
			(hide yes)
			(effects
				(font
					(size 1.27 1.27)
				)
			)
		)
		(property "Value" "SC2200P50V2KX-2GP"
			(at 1.1811 -2.7051 0)
			(unlocked yes)
			(layer "F.Fab")
			(hide yes)
			(effects
				(font
					(size 1.016 1.016)
					(thickness 0.1524)
				)
			)
		)
		(property "Device Type" "C402H22"
			(at 1.1811 -4.2291 0)
			(unlocked yes)
			(layer "F.Fab")
			(hide yes)
			(effects
				(font
					(size 1.016 1.016)
					(thickness 0.1524)
				)
			)
		)
		(duplicate_pad_numbers_are_jumpers no)
		(fp_rect
			(start -0.4318 0.9525)
			(end 0.4318 -0.9525)
			(stroke
				(width 0)
				(type default)
			)
			(fill no)
			(layer "F.CrtYd")
		)
		(fp_rect
			(start -0.4318 0.9525)
			(end 0.4318 -0.9525)
			(stroke
				(width 0)
				(type default)
			)
			(fill no)
			(layer "F.Fab")
		)
		(pad "1" smd custom
			(at 0 -0.4445)
			(size 0.1524 0.1524)
			(layers "F.Cu" "F.Mask" "F.Paste")
			(net "P3V3_LL")
			(options
				(clearance outline)
				(anchor circle)
			)
			(primitives
				(gr_poly
					(pts
						(arc
							(start 0.3048 -0.2032)
							(mid 0.275042 -0.275042)
							(end 0.2032 -0.3048)
						)
						(arc
							(start -0.2032 -0.3048)
							(mid -0.275042 -0.275042)
							(end -0.3048 -0.2032)
						)
						(arc
							(start -0.3048 0.2032)
							(mid -0.275042 0.275042)
							(end -0.2032 0.3048)
						)
						(arc
							(start 0.2032 0.3048)
							(mid 0.275042 0.275042)
							(end 0.3048 0.2032)
						)
					)
					(width 0)
					(fill yes)
				)
			)
		)
		(pad "2" smd custom
			(at 0 0.4445)
			(size 0.1524 0.1524)
			(layers "F.Cu" "F.Mask" "F.Paste")
			(net "P3V3_SNB")
			(options
				(clearance outline)
				(anchor circle)
			)
			(primitives
				(gr_poly
					(pts
						(arc
							(start 0.3048 -0.2032)
							(mid 0.275042 -0.275042)
							(end 0.2032 -0.3048)
						)
						(arc
							(start -0.2032 -0.3048)
							(mid -0.275042 -0.275042)
							(end -0.3048 -0.2032)
						)
						(arc
							(start -0.3048 0.2032)
							(mid -0.275042 0.275042)
							(end -0.2032 0.3048)
						)
						(arc
							(start 0.2032 0.3048)
							(mid 0.275042 0.275042)
							(end 0.3048 0.2032)
						)
					)
					(width 0)
					(fill yes)
				)
			)
		)
	)
	(footprint ""
		(layer "F.Cu")
		(at 136.227312 -79.730092 90)
		(property "Reference" "C679"
			(at 0 0 90)
			(layer "F.SilkS")
			(hide yes)
			(effects
				(font
					(size 1.27 1.27)
				)
			)
		)
		(property "Value" "SCD01U16V1KX-GP"
			(at -2.8321 -1.7399 90)
			(unlocked yes)
			(layer "F.Fab")
			(hide yes)
			(effects
				(font
					(size 1.016 1.016)
					(thickness 0.1524)
				)
			)
		)
		(property "Device Type" "C0201H13"
			(at -2.8321 -3.2639 90)
			(unlocked yes)
			(layer "F.Fab")
			(hide yes)
			(effects
				(font
					(size 1.016 1.016)
					(thickness 0.1524)
				)
			)
		)
		(duplicate_pad_numbers_are_jumpers no)
		(fp_rect
			(start -0.2794 0.6477)
			(end 0.2794 -0.6477)
			(stroke
				(width 0)
				(type default)
			)
			(fill no)
			(layer "F.CrtYd")
		)
		(fp_rect
			(start -0.2794 0.6477)
			(end 0.2794 -0.6477)
			(stroke
				(width 0)
				(type default)
			)
			(fill no)
			(layer "F.Fab")
		)
		(pad "1" smd custom
			(at 0 -0.2794 90)
			(size 0.0762 0.0762)
			(layers "F.Cu" "F.Mask" "F.Paste")
			(net "PHY_EXP_TO_CONN_C_10_DN")
			(options
				(clearance outline)
				(anchor circle)
			)
			(primitives
				(gr_poly
					(pts
						(arc
							(start 0.1524 -0.127)
							(mid 0.137521 -0.162921)
							(end 0.1016 -0.1778)
						)
						(arc
							(start -0.1016 -0.1778)
							(mid -0.137521 -0.162921)
							(end -0.1524 -0.127)
						)
						(arc
							(start -0.1524 0.127)
							(mid -0.137521 0.162921)
							(end -0.1016 0.1778)
						)
						(arc
							(start 0.1016 0.1778)
							(mid 0.137521 0.162921)
							(end 0.1524 0.127)
						)
					)
					(width 0)
					(fill yes)
				)
			)
		)
		(pad "2" smd custom
			(at 0 0.2794 90)
			(size 0.0762 0.0762)
			(layers "F.Cu" "F.Mask" "F.Paste")
			(net "PHY_EXP_TO_CONN_10_DN")
			(options
				(clearance outline)
				(anchor circle)
			)
			(primitives
				(gr_poly
					(pts
						(arc
							(start 0.1524 -0.127)
							(mid 0.137521 -0.162921)
							(end 0.1016 -0.1778)
						)
						(arc
							(start -0.1016 -0.1778)
							(mid -0.137521 -0.162921)
							(end -0.1524 -0.127)
						)
						(arc
							(start -0.1524 0.127)
							(mid -0.137521 0.162921)
							(end -0.1016 0.1778)
						)
						(arc
							(start 0.1016 0.1778)
							(mid 0.137521 0.162921)
							(end 0.1524 0.127)
						)
					)
					(width 0)
					(fill yes)
				)
			)
		)
	)
	(footprint ""
		(layer "F.Cu")
		(at 139.60221 -61.122052)
		(property "Reference" "VIA14"
			(at 0 0 0)
			(layer "F.SilkS")
			(hide yes)
			(effects
				(font
					(size 1.27 1.27)
				)
			)
		)
		(property "Value" "100OHM-8L-1D6MM-L13-GP"
			(at 3.2893 0.0508 0)
			(unlocked yes)
			(layer "F.Fab")
			(hide yes)
			(effects
				(font
					(size 1.016 1.016)
					(thickness 0.1524)
				)
			)
		)
		(property "Device Type" "VIA-PCIE-4P-409091"
			(at 3.2893 -1.4732 0)
			(unlocked yes)
			(layer "F.Fab")
			(hide yes)
			(effects
				(font
					(size 1.016 1.016)
					(thickness 0.1524)
				)
			)
		)
		(duplicate_pad_numbers_are_jumpers no)
		(fp_rect
			(start -2.0447 0.4572)
			(end 2.0447 -0.4572)
			(stroke
				(width 0)
				(type default)
			)
			(fill no)
			(layer "F.CrtYd")
		)
		(fp_rect
			(start -2.0447 0.4572)
			(end 2.0447 -0.4572)
			(stroke
				(width 0)
				(type default)
			)
			(fill no)
			(layer "F.Fab")
		)
		(pad "1" thru_hole circle
			(at -1.5875 0)
			(size 0.508 0.508)
			(drill 0.254)
			(layers "*.Cu" "*.Mask")
			(remove_unused_layers no)
			(net "GND")
			(clearance 0.2032)
			(thermal_gap 0.2032)
		)
		(pad "2" thru_hole circle
			(at -0.5715 0)
			(size 0.508 0.508)
			(drill 0.254)
			(layers "*.Cu" "*.Mask")
			(remove_unused_layers no)
			(net "PHY_IOC_TO_SCC_C_45_DP")
			(clearance 0.2032)
			(thermal_gap 0.2032)
		)
		(pad "3" thru_hole circle
			(at 0.5715 0)
			(size 0.508 0.508)
			(drill 0.254)
			(layers "*.Cu" "*.Mask")
			(remove_unused_layers no)
			(net "PHY_IOC_TO_SCC_C_45_DN")
			(clearance 0.2032)
			(thermal_gap 0.2032)
		)
		(pad "4" thru_hole circle
			(at 1.5875 0)
			(size 0.508 0.508)
			(drill 0.254)
			(layers "*.Cu" "*.Mask")
			(remove_unused_layers no)
			(net "GND")
			(clearance 0.2032)
			(thermal_gap 0.2032)
		)
	)
	(footprint ""
		(layer "F.Cu")
		(at 6.1849 -93.358208 90)
		(property "Reference" "R415"
			(at 0 0 90)
			(layer "F.SilkS")
			(hide yes)
			(effects
				(font
					(size 1.27 1.27)
				)
			)
		)
		(property "Value" "0R2J-2-GP"
			(at 0.064008 -3.993896 90)
			(unlocked yes)
			(layer "F.Fab")
			(hide yes)
			(effects
				(font
					(size 1.016 1.016)
					(thickness 0.1524)
				)
			)
		)
		(property "Device Type" "R402H16"
			(at 0.064008 -5.517896 90)
			(unlocked yes)
			(layer "F.Fab")
			(hide yes)
			(effects
				(font
					(size 1.016 1.016)
					(thickness 0.1524)
				)
			)
		)
		(duplicate_pad_numbers_are_jumpers no)
		(fp_line
			(start 0.508 -0.9398)
			(end -0.508 -0.9398)
			(stroke
				(width 0.1524)
				(type default)
			)
			(layer "F.SilkS")
		)
		(fp_line
			(start -0.508 -0.9398)
			(end -0.508 0.9398)
			(stroke
				(width 0.1524)
				(type default)
			)
			(layer "F.SilkS")
		)
		(fp_rect
			(start -0.508 0.9398)
			(end 0.508 -0.9398)
			(stroke
				(width 0)
				(type default)
			)
			(fill no)
			(layer "F.CrtYd")
		)
		(fp_rect
			(start -0.508 0.9398)
			(end 0.508 -0.9398)
			(stroke
				(width 0)
				(type default)
			)
			(fill no)
			(layer "F.Fab")
		)
		(pad "1" smd custom
			(at 0 -0.4445 90)
			(size 0.1397 0.1397)
			(layers "F.Cu" "F.Mask" "F.Paste")
			(net "LS_EN_U36")
			(options
				(clearance outline)
				(anchor circle)
			)
			(primitives
				(gr_poly
					(pts
						(arc
							(start -0.1778 -0.2794)
							(mid -0.249642 -0.249642)
							(end -0.2794 -0.1778)
						)
						(arc
							(start -0.2794 0.1778)
							(mid -0.249642 0.249642)
							(end -0.1778 0.2794)
						)
						(arc
							(start 0.1778 0.2794)
							(mid 0.249642 0.249642)
							(end 0.2794 0.1778)
						)
						(arc
							(start 0.2794 -0.1778)
							(mid 0.249642 -0.249642)
							(end 0.1778 -0.2794)
						)
					)
					(width 0)
					(fill yes)
				)
			)
		)
		(pad "2" smd custom
			(at 0 0.4445 90)
			(size 0.1397 0.1397)
			(layers "F.Cu" "F.Mask" "F.Paste")
			(net "VREF2")
			(options
				(clearance outline)
				(anchor circle)
			)
			(primitives
				(gr_poly
					(pts
						(arc
							(start -0.1778 -0.2794)
							(mid -0.249642 -0.249642)
							(end -0.2794 -0.1778)
						)
						(arc
							(start -0.2794 0.1778)
							(mid -0.249642 0.249642)
							(end -0.1778 0.2794)
						)
						(arc
							(start 0.1778 0.2794)
							(mid 0.249642 0.249642)
							(end 0.2794 0.1778)
						)
						(arc
							(start 0.2794 -0.1778)
							(mid 0.249642 -0.249642)
							(end 0.1778 -0.2794)
						)
					)
					(width 0)
					(fill yes)
				)
			)
		)
	)
	(footprint ""
		(layer "F.Cu")
		(at 21.7932 -55.3466 90)
		(property "Reference" "R20"
			(at 0 0 90)
			(layer "F.SilkS")
			(hide yes)
			(effects
				(font
					(size 1.27 1.27)
				)
			)
		)
		(property "Value" "63K4R2B-GP"
			(at 0.064008 -3.993896 90)
			(unlocked yes)
			(layer "F.Fab")
			(hide yes)
			(effects
				(font
					(size 1.016 1.016)
					(thickness 0.1524)
				)
			)
		)
		(property "Device Type" "R402H16"
			(at 0.064008 -5.517896 90)
			(unlocked yes)
			(layer "F.Fab")
			(hide yes)
			(effects
				(font
					(size 1.016 1.016)
					(thickness 0.1524)
				)
			)
		)
		(duplicate_pad_numbers_are_jumpers no)
		(fp_line
			(start 0.508 -0.9398)
			(end -0.508 -0.9398)
			(stroke
				(width 0.1524)
				(type default)
			)
			(layer "F.SilkS")
		)
		(fp_line
			(start -0.508 -0.9398)
			(end -0.508 0.9398)
			(stroke
				(width 0.1524)
				(type default)
			)
			(layer "F.SilkS")
		)
		(fp_rect
			(start -0.508 0.9398)
			(end 0.508 -0.9398)
			(stroke
				(width 0)
				(type default)
			)
			(fill no)
			(layer "F.CrtYd")
		)
		(fp_rect
			(start -0.508 0.9398)
			(end 0.508 -0.9398)
			(stroke
				(width 0)
				(type default)
			)
			(fill no)
			(layer "F.Fab")
		)
		(pad "1" smd custom
			(at 0 -0.4445 90)
			(size 0.1397 0.1397)
			(layers "F.Cu" "F.Mask" "F.Paste")
			(net "MB0_ISET_R")
			(options
				(clearance outline)
				(anchor circle)
			)
			(primitives
				(gr_poly
					(pts
						(arc
							(start -0.1778 -0.2794)
							(mid -0.249642 -0.249642)
							(end -0.2794 -0.1778)
						)
						(arc
							(start -0.2794 0.1778)
							(mid -0.249642 0.249642)
							(end -0.1778 0.2794)
						)
						(arc
							(start 0.1778 0.2794)
							(mid 0.249642 0.249642)
							(end 0.2794 0.1778)
						)
						(arc
							(start 0.2794 -0.1778)
							(mid 0.249642 -0.249642)
							(end 0.1778 -0.2794)
						)
					)
					(width 0)
					(fill yes)
				)
			)
		)
		(pad "2" smd custom
			(at 0 0.4445 90)
			(size 0.1397 0.1397)
			(layers "F.Cu" "F.Mask" "F.Paste")
			(net "AGND_CURRENT_MON")
			(options
				(clearance outline)
				(anchor circle)
			)
			(primitives
				(gr_poly
					(pts
						(arc
							(start -0.1778 -0.2794)
							(mid -0.249642 -0.249642)
							(end -0.2794 -0.1778)
						)
						(arc
							(start -0.2794 0.1778)
							(mid -0.249642 0.249642)
							(end -0.1778 0.2794)
						)
						(arc
							(start 0.1778 0.2794)
							(mid 0.249642 0.249642)
							(end 0.2794 0.1778)
						)
						(arc
							(start 0.2794 -0.1778)
							(mid 0.249642 -0.249642)
							(end 0.1778 -0.2794)
						)
					)
					(width 0)
					(fill yes)
				)
			)
		)
	)
	(footprint ""
		(layer "F.Cu")
		(at 17.6022 -94.9452 180)
		(property "Reference" "C542"
			(at 0 0 180)
			(layer "F.SilkS")
			(hide yes)
			(effects
				(font
					(size 1.27 1.27)
				)
			)
		)
		(property "Value" "SCD1U16V2KX-3GP"
			(at 1.1811 -2.7051 180)
			(unlocked yes)
			(layer "F.Fab")
			(hide yes)
			(effects
				(font
					(size 1.016 1.016)
					(thickness 0.1524)
				)
			)
		)
		(property "Device Type" "C402H22"
			(at 1.1811 -4.2291 180)
			(unlocked yes)
			(layer "F.Fab")
			(hide yes)
			(effects
				(font
					(size 1.016 1.016)
					(thickness 0.1524)
				)
			)
		)
		(duplicate_pad_numbers_are_jumpers no)
		(fp_rect
			(start -0.4318 0.9525)
			(end 0.4318 -0.9525)
			(stroke
				(width 0)
				(type default)
			)
			(fill no)
			(layer "F.CrtYd")
		)
		(fp_rect
			(start -0.4318 0.9525)
			(end 0.4318 -0.9525)
			(stroke
				(width 0)
				(type default)
			)
			(fill no)
			(layer "F.Fab")
		)
		(pad "1" smd custom
			(at 0 -0.4445 180)
			(size 0.1524 0.1524)
			(layers "F.Cu" "F.Mask" "F.Paste")
			(net "VREF0")
			(options
				(clearance outline)
				(anchor circle)
			)
			(primitives
				(gr_poly
					(pts
						(arc
							(start 0.3048 -0.2032)
							(mid 0.275042 -0.275042)
							(end 0.2032 -0.3048)
						)
						(arc
							(start -0.2032 -0.3048)
							(mid -0.275042 -0.275042)
							(end -0.3048 -0.2032)
						)
						(arc
							(start -0.3048 0.2032)
							(mid -0.275042 0.275042)
							(end -0.2032 0.3048)
						)
						(arc
							(start 0.2032 0.3048)
							(mid 0.275042 0.275042)
							(end 0.3048 0.2032)
						)
					)
					(width 0)
					(fill yes)
				)
			)
		)
		(pad "2" smd custom
			(at 0 0.4445 180)
			(size 0.1524 0.1524)
			(layers "F.Cu" "F.Mask" "F.Paste")
			(net "GND")
			(options
				(clearance outline)
				(anchor circle)
			)
			(primitives
				(gr_poly
					(pts
						(arc
							(start 0.3048 -0.2032)
							(mid 0.275042 -0.275042)
							(end 0.2032 -0.3048)
						)
						(arc
							(start -0.2032 -0.3048)
							(mid -0.275042 -0.275042)
							(end -0.3048 -0.2032)
						)
						(arc
							(start -0.3048 0.2032)
							(mid -0.275042 0.275042)
							(end -0.2032 0.3048)
						)
						(arc
							(start 0.2032 0.3048)
							(mid 0.275042 0.275042)
							(end 0.3048 0.2032)
						)
					)
					(width 0)
					(fill yes)
				)
			)
		)
	)
	(footprint ""
		(layer "F.Cu")
		(at 191.85382 -54.4068 90)
		(property "Reference" "R227"
			(at 0 0 90)
			(layer "F.SilkS")
			(hide yes)
			(effects
				(font
					(size 1.27 1.27)
				)
			)
		)
		(property "Value" "10KR2F-2-GP"
			(at 0.064008 -3.993896 90)
			(unlocked yes)
			(layer "F.Fab")
			(hide yes)
			(effects
				(font
					(size 1.016 1.016)
					(thickness 0.1524)
				)
			)
		)
		(property "Device Type" "R402H16"
			(at 0.064008 -5.517896 90)
			(unlocked yes)
			(layer "F.Fab")
			(hide yes)
			(effects
				(font
					(size 1.016 1.016)
					(thickness 0.1524)
				)
			)
		)
		(duplicate_pad_numbers_are_jumpers no)
		(fp_line
			(start 0.508 -0.9398)
			(end -0.508 -0.9398)
			(stroke
				(width 0.1524)
				(type default)
			)
			(layer "F.SilkS")
		)
		(fp_line
			(start -0.508 -0.9398)
			(end -0.508 0.9398)
			(stroke
				(width 0.1524)
				(type default)
			)
			(layer "F.SilkS")
		)
		(fp_rect
			(start -0.508 0.9398)
			(end 0.508 -0.9398)
			(stroke
				(width 0)
				(type default)
			)
			(fill no)
			(layer "F.CrtYd")
		)
		(fp_rect
			(start -0.508 0.9398)
			(end 0.508 -0.9398)
			(stroke
				(width 0)
				(type default)
			)
			(fill no)
			(layer "F.Fab")
		)
		(pad "1" smd custom
			(at 0 -0.4445 90)
			(size 0.1397 0.1397)
			(layers "F.Cu" "F.Mask" "F.Paste")
			(net "XM_ADDR_8")
			(options
				(clearance outline)
				(anchor circle)
			)
			(primitives
				(gr_poly
					(pts
						(arc
							(start -0.1778 -0.2794)
							(mid -0.249642 -0.249642)
							(end -0.2794 -0.1778)
						)
						(arc
							(start -0.2794 0.1778)
							(mid -0.249642 0.249642)
							(end -0.1778 0.2794)
						)
						(arc
							(start 0.1778 0.2794)
							(mid 0.249642 0.249642)
							(end 0.2794 0.1778)
						)
						(arc
							(start 0.2794 -0.1778)
							(mid 0.249642 -0.249642)
							(end 0.1778 -0.2794)
						)
					)
					(width 0)
					(fill yes)
				)
			)
		)
		(pad "2" smd custom
			(at 0 0.4445 90)
			(size 0.1397 0.1397)
			(layers "F.Cu" "F.Mask" "F.Paste")
			(net "GND")
			(options
				(clearance outline)
				(anchor circle)
			)
			(primitives
				(gr_poly
					(pts
						(arc
							(start -0.1778 -0.2794)
							(mid -0.249642 -0.249642)
							(end -0.2794 -0.1778)
						)
						(arc
							(start -0.2794 0.1778)
							(mid -0.249642 0.249642)
							(end -0.1778 0.2794)
						)
						(arc
							(start 0.1778 0.2794)
							(mid 0.249642 0.249642)
							(end 0.2794 0.1778)
						)
						(arc
							(start 0.2794 -0.1778)
							(mid 0.249642 -0.249642)
							(end 0.1778 -0.2794)
						)
					)
					(width 0)
					(fill yes)
				)
			)
		)
	)
	(footprint ""
		(layer "F.Cu")
		(at 155.9687 -89.7636 -90)
		(property "Reference" "R333"
			(at 0 0 270)
			(layer "F.SilkS")
			(hide yes)
			(effects
				(font
					(size 1.27 1.27)
				)
			)
		)
		(property "Value" "4K7R2F-GP"
			(at 0.064008 -3.993896 270)
			(unlocked yes)
			(layer "F.Fab")
			(hide yes)
			(effects
				(font
					(size 1.016 1.016)
					(thickness 0.1524)
				)
			)
		)
		(property "Device Type" "R402H16"
			(at 0.064008 -5.517896 270)
			(unlocked yes)
			(layer "F.Fab")
			(hide yes)
			(effects
				(font
					(size 1.016 1.016)
					(thickness 0.1524)
				)
			)
		)
		(duplicate_pad_numbers_are_jumpers no)
		(fp_line
			(start -0.508 -0.9398)
			(end -0.508 0.9398)
			(stroke
				(width 0.1524)
				(type default)
			)
			(layer "F.SilkS")
		)
		(fp_line
			(start 0.508 -0.9398)
			(end -0.508 -0.9398)
			(stroke
				(width 0.1524)
				(type default)
			)
			(layer "F.SilkS")
		)
		(fp_rect
			(start -0.508 0.9398)
			(end 0.508 -0.9398)
			(stroke
				(width 0)
				(type default)
			)
			(fill no)
			(layer "F.CrtYd")
		)
		(fp_rect
			(start -0.508 0.9398)
			(end 0.508 -0.9398)
			(stroke
				(width 0)
				(type default)
			)
			(fill no)
			(layer "F.Fab")
		)
		(pad "1" smd custom
			(at 0 -0.4445 270)
			(size 0.1397 0.1397)
			(layers "F.Cu" "F.Mask" "F.Paste")
			(net "VOL_SEN1_ADDR")
			(options
				(clearance outline)
				(anchor circle)
			)
			(primitives
				(gr_poly
					(pts
						(arc
							(start -0.1778 -0.2794)
							(mid -0.249642 -0.249642)
							(end -0.2794 -0.1778)
						)
						(arc
							(start -0.2794 0.1778)
							(mid -0.249642 0.249642)
							(end -0.1778 0.2794)
						)
						(arc
							(start 0.1778 0.2794)
							(mid 0.249642 0.249642)
							(end 0.2794 0.1778)
						)
						(arc
							(start 0.2794 -0.1778)
							(mid 0.249642 -0.249642)
							(end 0.1778 -0.2794)
						)
					)
					(width 0)
					(fill yes)
				)
			)
		)
		(pad "2" smd custom
			(at 0 0.4445 270)
			(size 0.1397 0.1397)
			(layers "F.Cu" "F.Mask" "F.Paste")
			(net "GND")
			(options
				(clearance outline)
				(anchor circle)
			)
			(primitives
				(gr_poly
					(pts
						(arc
							(start -0.1778 -0.2794)
							(mid -0.249642 -0.249642)
							(end -0.2794 -0.1778)
						)
						(arc
							(start -0.2794 0.1778)
							(mid -0.249642 0.249642)
							(end -0.1778 0.2794)
						)
						(arc
							(start 0.1778 0.2794)
							(mid 0.249642 0.249642)
							(end 0.2794 0.1778)
						)
						(arc
							(start 0.2794 -0.1778)
							(mid 0.249642 -0.249642)
							(end 0.1778 -0.2794)
						)
					)
					(width 0)
					(fill yes)
				)
			)
		)
	)
	(footprint ""
		(layer "F.Cu")
		(at 13.9446 -53.2638 -90)
		(property "Reference" "U5"
			(at 0 0 270)
			(layer "F.SilkS")
			(hide yes)
			(effects
				(font
					(size 1.27 1.27)
				)
			)
		)
		(property "Value" "ADM1278-2ACPZ-RL-1-GP"
			(at -4.7625 -7.4422 270)
			(unlocked yes)
			(layer "F.Fab")
			(hide yes)
			(effects
				(font
					(size 1.016 1.016)
					(thickness 0.1524)
				)
			)
		)
		(property "Device Type" "QFN32-G3D45-UH32"
			(at -4.7625 -8.9662 270)
			(unlocked yes)
			(layer "F.Fab")
			(hide yes)
			(effects
				(font
					(size 1.016 1.016)
					(thickness 0.1524)
				)
			)
		)
		(duplicate_pad_numbers_are_jumpers no)
		(fp_line
			(start -0.250698 4.0513)
			(end -0.250698 3.2893)
			(stroke
				(width 0.1524)
				(type default)
			)
			(layer "F.SilkS")
		)
		(fp_line
			(start -3.5179 3.5179)
			(end -2.2479 3.5179)
			(stroke
				(width 0.1524)
				(type default)
			)
			(layer "F.SilkS")
		)
		(fp_line
			(start 3.5179 3.5179)
			(end 2.2479 3.5179)
			(stroke
				(width 0.1524)
				(type default)
			)
			(layer "F.SilkS")
		)
		(fp_line
			(start -3.5179 2.2479)
			(end -3.5179 3.5179)
			(stroke
				(width 0.1524)
				(type default)
			)
			(layer "F.SilkS")
		)
		(fp_line
			(start 3.5179 2.2479)
			(end 3.5179 3.5179)
			(stroke
				(width 0.1524)
				(type default)
			)
			(layer "F.SilkS")
		)
		(fp_line
			(start 3.7973 1.749552)
			(end 3.2893 1.749552)
			(stroke
				(width 0.1524)
				(type default)
			)
			(layer "F.SilkS")
		)
		(fp_line
			(start -3.7973 1.24968)
			(end -3.2893 1.24968)
			(stroke
				(width 0.1524)
				(type default)
			)
			(layer "F.SilkS")
		)
		(fp_line
			(start 4.0513 -0.749808)
			(end 3.2893 -0.749808)
			(stroke
				(width 0.1524)
				(type default)
			)
			(layer "F.SilkS")
		)
		(fp_line
			(start -4.0513 -1.24968)
			(end -3.2893 -1.24968)
			(stroke
				(width 0.1524)
				(type default)
			)
			(layer "F.SilkS")
		)
		(fp_line
			(start -3.5179 -2.2479)
			(end -3.5179 -3.5179)
			(stroke
				(width 0.1524)
				(type default)
			)
			(layer "F.SilkS")
		)
		(fp_line
			(start -3.5179 -3.5179)
			(end -2.2479 -3.5179)
			(stroke
				(width 0.1524)
				(type default)
			)
			(layer "F.SilkS")
		)
		(fp_line
			(start -0.250698 -3.7973)
			(end -0.250698 -3.2893)
			(stroke
				(width 0.1524)
				(type default)
			)
			(layer "F.SilkS")
		)
		(fp_poly
			(pts
				(xy 2.2479 -3.5179) (xy 3.5179 -2.2479) (xy 3.5179 -3.5179)
			)
			(stroke
				(width 0)
				(type default)
			)
			(fill yes)
			(layer "F.SilkS")
		)
		(fp_rect
			(start -2.5019 2.5019)
			(end 2.5019 -2.5019)
			(stroke
				(width 0)
				(type default)
			)
			(fill no)
			(layer "F.CrtYd")
		)
		(fp_poly
			(pts
				(xy -3.5179 3.5179) (xy -3.5179 -3.5179) (xy 3.5179 -3.5179) (xy 3.5179 3.5179) (xy -2.49682 3.5179)
				(xy -2.49682 2.5019) (xy 2.5019 2.5019) (xy 2.5019 -2.5019) (xy -2.5019 -2.5019) (xy -2.5019 3.5179)
			)
			(stroke
				(width 0)
				(type default)
			)
			(fill no)
			(layer "F.CrtYd")
		)
		(fp_rect
			(start -3.5179 3.5179)
			(end 3.5179 -3.5179)
			(stroke
				(width 0)
				(type default)
			)
			(fill no)
			(layer "F.Fab")
		)
		(pad "1" smd rect
			(at 1.75006 -2.5527 270)
			(size 0.3048 0.9144)
			(layers "F.Cu" "F.Mask" "F.Paste")
			(net "MB0_PSET_R")
		)
		(pad "2" smd rect
			(at 1.249934 -2.4765 270)
			(size 0.3048 1.0668)
			(layers "F.Cu" "F.Mask" "F.Paste")
			(net "MB0_VCAP_R")
		)
		(pad "3" smd rect
			(at 0.750062 -2.4765 270)
			(size 0.3048 1.0668)
			(layers "F.Cu" "F.Mask" "F.Paste")
			(net "MB0_ISET_R")
		)
		(pad "4" smd rect
			(at 0.249936 -2.4765 270)
			(size 0.3048 1.0668)
			(layers "F.Cu" "F.Mask" "F.Paste")
			(net "MB0_ISTART_R")
		)
		(pad "5" smd rect
			(at -0.249936 -2.4765 270)
			(size 0.3048 1.0668)
			(layers "F.Cu" "F.Mask" "F.Paste")
			(net "MB0_TIME_R")
		)
		(pad "6" smd rect
			(at -0.750062 -2.4765 270)
			(size 0.3048 1.0668)
			(layers "F.Cu" "F.Mask" "F.Paste")
			(net "Net_696")
		)
		(pad "7" smd rect
			(at -1.249934 -2.4765 270)
			(size 0.3048 1.0668)
			(layers "F.Cu" "F.Mask" "F.Paste")
			(net "MB0_CM_ADR1_R")
		)
		(pad "8" smd rect
			(at -1.75006 -2.5527 270)
			(size 0.3048 0.9144)
			(layers "F.Cu" "F.Mask" "F.Paste")
			(net "MB0_CM_ADR2_R")
		)
		(pad "9" smd rect
			(at -2.5527 -1.75006 270)
			(size 0.9144 0.3048)
			(layers "F.Cu" "F.Mask" "F.Paste")
			(net "MB0_SPISS_PD")
		)
		(pad "10" smd rect
			(at -2.4765 -1.249934 270)
			(size 1.0668 0.3048)
			(layers "F.Cu" "F.Mask" "F.Paste")
			(net "Net_700")
		)
		(pad "11" smd rect
			(at -2.4765 -0.750062 270)
			(size 1.0668 0.3048)
			(layers "F.Cu" "F.Mask" "F.Paste")
			(net "Net_699")
		)
		(pad "12" smd rect
			(at -2.4765 -0.249936 270)
			(size 1.0668 0.3048)
			(layers "F.Cu" "F.Mask" "F.Paste")
			(net "MB0_HS_ENABLE")
		)
		(pad "13" smd rect
			(at -2.4765 0.249936 270)
			(size 1.0668 0.3048)
			(layers "F.Cu" "F.Mask" "F.Paste")
			(net "Net_698")
		)
		(pad "14" smd rect
			(at -2.4765 0.750062 270)
			(size 1.0668 0.3048)
			(layers "F.Cu" "F.Mask" "F.Paste")
			(net "Net_697")
		)
		(pad "15" smd rect
			(at -2.4765 1.249934 270)
			(size 1.0668 0.3048)
			(layers "F.Cu" "F.Mask" "F.Paste")
			(net "HSW_SDA_2")
		)
		(pad "16" smd rect
			(at -2.5527 1.75006 270)
			(size 0.9144 0.3048)
			(layers "F.Cu" "F.Mask" "F.Paste")
			(net "HSW_SCL_2")
		)
		(pad "17" smd rect
			(at -1.75006 2.5527 270)
			(size 0.3048 0.9144)
			(layers "F.Cu" "F.Mask" "F.Paste")
			(net "MB0_RETRY_R")
		)
		(pad "18" smd rect
			(at -1.249934 2.4765 270)
			(size 0.3048 1.0668)
			(layers "F.Cu" "F.Mask" "F.Paste")
			(net "P12V_SCC_PGOOD")
		)
		(pad "19" smd rect
			(at -0.750062 2.4765 270)
			(size 0.3048 1.0668)
			(layers "F.Cu" "F.Mask" "F.Paste")
			(net "Net_701")
		)
		(pad "20" smd rect
			(at -0.249936 2.4765 270)
			(size 0.3048 1.0668)
			(layers "F.Cu" "F.Mask" "F.Paste")
			(net "MB0_CM_VOUT_R")
		)
		(pad "21" smd rect
			(at 0.249936 2.4765 270)
			(size 0.3048 1.0668)
			(layers "F.Cu" "F.Mask" "F.Paste")
			(net "MB0_P12V_PWGIN_R")
		)
		(pad "22" smd rect
			(at 0.750062 2.4765 270)
			(size 0.3048 1.0668)
			(layers "F.Cu" "F.Mask" "F.Paste")
			(net "AGND_CURRENT_MON")
		)
		(pad "23" smd rect
			(at 1.249934 2.4765 270)
			(size 0.3048 1.0668)
			(layers "F.Cu" "F.Mask" "F.Paste")
			(net "GND")
		)
		(pad "24" smd rect
			(at 1.75006 2.5527 270)
			(size 0.3048 0.9144)
			(layers "F.Cu" "F.Mask" "F.Paste")
			(net "MB0_CM_GATE")
		)
		(pad "25" smd rect
			(at 2.5527 1.75006 270)
			(size 0.9144 0.3048)
			(layers "F.Cu" "F.Mask" "F.Paste")
			(net "MB0_TEMP")
		)
		(pad "26" smd rect
			(at 2.4765 1.249934 270)
			(size 1.0668 0.3048)
			(layers "F.Cu" "F.Mask" "F.Paste")
			(net "MB0_CM_SENSE_N")
		)
		(pad "27" smd rect
			(at 2.4765 0.750062 270)
			(size 1.0668 0.3048)
			(layers "F.Cu" "F.Mask" "F.Paste")
			(net "MB0_HS_SENSE_N")
		)
		(pad "28" smd rect
			(at 2.4765 0.249936 270)
			(size 1.0668 0.3048)
			(layers "F.Cu" "F.Mask" "F.Paste")
			(net "MB0_HS_SENSE_P")
		)
		(pad "29" smd rect
			(at 2.4765 -0.249936 270)
			(size 1.0668 0.3048)
			(layers "F.Cu" "F.Mask" "F.Paste")
			(net "MB0_CM_SENSE_P")
		)
		(pad "30" smd rect
			(at 2.4765 -0.750062 270)
			(size 1.0668 0.3048)
			(layers "F.Cu" "F.Mask" "F.Paste")
			(net "MB0_VCC")
		)
		(pad "31" smd rect
			(at 2.4765 -1.249934 270)
			(size 1.0668 0.3048)
			(layers "F.Cu" "F.Mask" "F.Paste")
			(net "MB0_CM_UV_R")
		)
		(pad "32" smd rect
			(at 2.5527 -1.75006 270)
			(size 0.9144 0.3048)
			(layers "F.Cu" "F.Mask" "F.Paste")
			(net "MB0_CM_OV_R")
		)
		(pad "33" smd rect
			(at 0 0 270)
			(size 3.4544 3.4544)
			(layers "F.Cu" "F.Mask" "F.Paste")
			(net "AGND_CURRENT_MON")
		)
	)
	(footprint ""
		(layer "F.Cu")
		(at 50.0126 -46.482 90)
		(property "Reference" "Q7"
			(at 0 0 90)
			(layer "F.SilkS")
			(hide yes)
			(effects
				(font
					(size 1.27 1.27)
				)
			)
		)
		(property "Value" "CSD87350Q5D-1-GP"
			(at -4.064 -3.3782 90)
			(unlocked yes)
			(layer "F.Fab")
			(hide yes)
			(effects
				(font
					(size 1.016 1.016)
					(thickness 0.1524)
				)
			)
		)
		(property "Device Type" "PPAK-8P-G510321H62"
			(at -4.064 -4.9022 90)
			(unlocked yes)
			(layer "F.Fab")
			(hide yes)
			(effects
				(font
					(size 1.016 1.016)
					(thickness 0.1524)
				)
			)
		)
		(duplicate_pad_numbers_are_jumpers no)
		(fp_line
			(start -2.0447 -4.0132)
			(end -3.0607 -4.0132)
			(stroke
				(width 0.1524)
				(type default)
			)
			(layer "F.SilkS")
		)
		(fp_line
			(start -3.0607 -4.0132)
			(end -3.0607 -2.9972)
			(stroke
				(width 0.1524)
				(type default)
			)
			(layer "F.SilkS")
		)
		(fp_line
			(start 3.0607 2.9972)
			(end 3.0607 4.0132)
			(stroke
				(width 0.1524)
				(type default)
			)
			(layer "F.SilkS")
		)
		(fp_line
			(start -3.0607 2.9972)
			(end -3.0607 4.0132)
			(stroke
				(width 0.1524)
				(type default)
			)
			(layer "F.SilkS")
		)
		(fp_line
			(start -1.905 3.761994)
			(end -1.905 4.269994)
			(stroke
				(width 0.1524)
				(type default)
			)
			(layer "F.SilkS")
		)
		(fp_line
			(start 3.0607 4.0132)
			(end 2.0447 4.0132)
			(stroke
				(width 0.1524)
				(type default)
			)
			(layer "F.SilkS")
		)
		(fp_line
			(start -3.0607 4.0132)
			(end -2.0447 4.0132)
			(stroke
				(width 0.1524)
				(type default)
			)
			(layer "F.SilkS")
		)
		(fp_poly
			(pts
				(xy 2.0447 -4.0132) (xy 3.0607 -4.0132) (xy 3.0607 -2.9972)
			)
			(stroke
				(width 0)
				(type default)
			)
			(fill yes)
			(layer "F.SilkS")
		)
		(fp_rect
			(start -2.5019 2.9972)
			(end 2.5019 -2.9972)
			(stroke
				(width 0)
				(type default)
			)
			(fill no)
			(layer "F.CrtYd")
		)
		(fp_poly
			(pts
				(xy -3.0607 4.0132) (xy -3.0607 -4.0132) (xy 3.0607 -4.0132) (xy 3.0607 4.0132) (xy 0.00254 4.0132)
				(xy 0.00254 2.9972) (xy 2.5019 2.9972) (xy 2.5019 -2.9972) (xy -2.5019 -2.9972) (xy -2.5019 2.9972)
				(xy -0.00254 2.9972) (xy -0.00254 4.0132)
			)
			(stroke
				(width 0)
				(type default)
			)
			(fill no)
			(layer "F.CrtYd")
		)
		(fp_rect
			(start -3.0607 4.0132)
			(end 3.0607 -4.0132)
			(stroke
				(width 0)
				(type default)
			)
			(fill no)
			(layer "F.Fab")
		)
		(pad "1" smd rect
			(at 1.27 -2.822194 90)
			(size 1.905 1.3716)
			(layers "F.Cu" "F.Mask" "F.Paste")
			(net "P12V_STBY_VIN_Q7")
		)
		(pad "2" smd rect
			(at 0.635 -2.822194 90)
			(size 0.0254 0.0254)
			(layers "F.Cu" "F.Mask" "F.Paste")
			(net "P12V_STBY_VIN_Q7")
		)
		(pad "3" smd rect
			(at -0.635 -2.822194 90)
			(size 0.635 1.3716)
			(layers "F.Cu" "F.Mask" "F.Paste")
			(net "P0V9_TG")
		)
		(pad "4" smd rect
			(at -1.905 -2.822194 90)
			(size 0.635 1.3716)
			(layers "F.Cu" "F.Mask" "F.Paste")
			(net "P0V9_SW")
		)
		(pad "5" smd rect
			(at -1.905 2.822194 90)
			(size 0.635 1.3716)
			(layers "F.Cu" "F.Mask" "F.Paste")
			(net "P0V9_BG")
		)
		(pad "6" smd rect
			(at -0.635 2.822194 90)
			(size 0.635 1.3716)
			(layers "F.Cu" "F.Mask" "F.Paste")
			(net "P0V9_VSW")
		)
		(pad "7" smd rect
			(at 0.635 2.822194 90)
			(size 0.635 1.3716)
			(layers "F.Cu" "F.Mask" "F.Paste")
			(net "P0V9_VSW")
		)
		(pad "8" smd rect
			(at 1.905 2.822194 90)
			(size 0.635 1.3716)
			(layers "F.Cu" "F.Mask" "F.Paste")
			(net "P0V9_VSW")
		)
		(pad "9" smd rect
			(at 0 0 90)
			(size 5.1054 3.2004)
			(layers "F.Cu" "F.Mask" "F.Paste")
			(net "GND")
		)
	)
	(footprint ""
		(layer "F.Cu")
		(at 19.177 -79.756 90)
		(property "Reference" "R341"
			(at 0 0 90)
			(layer "F.SilkS")
			(hide yes)
			(effects
				(font
					(size 1.27 1.27)
				)
			)
		)
		(property "Value" "0R2J-2-GP"
			(at 0.064008 -3.993896 90)
			(unlocked yes)
			(layer "F.Fab")
			(hide yes)
			(effects
				(font
					(size 1.016 1.016)
					(thickness 0.1524)
				)
			)
		)
		(property "Device Type" "R402H16"
			(at 0.064008 -5.517896 90)
			(unlocked yes)
			(layer "F.Fab")
			(hide yes)
			(effects
				(font
					(size 1.016 1.016)
					(thickness 0.1524)
				)
			)
		)
		(duplicate_pad_numbers_are_jumpers no)
		(fp_line
			(start 0.508 -0.9398)
			(end -0.508 -0.9398)
			(stroke
				(width 0.1524)
				(type default)
			)
			(layer "F.SilkS")
		)
		(fp_line
			(start -0.508 -0.9398)
			(end -0.508 0.9398)
			(stroke
				(width 0.1524)
				(type default)
			)
			(layer "F.SilkS")
		)
		(fp_rect
			(start -0.508 0.9398)
			(end 0.508 -0.9398)
			(stroke
				(width 0)
				(type default)
			)
			(fill no)
			(layer "F.CrtYd")
		)
		(fp_rect
			(start -0.508 0.9398)
			(end 0.508 -0.9398)
			(stroke
				(width 0)
				(type default)
			)
			(fill no)
			(layer "F.Fab")
		)
		(pad "1" smd custom
			(at 0 -0.4445 90)
			(size 0.1397 0.1397)
			(layers "F.Cu" "F.Mask" "F.Paste")
			(net "EXP_EEPROM_WP")
			(options
				(clearance outline)
				(anchor circle)
			)
			(primitives
				(gr_poly
					(pts
						(arc
							(start -0.1778 -0.2794)
							(mid -0.249642 -0.249642)
							(end -0.2794 -0.1778)
						)
						(arc
							(start -0.2794 0.1778)
							(mid -0.249642 0.249642)
							(end -0.1778 0.2794)
						)
						(arc
							(start 0.1778 0.2794)
							(mid 0.249642 0.249642)
							(end 0.2794 0.1778)
						)
						(arc
							(start 0.2794 -0.1778)
							(mid 0.249642 -0.249642)
							(end 0.1778 -0.2794)
						)
					)
					(width 0)
					(fill yes)
				)
			)
		)
		(pad "2" smd custom
			(at 0 0.4445 90)
			(size 0.1397 0.1397)
			(layers "F.Cu" "F.Mask" "F.Paste")
			(net "GND")
			(options
				(clearance outline)
				(anchor circle)
			)
			(primitives
				(gr_poly
					(pts
						(arc
							(start -0.1778 -0.2794)
							(mid -0.249642 -0.249642)
							(end -0.2794 -0.1778)
						)
						(arc
							(start -0.2794 0.1778)
							(mid -0.249642 0.249642)
							(end -0.1778 0.2794)
						)
						(arc
							(start 0.1778 0.2794)
							(mid 0.249642 0.249642)
							(end 0.2794 0.1778)
						)
						(arc
							(start 0.2794 -0.1778)
							(mid 0.249642 -0.249642)
							(end 0.1778 -0.2794)
						)
					)
					(width 0)
					(fill yes)
				)
			)
		)
	)
	(footprint ""
		(layer "F.Cu")
		(at 135.355076 -88.72601)
		(property "Reference" "R69"
			(at 0 0 0)
			(layer "F.SilkS")
			(hide yes)
			(effects
				(font
					(size 1.27 1.27)
				)
			)
		)
		(property "Value" "1KR2F-3-GP"
			(at 0.064008 -3.993896 0)
			(unlocked yes)
			(layer "F.Fab")
			(hide yes)
			(effects
				(font
					(size 1.016 1.016)
					(thickness 0.1524)
				)
			)
		)
		(property "Device Type" "R402H16"
			(at 0.064008 -5.517896 0)
			(unlocked yes)
			(layer "F.Fab")
			(hide yes)
			(effects
				(font
					(size 1.016 1.016)
					(thickness 0.1524)
				)
			)
		)
		(duplicate_pad_numbers_are_jumpers no)
		(fp_line
			(start -0.508 -0.9398)
			(end -0.508 0.9398)
			(stroke
				(width 0.1524)
				(type default)
			)
			(layer "F.SilkS")
		)
		(fp_line
			(start 0.508 -0.9398)
			(end -0.508 -0.9398)
			(stroke
				(width 0.1524)
				(type default)
			)
			(layer "F.SilkS")
		)
		(fp_rect
			(start -0.508 0.9398)
			(end 0.508 -0.9398)
			(stroke
				(width 0)
				(type default)
			)
			(fill no)
			(layer "F.CrtYd")
		)
		(fp_rect
			(start -0.508 0.9398)
			(end 0.508 -0.9398)
			(stroke
				(width 0)
				(type default)
			)
			(fill no)
			(layer "F.Fab")
		)
		(pad "1" smd custom
			(at 0 -0.4445)
			(size 0.1397 0.1397)
			(layers "F.Cu" "F.Mask" "F.Paste")
			(net "P1V8_E")
			(options
				(clearance outline)
				(anchor circle)
			)
			(primitives
				(gr_poly
					(pts
						(arc
							(start -0.1778 -0.2794)
							(mid -0.249642 -0.249642)
							(end -0.2794 -0.1778)
						)
						(arc
							(start -0.2794 0.1778)
							(mid -0.249642 0.249642)
							(end -0.1778 0.2794)
						)
						(arc
							(start 0.1778 0.2794)
							(mid 0.249642 0.249642)
							(end 0.2794 0.1778)
						)
						(arc
							(start 0.2794 -0.1778)
							(mid 0.249642 -0.249642)
							(end 0.1778 -0.2794)
						)
					)
					(width 0)
					(fill yes)
				)
			)
		)
		(pad "2" smd custom
			(at 0 0.4445)
			(size 0.1397 0.1397)
			(layers "F.Cu" "F.Mask" "F.Paste")
			(net "EXP_I2C_SDA10")
			(options
				(clearance outline)
				(anchor circle)
			)
			(primitives
				(gr_poly
					(pts
						(arc
							(start -0.1778 -0.2794)
							(mid -0.249642 -0.249642)
							(end -0.2794 -0.1778)
						)
						(arc
							(start -0.2794 0.1778)
							(mid -0.249642 0.249642)
							(end -0.1778 0.2794)
						)
						(arc
							(start 0.1778 0.2794)
							(mid 0.249642 0.249642)
							(end 0.2794 0.1778)
						)
						(arc
							(start 0.2794 -0.1778)
							(mid 0.249642 -0.249642)
							(end 0.1778 -0.2794)
						)
					)
					(width 0)
					(fill yes)
				)
			)
		)
	)
	(footprint ""
		(layer "F.Cu")
		(at 153.81478 -120.45442)
		(property "Reference" "G5"
			(at 0 0 0)
			(layer "F.SilkS")
			(hide yes)
			(effects
				(font
					(size 1.27 1.27)
				)
			)
		)
		(property "Value" "COPPER-CLOSE-GP-U"
			(at 0.0762 -2.8702 0)
			(unlocked yes)
			(layer "F.Fab")
			(hide yes)
			(effects
				(font
					(size 1.016 1.016)
					(thickness 0.1524)
				)
			)
		)
		(property "Device Type" "CON2C-U"
			(at 0.0762 -4.3942 0)
			(unlocked yes)
			(layer "F.Fab")
			(hide yes)
			(effects
				(font
					(size 1.016 1.016)
					(thickness 0.1524)
				)
			)
		)
		(duplicate_pad_numbers_are_jumpers no)
		(fp_rect
			(start -0.9398 0.9652)
			(end 0.9398 -0.9652)
			(stroke
				(width 0)
				(type default)
			)
			(fill no)
			(layer "F.CrtYd")
		)
		(fp_rect
			(start -0.9398 0.9652)
			(end 0.9398 -0.9652)
			(stroke
				(width 0)
				(type default)
			)
			(fill no)
			(layer "F.Fab")
		)
		(pad "1" smd custom
			(at 0 -0.5334)
			(size 0.17145 0.17145)
			(layers "F.Cu" "F.Mask" "F.Paste")
			(net "AGND_P1V5_E")
			(options
				(clearance outline)
				(anchor circle)
			)
			(primitives
				(gr_poly
					(pts
						(xy -0.127 0.3429) (xy -0.127 0.1651) (xy -0.635 -0.3429) (xy 0.635 -0.3429) (xy 0.127 0.1651)
						(xy 0.127 0.3429)
					)
					(width 0)
					(fill yes)
				)
			)
		)
		(pad "2" smd custom
			(at 0 0.5334)
			(size 0.17145 0.17145)
			(layers "F.Cu" "F.Mask" "F.Paste")
			(net "GND")
			(options
				(clearance outline)
				(anchor circle)
			)
			(primitives
				(gr_poly
					(pts
						(xy -0.635 0.3429) (xy -0.127 -0.1651) (xy -0.127 -0.3429) (xy 0.127 -0.3429) (xy 0.127 -0.1651)
						(xy 0.635 0.3429)
					)
					(width 0)
					(fill yes)
				)
			)
		)
	)
	(footprint ""
		(layer "F.Cu")
		(at 58.9788 -92.0496 -90)
		(property "Reference" "C595"
			(at 0 0 270)
			(layer "F.SilkS")
			(hide yes)
			(effects
				(font
					(size 1.27 1.27)
				)
			)
		)
		(property "Value" "SC10U16V5KX-7-GP-U"
			(at -0.0762 -6.1214 270)
			(unlocked yes)
			(layer "F.Fab")
			(hide yes)
			(effects
				(font
					(size 1.016 1.016)
					(thickness 0.1524)
				)
			)
		)
		(property "Device Type" "C805H58"
			(at -0.0762 -8.1534 270)
			(unlocked yes)
			(layer "F.Fab")
			(hide yes)
			(effects
				(font
					(size 1.016 1.016)
					(thickness 0.1524)
				)
			)
		)
		(duplicate_pad_numbers_are_jumpers no)
		(fp_line
			(start 0.635 0)
			(end -0.635 0)
			(stroke
				(width 0.508)
				(type default)
			)
			(layer "F.SilkS")
		)
		(fp_rect
			(start -0.9652 1.778)
			(end 0.9652 -1.778)
			(stroke
				(width 0)
				(type default)
			)
			(fill no)
			(layer "F.CrtYd")
		)
		(fp_poly
			(pts
				(xy -0.9652 -1.778) (xy 0.9652 -1.778) (xy 0.9652 1.778) (xy -0.9652 1.778)
			)
			(stroke
				(width 0)
				(type default)
			)
			(fill no)
			(layer "F.Fab")
		)
		(pad "1" smd rect
			(at 0 -0.9652 270)
			(size 1.397 1.143)
			(layers "F.Cu" "F.Mask" "F.Paste")
			(net "P12V_STBY_VIN_U10")
		)
		(pad "2" smd rect
			(at 0 0.9652 270)
			(size 1.397 1.143)
			(layers "F.Cu" "F.Mask" "F.Paste")
			(net "GND")
		)
	)
	(footprint ""
		(layer "F.Cu")
		(at 75.311 -35.941)
		(property "Reference" "C256"
			(at 0 0 0)
			(layer "F.SilkS")
			(hide yes)
			(effects
				(font
					(size 1.27 1.27)
				)
			)
		)
		(property "Value" "SC22U6D3V3MX-9-GP-U"
			(at 0 -2.8194 0)
			(unlocked yes)
			(layer "F.Fab")
			(hide yes)
			(effects
				(font
					(size 1.016 1.016)
					(thickness 0.1524)
				)
			)
		)
		(property "Device Type" "C603H40"
			(at 0 -4.3434 0)
			(unlocked yes)
			(layer "F.Fab")
			(hide yes)
			(effects
				(font
					(size 1.016 1.016)
					(thickness 0.1524)
				)
			)
		)
		(duplicate_pad_numbers_are_jumpers no)
		(fp_line
			(start 0.508 0)
			(end -0.508 0)
			(stroke
				(width 0.2032)
				(type default)
			)
			(layer "F.SilkS")
		)
		(fp_rect
			(start -0.5842 1.3335)
			(end 0.5842 -1.3335)
			(stroke
				(width 0)
				(type default)
			)
			(fill no)
			(layer "F.CrtYd")
		)
		(fp_rect
			(start -0.5842 1.3335)
			(end 0.5842 -1.3335)
			(stroke
				(width 0)
				(type default)
			)
			(fill no)
			(layer "F.Fab")
		)
		(pad "1" smd custom
			(at 0 -0.762)
			(size 0.2159 0.2159)
			(layers "F.Cu" "F.Mask" "F.Paste")
			(net "GB_VDDA")
			(options
				(clearance outline)
				(anchor circle)
			)
			(primitives
				(gr_poly
					(pts
						(arc
							(start -0.3302 -0.4318)
							(mid -0.402042 -0.402042)
							(end -0.4318 -0.3302)
						)
						(arc
							(start -0.4318 0.3302)
							(mid -0.402042 0.402042)
							(end -0.3302 0.4318)
						)
						(arc
							(start 0.3302 0.4318)
							(mid 0.402042 0.402042)
							(end 0.4318 0.3302)
						)
						(arc
							(start 0.4318 -0.3302)
							(mid 0.402042 -0.402042)
							(end 0.3302 -0.4318)
						)
					)
					(width 0)
					(fill yes)
				)
			)
		)
		(pad "2" smd custom
			(at 0 0.762)
			(size 0.2159 0.2159)
			(layers "F.Cu" "F.Mask" "F.Paste")
			(net "GND")
			(options
				(clearance outline)
				(anchor circle)
			)
			(primitives
				(gr_poly
					(pts
						(arc
							(start -0.3302 -0.4318)
							(mid -0.402042 -0.402042)
							(end -0.4318 -0.3302)
						)
						(arc
							(start -0.4318 0.3302)
							(mid -0.402042 0.402042)
							(end -0.3302 0.4318)
						)
						(arc
							(start 0.3302 0.4318)
							(mid 0.402042 0.402042)
							(end 0.4318 0.3302)
						)
						(arc
							(start 0.4318 -0.3302)
							(mid 0.402042 -0.402042)
							(end 0.3302 -0.4318)
						)
					)
					(width 0)
					(fill yes)
				)
			)
		)
	)
	(footprint ""
		(layer "F.Cu")
		(at 147.574 -100.457 180)
		(property "Reference" "C719"
			(at 0 0 180)
			(layer "F.SilkS")
			(hide yes)
			(effects
				(font
					(size 1.27 1.27)
				)
			)
		)
		(property "Value" "SC22U6D3V3MX-9-GP-U"
			(at 0 -2.8194 180)
			(unlocked yes)
			(layer "F.Fab")
			(hide yes)
			(effects
				(font
					(size 1.016 1.016)
					(thickness 0.1524)
				)
			)
		)
		(property "Device Type" "C603H40"
			(at 0 -4.3434 180)
			(unlocked yes)
			(layer "F.Fab")
			(hide yes)
			(effects
				(font
					(size 1.016 1.016)
					(thickness 0.1524)
				)
			)
		)
		(duplicate_pad_numbers_are_jumpers no)
		(fp_line
			(start 0.508 0)
			(end -0.508 0)
			(stroke
				(width 0.2032)
				(type default)
			)
			(layer "F.SilkS")
		)
		(fp_rect
			(start -0.5842 1.3335)
			(end 0.5842 -1.3335)
			(stroke
				(width 0)
				(type default)
			)
			(fill no)
			(layer "F.CrtYd")
		)
		(fp_rect
			(start -0.5842 1.3335)
			(end 0.5842 -1.3335)
			(stroke
				(width 0)
				(type default)
			)
			(fill no)
			(layer "F.Fab")
		)
		(pad "1" smd custom
			(at 0 -0.762 180)
			(size 0.2159 0.2159)
			(layers "F.Cu" "F.Mask" "F.Paste")
			(net "GB_VDDH")
			(options
				(clearance outline)
				(anchor circle)
			)
			(primitives
				(gr_poly
					(pts
						(arc
							(start -0.3302 -0.4318)
							(mid -0.402042 -0.402042)
							(end -0.4318 -0.3302)
						)
						(arc
							(start -0.4318 0.3302)
							(mid -0.402042 0.402042)
							(end -0.3302 0.4318)
						)
						(arc
							(start 0.3302 0.4318)
							(mid 0.402042 0.402042)
							(end 0.4318 0.3302)
						)
						(arc
							(start 0.4318 -0.3302)
							(mid 0.402042 -0.402042)
							(end 0.3302 -0.4318)
						)
					)
					(width 0)
					(fill yes)
				)
			)
		)
		(pad "2" smd custom
			(at 0 0.762 180)
			(size 0.2159 0.2159)
			(layers "F.Cu" "F.Mask" "F.Paste")
			(net "GND")
			(options
				(clearance outline)
				(anchor circle)
			)
			(primitives
				(gr_poly
					(pts
						(arc
							(start -0.3302 -0.4318)
							(mid -0.402042 -0.402042)
							(end -0.4318 -0.3302)
						)
						(arc
							(start -0.4318 0.3302)
							(mid -0.402042 0.402042)
							(end -0.3302 0.4318)
						)
						(arc
							(start 0.3302 0.4318)
							(mid 0.402042 0.402042)
							(end 0.4318 0.3302)
						)
						(arc
							(start 0.4318 -0.3302)
							(mid 0.402042 -0.402042)
							(end 0.3302 -0.4318)
						)
					)
					(width 0)
					(fill yes)
				)
			)
		)
	)
	(footprint ""
		(layer "F.Cu")
		(at 145.37055 -32.408114 102)
		(property "Reference" "C328"
			(at 0 0 102)
			(layer "F.SilkS")
			(hide yes)
			(effects
				(font
					(size 1.27 1.27)
				)
			)
		)
		(property "Value" "SCD01U16V1KX-GP"
			(at -2.831995 -1.740026 102)
			(unlocked yes)
			(layer "F.Fab")
			(hide yes)
			(effects
				(font
					(size 1.016 1.016)
					(thickness 0.1524)
				)
			)
		)
		(property "Device Type" "C0201H13"
			(at -2.831925 -3.263781 102)
			(unlocked yes)
			(layer "F.Fab")
			(hide yes)
			(effects
				(font
					(size 1.016 1.016)
					(thickness 0.1524)
				)
			)
		)
		(duplicate_pad_numbers_are_jumpers no)
		(fp_poly
			(pts
				(xy -0.279454 -0.647706) (xy 0.279346 -0.647706) (xy 0.279346 0.647694) (xy -0.279454 0.647694)
			)
			(stroke
				(width 0)
				(type default)
			)
			(fill no)
			(layer "F.CrtYd")
		)
		(fp_poly
			(pts
				(xy -0.279454 -0.647706) (xy 0.279346 -0.647706) (xy 0.279346 0.647694) (xy -0.279454 0.647694)
			)
			(stroke
				(width 0)
				(type default)
			)
			(fill no)
			(layer "F.Fab")
		)
		(pad "1" smd custom
			(at -0.000001 -0.2794 102)
			(size 0.0762 0.0762)
			(layers "F.Cu" "F.Mask" "F.Paste")
			(net "PHY_SCC_TO_IOC_40_DN")
			(options
				(clearance outline)
				(anchor circle)
			)
			(primitives
				(gr_poly
					(pts
						(arc
							(start 0.1524 -0.127)
							(mid 0.137521 -0.162921)
							(end 0.1016 -0.1778)
						)
						(arc
							(start -0.1016 -0.1778)
							(mid -0.137521 -0.162921)
							(end -0.1524 -0.127)
						)
						(arc
							(start -0.1524 0.127)
							(mid -0.137521 0.162921)
							(end -0.1016 0.1778)
						)
						(arc
							(start 0.1016 0.1778)
							(mid 0.137521 0.162921)
							(end 0.1524 0.127)
						)
					)
					(width 0)
					(fill yes)
				)
			)
		)
		(pad "2" smd custom
			(at 0.000001 0.2794 102)
			(size 0.0762 0.0762)
			(layers "F.Cu" "F.Mask" "F.Paste")
			(net "PHY_SCC_TO_IOC_C_40_DN")
			(options
				(clearance outline)
				(anchor circle)
			)
			(primitives
				(gr_poly
					(pts
						(arc
							(start 0.1524 -0.127)
							(mid 0.137521 -0.162921)
							(end 0.1016 -0.1778)
						)
						(arc
							(start -0.1016 -0.1778)
							(mid -0.137521 -0.162921)
							(end -0.1524 -0.127)
						)
						(arc
							(start -0.1524 0.127)
							(mid -0.137521 0.162921)
							(end -0.1016 0.1778)
						)
						(arc
							(start 0.1016 0.1778)
							(mid 0.137521 0.162921)
							(end 0.1524 0.127)
						)
					)
					(width 0)
					(fill yes)
				)
			)
		)
	)
	(footprint ""
		(layer "F.Cu")
		(at 169.489882 -88.142572 -90)
		(property "Reference" "C744"
			(at 0 0 270)
			(layer "F.SilkS")
			(hide yes)
			(effects
				(font
					(size 1.27 1.27)
				)
			)
		)
		(property "Value" "SC2200P50V2KX-2GP"
			(at 1.1811 -2.7051 270)
			(unlocked yes)
			(layer "F.Fab")
			(hide yes)
			(effects
				(font
					(size 1.016 1.016)
					(thickness 0.1524)
				)
			)
		)
		(property "Device Type" "C402H22"
			(at 1.1811 -4.2291 270)
			(unlocked yes)
			(layer "F.Fab")
			(hide yes)
			(effects
				(font
					(size 1.016 1.016)
					(thickness 0.1524)
				)
			)
		)
		(duplicate_pad_numbers_are_jumpers no)
		(fp_rect
			(start -0.4318 0.9525)
			(end 0.4318 -0.9525)
			(stroke
				(width 0)
				(type default)
			)
			(fill no)
			(layer "F.CrtYd")
		)
		(fp_rect
			(start -0.4318 0.9525)
			(end 0.4318 -0.9525)
			(stroke
				(width 0)
				(type default)
			)
			(fill no)
			(layer "F.Fab")
		)
		(pad "1" smd custom
			(at 0 -0.4445 270)
			(size 0.1524 0.1524)
			(layers "F.Cu" "F.Mask" "F.Paste")
			(net "VT235_VX_R")
			(options
				(clearance outline)
				(anchor circle)
			)
			(primitives
				(gr_poly
					(pts
						(arc
							(start 0.3048 -0.2032)
							(mid 0.275042 -0.275042)
							(end 0.2032 -0.3048)
						)
						(arc
							(start -0.2032 -0.3048)
							(mid -0.275042 -0.275042)
							(end -0.3048 -0.2032)
						)
						(arc
							(start -0.3048 0.2032)
							(mid -0.275042 0.275042)
							(end -0.2032 0.3048)
						)
						(arc
							(start 0.2032 0.3048)
							(mid 0.275042 0.275042)
							(end 0.3048 0.2032)
						)
					)
					(width 0)
					(fill yes)
				)
			)
		)
		(pad "2" smd custom
			(at 0 0.4445 270)
			(size 0.1524 0.1524)
			(layers "F.Cu" "F.Mask" "F.Paste")
			(net "GND")
			(options
				(clearance outline)
				(anchor circle)
			)
			(primitives
				(gr_poly
					(pts
						(arc
							(start 0.3048 -0.2032)
							(mid 0.275042 -0.275042)
							(end 0.2032 -0.3048)
						)
						(arc
							(start -0.2032 -0.3048)
							(mid -0.275042 -0.275042)
							(end -0.3048 -0.2032)
						)
						(arc
							(start -0.3048 0.2032)
							(mid -0.275042 0.275042)
							(end -0.2032 0.3048)
						)
						(arc
							(start 0.2032 0.3048)
							(mid 0.275042 0.275042)
							(end 0.3048 0.2032)
						)
					)
					(width 0)
					(fill yes)
				)
			)
		)
	)
	(footprint ""
		(layer "F.Cu")
		(at 181.580282 -104.651556 90)
		(property "Reference" "C395"
			(at 0 0 90)
			(layer "F.SilkS")
			(hide yes)
			(effects
				(font
					(size 1.27 1.27)
				)
			)
		)
		(property "Value" "SC100U6D3V6MX-GP"
			(at -0.0762 -5.1308 90)
			(unlocked yes)
			(layer "F.Fab")
			(hide yes)
			(effects
				(font
					(size 1.016 1.016)
					(thickness 0.1524)
				)
			)
		)
		(property "Device Type" "C1206H71"
			(at -0.127 -6.6548 90)
			(unlocked yes)
			(layer "F.Fab")
			(hide yes)
			(effects
				(font
					(size 1.016 1.016)
					(thickness 0.1524)
				)
			)
		)
		(duplicate_pad_numbers_are_jumpers no)
		(fp_line
			(start 1.016 -2.2352)
			(end 1.016 -0.8382)
			(stroke
				(width 0.1524)
				(type default)
			)
			(layer "F.SilkS")
		)
		(fp_line
			(start -1.016 -2.2352)
			(end 1.016 -2.2352)
			(stroke
				(width 0.1524)
				(type default)
			)
			(layer "F.SilkS")
		)
		(fp_line
			(start -1.016 -0.8382)
			(end -1.016 -2.2352)
			(stroke
				(width 0.1524)
				(type default)
			)
			(layer "F.SilkS")
		)
		(fp_line
			(start 1.016 0.8382)
			(end 1.016 2.2352)
			(stroke
				(width 0.1524)
				(type default)
			)
			(layer "F.SilkS")
		)
		(fp_line
			(start 1.016 2.2352)
			(end -1.016 2.2352)
			(stroke
				(width 0.1524)
				(type default)
			)
			(layer "F.SilkS")
		)
		(fp_line
			(start -1.016 2.2352)
			(end -1.016 0.8382)
			(stroke
				(width 0.1524)
				(type default)
			)
			(layer "F.SilkS")
		)
		(fp_rect
			(start -1.0922 2.3114)
			(end 1.0922 -2.3114)
			(stroke
				(width 0)
				(type default)
			)
			(fill no)
			(layer "F.CrtYd")
		)
		(fp_poly
			(pts
				(xy 1.0922 -2.3114) (xy 1.0922 2.3114) (xy -1.0922 2.3114) (xy -1.0922 -2.3114)
			)
			(stroke
				(width 0)
				(type default)
			)
			(fill no)
			(layer "F.Fab")
		)
		(pad "1" smd rect
			(at 0 -1.397 90)
			(size 1.651 1.27)
			(layers "F.Cu" "F.Mask" "F.Paste")
			(net "GND")
		)
		(pad "2" smd rect
			(at 0 1.397 90)
			(size 1.651 1.27)
			(layers "F.Cu" "F.Mask" "F.Paste")
			(net "SAS0_AVDD")
		)
	)
	(footprint ""
		(layer "F.Cu")
		(at 9.500108 -131.430014)
		(property "Reference" "LHOLE1"
			(at 0 0 0)
			(layer "F.SilkS")
			(hide yes)
			(effects
				(font
					(size 1.27 1.27)
				)
			)
		)
		(property "Value" "HOLE709R146-3P-S3-GP"
			(at -5.5626 -0.9652 0)
			(unlocked yes)
			(layer "F.Fab")
			(hide yes)
			(effects
				(font
					(size 1.016 1.016)
					(thickness 0.1524)
				)
			)
		)
		(property "Device Type" "HOLE709R146-3P-S3"
			(at -5.5626 -2.4892 0)
			(unlocked yes)
			(layer "F.Fab")
			(hide yes)
			(effects
				(font
					(size 1.016 1.016)
					(thickness 0.1524)
				)
			)
		)
		(duplicate_pad_numbers_are_jumpers no)
		(fp_poly
			(pts
				(arc
					(start -4.8006 -7.975854)
					(mid 9.309136 0)
					(end -4.8006 7.975854)
				)
			)
			(stroke
				(width 0)
				(type default)
			)
			(fill no)
			(layer "B.CrtYd")
		)
		(fp_poly
			(pts
				(arc
					(start -4.8006 -7.975854)
					(mid 9.309136 0)
					(end -4.8006 7.975854)
				)
			)
			(stroke
				(width 0)
				(type default)
			)
			(fill no)
			(layer "F.CrtYd")
		)
		(fp_poly
			(pts
				(arc
					(start -4.8006 -7.975854)
					(mid 9.309136 0)
					(end -4.8006 7.975854)
				)
			)
			(stroke
				(width 0)
				(type default)
			)
			(fill no)
			(layer "B.Fab")
		)
		(fp_poly
			(pts
				(arc
					(start -4.8006 -7.975854)
					(mid 9.309136 0)
					(end -4.8006 7.975854)
				)
			)
			(stroke
				(width 0)
				(type default)
			)
			(fill no)
			(layer "F.Fab")
		)
		(pad "1" thru_hole circle
			(at 0 -4.500118)
			(size 2.5146 2.5146)
			(drill 2.1082)
			(layers "*.Cu" "*.Mask")
			(remove_unused_layers no)
			(net "GND")
			(clearance 0.1524)
			(thermal_gap 0.1524)
		)
		(pad "2" thru_hole custom
			(at 0 0)
			(size 3.374898 3.374898)
			(drill 3.7084)
			(layers "*.Cu" "*.Mask")
			(remove_unused_layers no)
			(net "GND")
			(clearance -4.38785)
			(thermal_gap 0.3048)
			(options
				(clearance outline)
				(anchor circle)
			)
			(primitives
				(gr_poly
					(pts
						(arc
							(start -6.75005 -7.80161)
							(mid 6.750045 0)
							(end -6.75005 7.80161)
						)
					)
					(width 0)
					(fill yes)
				)
			)
			(padstack
				(mode front_inner_back)
				(layer "Inner"
					(shape circle)
					(size 4.1148 4.1148)
					(clearance 0.3048)
				)
				(layer "B.Cu"
					(shape custom)
					(size 3.374898 3.374898)
					(options
						(anchor circle)
					)
					(primitives
						(gr_poly
							(pts
								(arc
									(start -6.75005 -7.80161)
									(mid 6.750045 0)
									(end -6.75005 7.80161)
								)
							)
							(width 0)
							(fill yes)
						)
					)
					(clearance -4.38785)
				)
			)
		)
		(pad "3" thru_hole circle
			(at 0 4.500118)
			(size 1.9812 1.9812)
			(drill 1.5748)
			(layers "*.Cu" "*.Mask")
			(remove_unused_layers no)
			(net "GND")
			(clearance 0.1524)
			(thermal_gap 0.1524)
		)
	)
	(footprint ""
		(layer "F.Cu")
		(at 147.438618 -50.468022 102)
		(property "Reference" "C342"
			(at 0 0 102)
			(layer "F.SilkS")
			(hide yes)
			(effects
				(font
					(size 1.27 1.27)
				)
			)
		)
		(property "Value" "SCD01U16V1KX-GP"
			(at -2.832244 -1.740078 102)
			(unlocked yes)
			(layer "F.Fab")
			(hide yes)
			(effects
				(font
					(size 1.016 1.016)
					(thickness 0.1524)
				)
			)
		)
		(property "Device Type" "C0201H13"
			(at -2.832121 -3.264082 102)
			(unlocked yes)
			(layer "F.Fab")
			(hide yes)
			(effects
				(font
					(size 1.016 1.016)
					(thickness 0.1524)
				)
			)
		)
		(duplicate_pad_numbers_are_jumpers no)
		(fp_poly
			(pts
				(xy -0.279454 -0.647706) (xy 0.279346 -0.647706) (xy 0.279346 0.647694) (xy -0.279454 0.647694)
			)
			(stroke
				(width 0)
				(type default)
			)
			(fill no)
			(layer "F.CrtYd")
		)
		(fp_poly
			(pts
				(xy -0.279454 -0.647706) (xy 0.279346 -0.647706) (xy 0.279346 0.647694) (xy -0.279454 0.647694)
			)
			(stroke
				(width 0)
				(type default)
			)
			(fill no)
			(layer "F.Fab")
		)
		(pad "1" smd custom
			(at -0.000001 -0.2794 102)
			(size 0.0762 0.0762)
			(layers "F.Cu" "F.Mask" "F.Paste")
			(net "PHY_SCC_TO_IOC_46_DN")
			(options
				(clearance outline)
				(anchor circle)
			)
			(primitives
				(gr_poly
					(pts
						(arc
							(start 0.1524 -0.127)
							(mid 0.137521 -0.162921)
							(end 0.1016 -0.1778)
						)
						(arc
							(start -0.1016 -0.1778)
							(mid -0.137521 -0.162921)
							(end -0.1524 -0.127)
						)
						(arc
							(start -0.1524 0.127)
							(mid -0.137521 0.162921)
							(end -0.1016 0.1778)
						)
						(arc
							(start 0.1016 0.1778)
							(mid 0.137521 0.162921)
							(end 0.1524 0.127)
						)
					)
					(width 0)
					(fill yes)
				)
			)
		)
		(pad "2" smd custom
			(at 0.000001 0.2794 102)
			(size 0.0762 0.0762)
			(layers "F.Cu" "F.Mask" "F.Paste")
			(net "PHY_SCC_TO_IOC_C_46_DN")
			(options
				(clearance outline)
				(anchor circle)
			)
			(primitives
				(gr_poly
					(pts
						(arc
							(start 0.1524 -0.127)
							(mid 0.137521 -0.162921)
							(end 0.1016 -0.1778)
						)
						(arc
							(start -0.1016 -0.1778)
							(mid -0.137521 -0.162921)
							(end -0.1524 -0.127)
						)
						(arc
							(start -0.1524 0.127)
							(mid -0.137521 0.162921)
							(end -0.1016 0.1778)
						)
						(arc
							(start 0.1016 0.1778)
							(mid 0.137521 0.162921)
							(end 0.1524 0.127)
						)
					)
					(width 0)
					(fill yes)
				)
			)
		)
	)
	(footprint ""
		(layer "F.Cu")
		(at 88.543638 -55.58536 180)
		(property "Reference" "C110"
			(at 0 0 180)
			(layer "F.SilkS")
			(hide yes)
			(effects
				(font
					(size 1.27 1.27)
				)
			)
		)
		(property "Value" "SC15P50V2JN-2-GP"
			(at 1.1811 -2.7051 180)
			(unlocked yes)
			(layer "F.Fab")
			(hide yes)
			(effects
				(font
					(size 1.016 1.016)
					(thickness 0.1524)
				)
			)
		)
		(property "Device Type" "C402H22"
			(at 1.1811 -4.2291 180)
			(unlocked yes)
			(layer "F.Fab")
			(hide yes)
			(effects
				(font
					(size 1.016 1.016)
					(thickness 0.1524)
				)
			)
		)
		(duplicate_pad_numbers_are_jumpers no)
		(fp_rect
			(start -0.4318 0.9525)
			(end 0.4318 -0.9525)
			(stroke
				(width 0)
				(type default)
			)
			(fill no)
			(layer "F.CrtYd")
		)
		(fp_rect
			(start -0.4318 0.9525)
			(end 0.4318 -0.9525)
			(stroke
				(width 0)
				(type default)
			)
			(fill no)
			(layer "F.Fab")
		)
		(pad "1" smd custom
			(at 0 -0.4445 180)
			(size 0.1524 0.1524)
			(layers "F.Cu" "F.Mask" "F.Paste")
			(net "EXP_REF_CLK_P")
			(options
				(clearance outline)
				(anchor circle)
			)
			(primitives
				(gr_poly
					(pts
						(arc
							(start 0.3048 -0.2032)
							(mid 0.275042 -0.275042)
							(end 0.2032 -0.3048)
						)
						(arc
							(start -0.2032 -0.3048)
							(mid -0.275042 -0.275042)
							(end -0.3048 -0.2032)
						)
						(arc
							(start -0.3048 0.2032)
							(mid -0.275042 0.275042)
							(end -0.2032 0.3048)
						)
						(arc
							(start 0.2032 0.3048)
							(mid 0.275042 0.275042)
							(end 0.3048 0.2032)
						)
					)
					(width 0)
					(fill yes)
				)
			)
		)
		(pad "2" smd custom
			(at 0 0.4445 180)
			(size 0.1524 0.1524)
			(layers "F.Cu" "F.Mask" "F.Paste")
			(net "GND")
			(options
				(clearance outline)
				(anchor circle)
			)
			(primitives
				(gr_poly
					(pts
						(arc
							(start 0.3048 -0.2032)
							(mid 0.275042 -0.275042)
							(end 0.2032 -0.3048)
						)
						(arc
							(start -0.2032 -0.3048)
							(mid -0.275042 -0.275042)
							(end -0.3048 -0.2032)
						)
						(arc
							(start -0.3048 0.2032)
							(mid -0.275042 0.275042)
							(end -0.2032 0.3048)
						)
						(arc
							(start 0.2032 0.3048)
							(mid 0.275042 0.275042)
							(end 0.3048 0.2032)
						)
					)
					(width 0)
					(fill yes)
				)
			)
		)
	)
	(footprint ""
		(layer "F.Cu")
		(at 151.257 -88.1253 -90)
		(property "Reference" "R445"
			(at 0 0 270)
			(layer "F.SilkS")
			(hide yes)
			(effects
				(font
					(size 1.27 1.27)
				)
			)
		)
		(property "Value" "1KR2F-3-GP"
			(at 0.064008 -3.993896 270)
			(unlocked yes)
			(layer "F.Fab")
			(hide yes)
			(effects
				(font
					(size 1.016 1.016)
					(thickness 0.1524)
				)
			)
		)
		(property "Device Type" "R402H16"
			(at 0.064008 -5.517896 270)
			(unlocked yes)
			(layer "F.Fab")
			(hide yes)
			(effects
				(font
					(size 1.016 1.016)
					(thickness 0.1524)
				)
			)
		)
		(duplicate_pad_numbers_are_jumpers no)
		(fp_line
			(start -0.508 -0.9398)
			(end -0.508 0.9398)
			(stroke
				(width 0.1524)
				(type default)
			)
			(layer "F.SilkS")
		)
		(fp_line
			(start 0.508 -0.9398)
			(end -0.508 -0.9398)
			(stroke
				(width 0.1524)
				(type default)
			)
			(layer "F.SilkS")
		)
		(fp_rect
			(start -0.508 0.9398)
			(end 0.508 -0.9398)
			(stroke
				(width 0)
				(type default)
			)
			(fill no)
			(layer "F.CrtYd")
		)
		(fp_rect
			(start -0.508 0.9398)
			(end 0.508 -0.9398)
			(stroke
				(width 0)
				(type default)
			)
			(fill no)
			(layer "F.Fab")
		)
		(pad "1" smd custom
			(at 0 -0.4445 270)
			(size 0.1397 0.1397)
			(layers "F.Cu" "F.Mask" "F.Paste")
			(net "P3V3")
			(options
				(clearance outline)
				(anchor circle)
			)
			(primitives
				(gr_poly
					(pts
						(arc
							(start -0.1778 -0.2794)
							(mid -0.249642 -0.249642)
							(end -0.2794 -0.1778)
						)
						(arc
							(start -0.2794 0.1778)
							(mid -0.249642 0.249642)
							(end -0.1778 0.2794)
						)
						(arc
							(start 0.1778 0.2794)
							(mid 0.249642 0.249642)
							(end 0.2794 0.1778)
						)
						(arc
							(start 0.2794 -0.1778)
							(mid 0.249642 -0.249642)
							(end 0.1778 -0.2794)
						)
					)
					(width 0)
					(fill yes)
				)
			)
		)
		(pad "2" smd custom
			(at 0 0.4445 270)
			(size 0.1397 0.1397)
			(layers "F.Cu" "F.Mask" "F.Paste")
			(net "P3V3_SENSE")
			(options
				(clearance outline)
				(anchor circle)
			)
			(primitives
				(gr_poly
					(pts
						(arc
							(start -0.1778 -0.2794)
							(mid -0.249642 -0.249642)
							(end -0.2794 -0.1778)
						)
						(arc
							(start -0.2794 0.1778)
							(mid -0.249642 0.249642)
							(end -0.1778 0.2794)
						)
						(arc
							(start 0.1778 0.2794)
							(mid 0.249642 0.249642)
							(end 0.2794 0.1778)
						)
						(arc
							(start 0.2794 -0.1778)
							(mid 0.249642 -0.249642)
							(end 0.1778 -0.2794)
						)
					)
					(width 0)
					(fill yes)
				)
			)
		)
	)
	(footprint ""
		(layer "F.Cu")
		(at 142.778226 -63.791084 -90)
		(property "Reference" "C33"
			(at 0 0 270)
			(layer "F.SilkS")
			(hide yes)
			(effects
				(font
					(size 1.27 1.27)
				)
			)
		)
		(property "Value" "SCD01U16V1KX-GP"
			(at -2.8321 -1.7399 270)
			(unlocked yes)
			(layer "F.Fab")
			(hide yes)
			(effects
				(font
					(size 1.016 1.016)
					(thickness 0.1524)
				)
			)
		)
		(property "Device Type" "C0201H13"
			(at -2.8321 -3.2639 270)
			(unlocked yes)
			(layer "F.Fab")
			(hide yes)
			(effects
				(font
					(size 1.016 1.016)
					(thickness 0.1524)
				)
			)
		)
		(duplicate_pad_numbers_are_jumpers no)
		(fp_rect
			(start -0.2794 0.6477)
			(end 0.2794 -0.6477)
			(stroke
				(width 0)
				(type default)
			)
			(fill no)
			(layer "F.CrtYd")
		)
		(fp_rect
			(start -0.2794 0.6477)
			(end 0.2794 -0.6477)
			(stroke
				(width 0)
				(type default)
			)
			(fill no)
			(layer "F.Fab")
		)
		(pad "1" smd custom
			(at 0 -0.2794 270)
			(size 0.0762 0.0762)
			(layers "F.Cu" "F.Mask" "F.Paste")
			(net "PHY_IOC_TO_SCC_47_DP")
			(options
				(clearance outline)
				(anchor circle)
			)
			(primitives
				(gr_poly
					(pts
						(arc
							(start 0.1524 -0.127)
							(mid 0.137521 -0.162921)
							(end 0.1016 -0.1778)
						)
						(arc
							(start -0.1016 -0.1778)
							(mid -0.137521 -0.162921)
							(end -0.1524 -0.127)
						)
						(arc
							(start -0.1524 0.127)
							(mid -0.137521 0.162921)
							(end -0.1016 0.1778)
						)
						(arc
							(start 0.1016 0.1778)
							(mid 0.137521 0.162921)
							(end 0.1524 0.127)
						)
					)
					(width 0)
					(fill yes)
				)
			)
		)
		(pad "2" smd custom
			(at 0 0.2794 270)
			(size 0.0762 0.0762)
			(layers "F.Cu" "F.Mask" "F.Paste")
			(net "PHY_IOC_TO_SCC_C_47_DP")
			(options
				(clearance outline)
				(anchor circle)
			)
			(primitives
				(gr_poly
					(pts
						(arc
							(start 0.1524 -0.127)
							(mid 0.137521 -0.162921)
							(end 0.1016 -0.1778)
						)
						(arc
							(start -0.1016 -0.1778)
							(mid -0.137521 -0.162921)
							(end -0.1524 -0.127)
						)
						(arc
							(start -0.1524 0.127)
							(mid -0.137521 0.162921)
							(end -0.1016 0.1778)
						)
						(arc
							(start 0.1016 0.1778)
							(mid 0.137521 0.162921)
							(end 0.1524 0.127)
						)
					)
					(width 0)
					(fill yes)
				)
			)
		)
	)
	(footprint ""
		(layer "F.Cu")
		(at 191.994282 -81.707736 90)
		(property "Reference" "R368"
			(at 0 0 90)
			(layer "F.SilkS")
			(hide yes)
			(effects
				(font
					(size 1.27 1.27)
				)
			)
		)
		(property "Value" "4K7R2F-GP"
			(at 0.064008 -3.993896 90)
			(unlocked yes)
			(layer "F.Fab")
			(hide yes)
			(effects
				(font
					(size 1.016 1.016)
					(thickness 0.1524)
				)
			)
		)
		(property "Device Type" "R402H16"
			(at 0.064008 -5.517896 90)
			(unlocked yes)
			(layer "F.Fab")
			(hide yes)
			(effects
				(font
					(size 1.016 1.016)
					(thickness 0.1524)
				)
			)
		)
		(duplicate_pad_numbers_are_jumpers no)
		(fp_line
			(start 0.508 -0.9398)
			(end -0.508 -0.9398)
			(stroke
				(width 0.1524)
				(type default)
			)
			(layer "F.SilkS")
		)
		(fp_line
			(start -0.508 -0.9398)
			(end -0.508 0.9398)
			(stroke
				(width 0.1524)
				(type default)
			)
			(layer "F.SilkS")
		)
		(fp_rect
			(start -0.508 0.9398)
			(end 0.508 -0.9398)
			(stroke
				(width 0)
				(type default)
			)
			(fill no)
			(layer "F.CrtYd")
		)
		(fp_rect
			(start -0.508 0.9398)
			(end 0.508 -0.9398)
			(stroke
				(width 0)
				(type default)
			)
			(fill no)
			(layer "F.Fab")
		)
		(pad "1" smd custom
			(at 0 -0.4445 90)
			(size 0.1397 0.1397)
			(layers "F.Cu" "F.Mask" "F.Paste")
			(net "P3V3")
			(options
				(clearance outline)
				(anchor circle)
			)
			(primitives
				(gr_poly
					(pts
						(arc
							(start -0.1778 -0.2794)
							(mid -0.249642 -0.249642)
							(end -0.2794 -0.1778)
						)
						(arc
							(start -0.2794 0.1778)
							(mid -0.249642 0.249642)
							(end -0.1778 0.2794)
						)
						(arc
							(start 0.1778 0.2794)
							(mid 0.249642 0.249642)
							(end 0.2794 0.1778)
						)
						(arc
							(start 0.2794 -0.1778)
							(mid 0.249642 -0.249642)
							(end 0.1778 -0.2794)
						)
					)
					(width 0)
					(fill yes)
				)
			)
		)
		(pad "2" smd custom
			(at 0 0.4445 90)
			(size 0.1397 0.1397)
			(layers "F.Cu" "F.Mask" "F.Paste")
			(net "TEMP2_A2")
			(options
				(clearance outline)
				(anchor circle)
			)
			(primitives
				(gr_poly
					(pts
						(arc
							(start -0.1778 -0.2794)
							(mid -0.249642 -0.249642)
							(end -0.2794 -0.1778)
						)
						(arc
							(start -0.2794 0.1778)
							(mid -0.249642 0.249642)
							(end -0.1778 0.2794)
						)
						(arc
							(start 0.1778 0.2794)
							(mid 0.249642 0.249642)
							(end 0.2794 0.1778)
						)
						(arc
							(start 0.2794 -0.1778)
							(mid 0.249642 -0.249642)
							(end 0.1778 -0.2794)
						)
					)
					(width 0)
					(fill yes)
				)
			)
		)
	)
	(footprint ""
		(layer "F.Cu")
		(at 182.1561 -114.80673)
		(property "Reference" "R99"
			(at 0 0 0)
			(layer "F.SilkS")
			(hide yes)
			(effects
				(font
					(size 1.27 1.27)
				)
			)
		)
		(property "Value" "3K57R2F-GP"
			(at 0.064008 -3.993896 0)
			(unlocked yes)
			(layer "F.Fab")
			(hide yes)
			(effects
				(font
					(size 1.016 1.016)
					(thickness 0.1524)
				)
			)
		)
		(property "Device Type" "R402H16"
			(at 0.064008 -5.517896 0)
			(unlocked yes)
			(layer "F.Fab")
			(hide yes)
			(effects
				(font
					(size 1.016 1.016)
					(thickness 0.1524)
				)
			)
		)
		(duplicate_pad_numbers_are_jumpers no)
		(fp_line
			(start -0.508 -0.9398)
			(end -0.508 0.9398)
			(stroke
				(width 0.1524)
				(type default)
			)
			(layer "F.SilkS")
		)
		(fp_line
			(start 0.508 -0.9398)
			(end -0.508 -0.9398)
			(stroke
				(width 0.1524)
				(type default)
			)
			(layer "F.SilkS")
		)
		(fp_rect
			(start -0.508 0.9398)
			(end 0.508 -0.9398)
			(stroke
				(width 0)
				(type default)
			)
			(fill no)
			(layer "F.CrtYd")
		)
		(fp_rect
			(start -0.508 0.9398)
			(end 0.508 -0.9398)
			(stroke
				(width 0)
				(type default)
			)
			(fill no)
			(layer "F.Fab")
		)
		(pad "1" smd custom
			(at 0 -0.4445)
			(size 0.1397 0.1397)
			(layers "F.Cu" "F.Mask" "F.Paste")
			(net "P1V8_E_OUT")
			(options
				(clearance outline)
				(anchor circle)
			)
			(primitives
				(gr_poly
					(pts
						(arc
							(start -0.1778 -0.2794)
							(mid -0.249642 -0.249642)
							(end -0.2794 -0.1778)
						)
						(arc
							(start -0.2794 0.1778)
							(mid -0.249642 0.249642)
							(end -0.1778 0.2794)
						)
						(arc
							(start 0.1778 0.2794)
							(mid 0.249642 0.249642)
							(end 0.2794 0.1778)
						)
						(arc
							(start 0.2794 -0.1778)
							(mid 0.249642 -0.249642)
							(end 0.1778 -0.2794)
						)
					)
					(width 0)
					(fill yes)
				)
			)
		)
		(pad "2" smd custom
			(at 0 0.4445)
			(size 0.1397 0.1397)
			(layers "F.Cu" "F.Mask" "F.Paste")
			(net "P1V8_E_FB")
			(options
				(clearance outline)
				(anchor circle)
			)
			(primitives
				(gr_poly
					(pts
						(arc
							(start -0.1778 -0.2794)
							(mid -0.249642 -0.249642)
							(end -0.2794 -0.1778)
						)
						(arc
							(start -0.2794 0.1778)
							(mid -0.249642 0.249642)
							(end -0.1778 0.2794)
						)
						(arc
							(start 0.1778 0.2794)
							(mid 0.249642 0.249642)
							(end 0.2794 0.1778)
						)
						(arc
							(start 0.2794 -0.1778)
							(mid 0.249642 -0.249642)
							(end 0.1778 -0.2794)
						)
					)
					(width 0)
					(fill yes)
				)
			)
		)
	)
	(footprint ""
		(layer "F.Cu")
		(at 119.963184 -86.995)
		(property "Reference" "R38"
			(at 0 0 0)
			(layer "F.SilkS")
			(hide yes)
			(effects
				(font
					(size 1.27 1.27)
				)
			)
		)
		(property "Value" "4K7R2F-GP"
			(at 0.064008 -3.993896 0)
			(unlocked yes)
			(layer "F.Fab")
			(hide yes)
			(effects
				(font
					(size 1.016 1.016)
					(thickness 0.1524)
				)
			)
		)
		(property "Device Type" "R402H16"
			(at 0.064008 -5.517896 0)
			(unlocked yes)
			(layer "F.Fab")
			(hide yes)
			(effects
				(font
					(size 1.016 1.016)
					(thickness 0.1524)
				)
			)
		)
		(duplicate_pad_numbers_are_jumpers no)
		(fp_line
			(start -0.508 -0.9398)
			(end -0.508 0.9398)
			(stroke
				(width 0.1524)
				(type default)
			)
			(layer "F.SilkS")
		)
		(fp_line
			(start 0.508 -0.9398)
			(end -0.508 -0.9398)
			(stroke
				(width 0.1524)
				(type default)
			)
			(layer "F.SilkS")
		)
		(fp_rect
			(start -0.508 0.9398)
			(end 0.508 -0.9398)
			(stroke
				(width 0)
				(type default)
			)
			(fill no)
			(layer "F.CrtYd")
		)
		(fp_rect
			(start -0.508 0.9398)
			(end 0.508 -0.9398)
			(stroke
				(width 0)
				(type default)
			)
			(fill no)
			(layer "F.Fab")
		)
		(pad "1" smd custom
			(at 0 -0.4445)
			(size 0.1397 0.1397)
			(layers "F.Cu" "F.Mask" "F.Paste")
			(net "P1V8_E")
			(options
				(clearance outline)
				(anchor circle)
			)
			(primitives
				(gr_poly
					(pts
						(arc
							(start -0.1778 -0.2794)
							(mid -0.249642 -0.249642)
							(end -0.2794 -0.1778)
						)
						(arc
							(start -0.2794 0.1778)
							(mid -0.249642 0.249642)
							(end -0.1778 0.2794)
						)
						(arc
							(start 0.1778 0.2794)
							(mid 0.249642 0.249642)
							(end 0.2794 0.1778)
						)
						(arc
							(start 0.2794 -0.1778)
							(mid 0.249642 -0.249642)
							(end 0.1778 -0.2794)
						)
					)
					(width 0)
					(fill yes)
				)
			)
		)
		(pad "2" smd custom
			(at 0 0.4445)
			(size 0.1397 0.1397)
			(layers "F.Cu" "F.Mask" "F.Paste")
			(net "EXP_GPIO15")
			(options
				(clearance outline)
				(anchor circle)
			)
			(primitives
				(gr_poly
					(pts
						(arc
							(start -0.1778 -0.2794)
							(mid -0.249642 -0.249642)
							(end -0.2794 -0.1778)
						)
						(arc
							(start -0.2794 0.1778)
							(mid -0.249642 0.249642)
							(end -0.1778 0.2794)
						)
						(arc
							(start 0.1778 0.2794)
							(mid 0.249642 0.249642)
							(end 0.2794 0.1778)
						)
						(arc
							(start 0.2794 -0.1778)
							(mid 0.249642 -0.249642)
							(end 0.1778 -0.2794)
						)
					)
					(width 0)
					(fill yes)
				)
			)
		)
	)
	(footprint ""
		(layer "F.Cu")
		(at 21.7678 -47.0154)
		(property "Reference" "R15"
			(at 0 0 0)
			(layer "F.SilkS")
			(hide yes)
			(effects
				(font
					(size 1.27 1.27)
				)
			)
		)
		(property "Value" "4K12R2F-3-GP"
			(at 0.064008 -3.993896 0)
			(unlocked yes)
			(layer "F.Fab")
			(hide yes)
			(effects
				(font
					(size 1.016 1.016)
					(thickness 0.1524)
				)
			)
		)
		(property "Device Type" "R402H16"
			(at 0.064008 -5.517896 0)
			(unlocked yes)
			(layer "F.Fab")
			(hide yes)
			(effects
				(font
					(size 1.016 1.016)
					(thickness 0.1524)
				)
			)
		)
		(duplicate_pad_numbers_are_jumpers no)
		(fp_line
			(start -0.508 -0.9398)
			(end -0.508 0.9398)
			(stroke
				(width 0.1524)
				(type default)
			)
			(layer "F.SilkS")
		)
		(fp_line
			(start 0.508 -0.9398)
			(end -0.508 -0.9398)
			(stroke
				(width 0.1524)
				(type default)
			)
			(layer "F.SilkS")
		)
		(fp_rect
			(start -0.508 0.9398)
			(end 0.508 -0.9398)
			(stroke
				(width 0)
				(type default)
			)
			(fill no)
			(layer "F.CrtYd")
		)
		(fp_rect
			(start -0.508 0.9398)
			(end 0.508 -0.9398)
			(stroke
				(width 0)
				(type default)
			)
			(fill no)
			(layer "F.Fab")
		)
		(pad "1" smd custom
			(at 0 -0.4445)
			(size 0.1397 0.1397)
			(layers "F.Cu" "F.Mask" "F.Paste")
			(net "MB0_CM_OV_R")
			(options
				(clearance outline)
				(anchor circle)
			)
			(primitives
				(gr_poly
					(pts
						(arc
							(start -0.1778 -0.2794)
							(mid -0.249642 -0.249642)
							(end -0.2794 -0.1778)
						)
						(arc
							(start -0.2794 0.1778)
							(mid -0.249642 0.249642)
							(end -0.1778 0.2794)
						)
						(arc
							(start 0.1778 0.2794)
							(mid 0.249642 0.249642)
							(end 0.2794 0.1778)
						)
						(arc
							(start 0.2794 -0.1778)
							(mid 0.249642 -0.249642)
							(end 0.1778 -0.2794)
						)
					)
					(width 0)
					(fill yes)
				)
			)
		)
		(pad "2" smd custom
			(at 0 0.4445)
			(size 0.1397 0.1397)
			(layers "F.Cu" "F.Mask" "F.Paste")
			(net "AGND_CURRENT_MON")
			(options
				(clearance outline)
				(anchor circle)
			)
			(primitives
				(gr_poly
					(pts
						(arc
							(start -0.1778 -0.2794)
							(mid -0.249642 -0.249642)
							(end -0.2794 -0.1778)
						)
						(arc
							(start -0.2794 0.1778)
							(mid -0.249642 0.249642)
							(end -0.1778 0.2794)
						)
						(arc
							(start 0.1778 0.2794)
							(mid 0.249642 0.249642)
							(end 0.2794 0.1778)
						)
						(arc
							(start 0.2794 -0.1778)
							(mid 0.249642 -0.249642)
							(end 0.1778 -0.2794)
						)
					)
					(width 0)
					(fill yes)
				)
			)
		)
	)
	(footprint ""
		(layer "F.Cu")
		(at 158.5087 -78.864714 -90)
		(property "Reference" "R331"
			(at 0 0 270)
			(layer "F.SilkS")
			(hide yes)
			(effects
				(font
					(size 1.27 1.27)
				)
			)
		)
		(property "Value" "4K7R2F-GP"
			(at 0.064008 -3.993896 270)
			(unlocked yes)
			(layer "F.Fab")
			(hide yes)
			(effects
				(font
					(size 1.016 1.016)
					(thickness 0.1524)
				)
			)
		)
		(property "Device Type" "R402H16"
			(at 0.064008 -5.517896 270)
			(unlocked yes)
			(layer "F.Fab")
			(hide yes)
			(effects
				(font
					(size 1.016 1.016)
					(thickness 0.1524)
				)
			)
		)
		(duplicate_pad_numbers_are_jumpers no)
		(fp_line
			(start -0.508 -0.9398)
			(end -0.508 0.9398)
			(stroke
				(width 0.1524)
				(type default)
			)
			(layer "F.SilkS")
		)
		(fp_line
			(start 0.508 -0.9398)
			(end -0.508 -0.9398)
			(stroke
				(width 0.1524)
				(type default)
			)
			(layer "F.SilkS")
		)
		(fp_rect
			(start -0.508 0.9398)
			(end 0.508 -0.9398)
			(stroke
				(width 0)
				(type default)
			)
			(fill no)
			(layer "F.CrtYd")
		)
		(fp_rect
			(start -0.508 0.9398)
			(end 0.508 -0.9398)
			(stroke
				(width 0)
				(type default)
			)
			(fill no)
			(layer "F.Fab")
		)
		(pad "1" smd custom
			(at 0 -0.4445 270)
			(size 0.1397 0.1397)
			(layers "F.Cu" "F.Mask" "F.Paste")
			(net "P3V3")
			(options
				(clearance outline)
				(anchor circle)
			)
			(primitives
				(gr_poly
					(pts
						(arc
							(start -0.1778 -0.2794)
							(mid -0.249642 -0.249642)
							(end -0.2794 -0.1778)
						)
						(arc
							(start -0.2794 0.1778)
							(mid -0.249642 0.249642)
							(end -0.1778 0.2794)
						)
						(arc
							(start 0.1778 0.2794)
							(mid 0.249642 0.249642)
							(end 0.2794 0.1778)
						)
						(arc
							(start 0.2794 -0.1778)
							(mid 0.249642 -0.249642)
							(end 0.1778 -0.2794)
						)
					)
					(width 0)
					(fill yes)
				)
			)
		)
		(pad "2" smd custom
			(at 0 0.4445 270)
			(size 0.1397 0.1397)
			(layers "F.Cu" "F.Mask" "F.Paste")
			(net "VOL_SEN2_ALERT")
			(options
				(clearance outline)
				(anchor circle)
			)
			(primitives
				(gr_poly
					(pts
						(arc
							(start -0.1778 -0.2794)
							(mid -0.249642 -0.249642)
							(end -0.2794 -0.1778)
						)
						(arc
							(start -0.2794 0.1778)
							(mid -0.249642 0.249642)
							(end -0.1778 0.2794)
						)
						(arc
							(start 0.1778 0.2794)
							(mid 0.249642 0.249642)
							(end 0.2794 0.1778)
						)
						(arc
							(start 0.2794 -0.1778)
							(mid 0.249642 -0.249642)
							(end 0.1778 -0.2794)
						)
					)
					(width 0)
					(fill yes)
				)
			)
		)
	)
	(footprint ""
		(layer "F.Cu")
		(at 123.317 -111.28248)
		(property "Reference" "TP23"
			(at 0 0 0)
			(layer "F.SilkS")
			(hide yes)
			(effects
				(font
					(size 1.27 1.27)
				)
			)
		)
		(property "Value" "TPAD28-2-GP"
			(at -0.0127 -1.6637 0)
			(unlocked yes)
			(layer "F.Fab")
			(hide yes)
			(effects
				(font
					(size 1.016 1.016)
					(thickness 0.1524)
				)
			)
		)
		(property "Device Type" "TPAD28"
			(at -0.0127 -3.1877 0)
			(unlocked yes)
			(layer "F.Fab")
			(hide yes)
			(effects
				(font
					(size 1.016 1.016)
					(thickness 0.1524)
				)
			)
		)
		(duplicate_pad_numbers_are_jumpers no)
		(fp_poly
			(pts
				(arc
					(start 0.3556 0)
					(mid -0.3556 0)
					(end 0.3556 0)
				)
			)
			(stroke
				(width 0)
				(type default)
			)
			(fill no)
			(layer "F.CrtYd")
		)
		(fp_poly
			(pts
				(arc
					(start 0.6096 0)
					(mid -0.6096 0)
					(end 0.6096 0)
				)
			)
			(stroke
				(width 0)
				(type default)
			)
			(fill no)
			(layer "F.Fab")
		)
		(pad "1" smd circle
			(at 0 0)
			(size 0.7112 0.7112)
			(layers "F.Cu" "F.Mask" "F.Paste")
			(net "INT_B1_CONN1")
		)
	)
	(footprint ""
		(layer "F.Cu")
		(at 38.9382 -43.4086)
		(property "Reference" "C668"
			(at 0 0 0)
			(layer "F.SilkS")
			(hide yes)
			(effects
				(font
					(size 1.27 1.27)
				)
			)
		)
		(property "Value" "SC10U16V5KX-7-GP-U"
			(at -0.0762 -6.1214 0)
			(unlocked yes)
			(layer "F.Fab")
			(hide yes)
			(effects
				(font
					(size 1.016 1.016)
					(thickness 0.1524)
				)
			)
		)
		(property "Device Type" "C805H58"
			(at -0.0762 -8.1534 0)
			(unlocked yes)
			(layer "F.Fab")
			(hide yes)
			(effects
				(font
					(size 1.016 1.016)
					(thickness 0.1524)
				)
			)
		)
		(duplicate_pad_numbers_are_jumpers no)
		(fp_line
			(start 0.635 0)
			(end -0.635 0)
			(stroke
				(width 0.508)
				(type default)
			)
			(layer "F.SilkS")
		)
		(fp_rect
			(start -0.9652 1.778)
			(end 0.9652 -1.778)
			(stroke
				(width 0)
				(type default)
			)
			(fill no)
			(layer "F.CrtYd")
		)
		(fp_poly
			(pts
				(xy -0.9652 -1.778) (xy 0.9652 -1.778) (xy 0.9652 1.778) (xy -0.9652 1.778)
			)
			(stroke
				(width 0)
				(type default)
			)
			(fill no)
			(layer "F.Fab")
		)
		(pad "1" smd rect
			(at 0 -0.9652)
			(size 1.397 1.143)
			(layers "F.Cu" "F.Mask" "F.Paste")
			(net "P12V_STBY_VIN_Q7")
		)
		(pad "2" smd rect
			(at 0 0.9652)
			(size 1.397 1.143)
			(layers "F.Cu" "F.Mask" "F.Paste")
			(net "GND")
		)
	)
	(footprint ""
		(layer "F.Cu")
		(at 161.29 -111.125 180)
		(property "Reference" "L6"
			(at 0 0 180)
			(layer "F.SilkS")
			(hide yes)
			(effects
				(font
					(size 1.27 1.27)
				)
			)
		)
		(property "Value" "BLM21PG220SN1DGP"
			(at 0.0254 -5.6896 180)
			(unlocked yes)
			(layer "F.Fab")
			(hide yes)
			(effects
				(font
					(size 1.016 1.016)
					(thickness 0.1524)
				)
			)
		)
		(property "Device Type" "L20125H42"
			(at 0.0254 -7.5946 180)
			(unlocked yes)
			(layer "F.Fab")
			(hide yes)
			(effects
				(font
					(size 1.016 1.016)
					(thickness 0.1524)
				)
			)
		)
		(duplicate_pad_numbers_are_jumpers no)
		(fp_line
			(start 0.9144 1.7018)
			(end 0.9144 -1.7018)
			(stroke
				(width 0.1524)
				(type default)
			)
			(layer "F.SilkS")
		)
		(fp_line
			(start 0.9144 -1.7018)
			(end -0.9144 -1.7018)
			(stroke
				(width 0.1524)
				(type default)
			)
			(layer "F.SilkS")
		)
		(fp_line
			(start -0.9144 1.7018)
			(end 0.9144 1.7018)
			(stroke
				(width 0.1524)
				(type default)
			)
			(layer "F.SilkS")
		)
		(fp_line
			(start -0.9144 -1.7018)
			(end -0.9144 1.7018)
			(stroke
				(width 0.1524)
				(type default)
			)
			(layer "F.SilkS")
		)
		(fp_rect
			(start -1.0033 1.778)
			(end 1.0033 -1.778)
			(stroke
				(width 0)
				(type default)
			)
			(fill no)
			(layer "F.CrtYd")
		)
		(fp_poly
			(pts
				(xy -1.0033 -1.778) (xy 1.0033 -1.778) (xy 1.0033 1.778) (xy -1.0033 1.778)
			)
			(stroke
				(width 0)
				(type default)
			)
			(fill no)
			(layer "F.Fab")
		)
		(pad "1" smd rect
			(at 0 -0.9652 180)
			(size 1.397 1.143)
			(layers "F.Cu" "F.Mask" "F.Paste")
			(net "P12V_STBY_SCC")
		)
		(pad "2" smd rect
			(at 0 0.9652 180)
			(size 1.397 1.143)
			(layers "F.Cu" "F.Mask" "F.Paste")
			(net "P12V_STBY_VIN_U11")
		)
	)
	(footprint ""
		(layer "F.Cu")
		(at 165.4556 -86.106 90)
		(property "Reference" "C637"
			(at 0 0 90)
			(layer "F.SilkS")
			(hide yes)
			(effects
				(font
					(size 1.27 1.27)
				)
			)
		)
		(property "Value" "SC10U16V5KX-7-GP-U"
			(at -0.0762 -6.1214 90)
			(unlocked yes)
			(layer "F.Fab")
			(hide yes)
			(effects
				(font
					(size 1.016 1.016)
					(thickness 0.1524)
				)
			)
		)
		(property "Device Type" "C805H58"
			(at -0.0762 -8.1534 90)
			(unlocked yes)
			(layer "F.Fab")
			(hide yes)
			(effects
				(font
					(size 1.016 1.016)
					(thickness 0.1524)
				)
			)
		)
		(duplicate_pad_numbers_are_jumpers no)
		(fp_line
			(start 0.635 0)
			(end -0.635 0)
			(stroke
				(width 0.508)
				(type default)
			)
			(layer "F.SilkS")
		)
		(fp_rect
			(start -0.9652 1.778)
			(end 0.9652 -1.778)
			(stroke
				(width 0)
				(type default)
			)
			(fill no)
			(layer "F.CrtYd")
		)
		(fp_poly
			(pts
				(xy -0.9652 -1.778) (xy 0.9652 -1.778) (xy 0.9652 1.778) (xy -0.9652 1.778)
			)
			(stroke
				(width 0)
				(type default)
			)
			(fill no)
			(layer "F.Fab")
		)
		(pad "1" smd rect
			(at 0 -0.9652 90)
			(size 1.397 1.143)
			(layers "F.Cu" "F.Mask" "F.Paste")
			(net "P12V_SYBY_VDD_U6")
		)
		(pad "2" smd rect
			(at 0 0.9652 90)
			(size 1.397 1.143)
			(layers "F.Cu" "F.Mask" "F.Paste")
			(net "GND")
		)
	)
	(footprint ""
		(layer "F.Cu")
		(at 164.2364 -93.5736)
		(property "Reference" "C644"
			(at 0 0 0)
			(layer "F.SilkS")
			(hide yes)
			(effects
				(font
					(size 1.27 1.27)
				)
			)
		)
		(property "Value" "SC10U16V5KX-7-GP-U"
			(at -0.0762 -6.1214 0)
			(unlocked yes)
			(layer "F.Fab")
			(hide yes)
			(effects
				(font
					(size 1.016 1.016)
					(thickness 0.1524)
				)
			)
		)
		(property "Device Type" "C805H58"
			(at -0.0762 -8.1534 0)
			(unlocked yes)
			(layer "F.Fab")
			(hide yes)
			(effects
				(font
					(size 1.016 1.016)
					(thickness 0.1524)
				)
			)
		)
		(duplicate_pad_numbers_are_jumpers no)
		(fp_line
			(start 0.635 0)
			(end -0.635 0)
			(stroke
				(width 0.508)
				(type default)
			)
			(layer "F.SilkS")
		)
		(fp_rect
			(start -0.9652 1.778)
			(end 0.9652 -1.778)
			(stroke
				(width 0)
				(type default)
			)
			(fill no)
			(layer "F.CrtYd")
		)
		(fp_poly
			(pts
				(xy -0.9652 -1.778) (xy 0.9652 -1.778) (xy 0.9652 1.778) (xy -0.9652 1.778)
			)
			(stroke
				(width 0)
				(type default)
			)
			(fill no)
			(layer "F.Fab")
		)
		(pad "1" smd rect
			(at 0 -0.9652)
			(size 1.397 1.143)
			(layers "F.Cu" "F.Mask" "F.Paste")
			(net "P12V_SYBY_VDD_U6")
		)
		(pad "2" smd rect
			(at 0 0.9652)
			(size 1.397 1.143)
			(layers "F.Cu" "F.Mask" "F.Paste")
			(net "GND")
		)
	)
	(footprint ""
		(layer "F.Cu")
		(at 204.5462 -68.326 180)
		(property "Reference" "C350"
			(at 0 0 180)
			(layer "F.SilkS")
			(hide yes)
			(effects
				(font
					(size 1.27 1.27)
				)
			)
		)
		(property "Value" "SCD1U16V2KX-3GP"
			(at 1.1811 -2.7051 180)
			(unlocked yes)
			(layer "F.Fab")
			(hide yes)
			(effects
				(font
					(size 1.016 1.016)
					(thickness 0.1524)
				)
			)
		)
		(property "Device Type" "C402H22"
			(at 1.1811 -4.2291 180)
			(unlocked yes)
			(layer "F.Fab")
			(hide yes)
			(effects
				(font
					(size 1.016 1.016)
					(thickness 0.1524)
				)
			)
		)
		(duplicate_pad_numbers_are_jumpers no)
		(fp_rect
			(start -0.4318 0.9525)
			(end 0.4318 -0.9525)
			(stroke
				(width 0)
				(type default)
			)
			(fill no)
			(layer "F.CrtYd")
		)
		(fp_rect
			(start -0.4318 0.9525)
			(end 0.4318 -0.9525)
			(stroke
				(width 0)
				(type default)
			)
			(fill no)
			(layer "F.Fab")
		)
		(pad "1" smd custom
			(at 0 -0.4445 180)
			(size 0.1524 0.1524)
			(layers "F.Cu" "F.Mask" "F.Paste")
			(net "P3V3")
			(options
				(clearance outline)
				(anchor circle)
			)
			(primitives
				(gr_poly
					(pts
						(arc
							(start 0.3048 -0.2032)
							(mid 0.275042 -0.275042)
							(end 0.2032 -0.3048)
						)
						(arc
							(start -0.2032 -0.3048)
							(mid -0.275042 -0.275042)
							(end -0.3048 -0.2032)
						)
						(arc
							(start -0.3048 0.2032)
							(mid -0.275042 0.275042)
							(end -0.2032 0.3048)
						)
						(arc
							(start 0.2032 0.3048)
							(mid 0.275042 0.275042)
							(end 0.3048 0.2032)
						)
					)
					(width 0)
					(fill yes)
				)
			)
		)
		(pad "2" smd custom
			(at 0 0.4445 180)
			(size 0.1524 0.1524)
			(layers "F.Cu" "F.Mask" "F.Paste")
			(net "GND")
			(options
				(clearance outline)
				(anchor circle)
			)
			(primitives
				(gr_poly
					(pts
						(arc
							(start 0.3048 -0.2032)
							(mid 0.275042 -0.275042)
							(end 0.2032 -0.3048)
						)
						(arc
							(start -0.2032 -0.3048)
							(mid -0.275042 -0.275042)
							(end -0.3048 -0.2032)
						)
						(arc
							(start -0.3048 0.2032)
							(mid -0.275042 0.275042)
							(end -0.2032 0.3048)
						)
						(arc
							(start 0.2032 0.3048)
							(mid 0.275042 0.275042)
							(end 0.3048 0.2032)
						)
					)
					(width 0)
					(fill yes)
				)
			)
		)
	)
	(footprint ""
		(layer "F.Cu")
		(at 68.92671 -80.556354 90)
		(property "Reference" "C557"
			(at 0 0 90)
			(layer "F.SilkS")
			(hide yes)
			(effects
				(font
					(size 1.27 1.27)
				)
			)
		)
		(property "Value" "SCD1U16V2KX-3GP"
			(at 1.1811 -2.7051 90)
			(unlocked yes)
			(layer "F.Fab")
			(hide yes)
			(effects
				(font
					(size 1.016 1.016)
					(thickness 0.1524)
				)
			)
		)
		(property "Device Type" "C402H22"
			(at 1.1811 -4.2291 90)
			(unlocked yes)
			(layer "F.Fab")
			(hide yes)
			(effects
				(font
					(size 1.016 1.016)
					(thickness 0.1524)
				)
			)
		)
		(duplicate_pad_numbers_are_jumpers no)
		(fp_rect
			(start -0.4318 0.9525)
			(end 0.4318 -0.9525)
			(stroke
				(width 0)
				(type default)
			)
			(fill no)
			(layer "F.CrtYd")
		)
		(fp_rect
			(start -0.4318 0.9525)
			(end 0.4318 -0.9525)
			(stroke
				(width 0)
				(type default)
			)
			(fill no)
			(layer "F.Fab")
		)
		(pad "1" smd custom
			(at 0 -0.4445 90)
			(size 0.1524 0.1524)
			(layers "F.Cu" "F.Mask" "F.Paste")
			(net "P1V8_E")
			(options
				(clearance outline)
				(anchor circle)
			)
			(primitives
				(gr_poly
					(pts
						(arc
							(start 0.3048 -0.2032)
							(mid 0.275042 -0.275042)
							(end 0.2032 -0.3048)
						)
						(arc
							(start -0.2032 -0.3048)
							(mid -0.275042 -0.275042)
							(end -0.3048 -0.2032)
						)
						(arc
							(start -0.3048 0.2032)
							(mid -0.275042 0.275042)
							(end -0.2032 0.3048)
						)
						(arc
							(start 0.2032 0.3048)
							(mid 0.275042 0.275042)
							(end 0.3048 0.2032)
						)
					)
					(width 0)
					(fill yes)
				)
			)
		)
		(pad "2" smd custom
			(at 0 0.4445 90)
			(size 0.1524 0.1524)
			(layers "F.Cu" "F.Mask" "F.Paste")
			(net "GND")
			(options
				(clearance outline)
				(anchor circle)
			)
			(primitives
				(gr_poly
					(pts
						(arc
							(start 0.3048 -0.2032)
							(mid 0.275042 -0.275042)
							(end 0.2032 -0.3048)
						)
						(arc
							(start -0.2032 -0.3048)
							(mid -0.275042 -0.275042)
							(end -0.3048 -0.2032)
						)
						(arc
							(start -0.3048 0.2032)
							(mid -0.275042 0.275042)
							(end -0.2032 0.3048)
						)
						(arc
							(start 0.2032 0.3048)
							(mid 0.275042 0.275042)
							(end 0.3048 0.2032)
						)
					)
					(width 0)
					(fill yes)
				)
			)
		)
	)
	(footprint ""
		(layer "F.Cu")
		(at 70.104 -9.652 90)
		(property "Reference" "R90"
			(at 0 0 90)
			(layer "F.SilkS")
			(hide yes)
			(effects
				(font
					(size 1.27 1.27)
				)
			)
		)
		(property "Value" "0R2J-2-GP"
			(at 0.064008 -3.993896 90)
			(unlocked yes)
			(layer "F.Fab")
			(hide yes)
			(effects
				(font
					(size 1.016 1.016)
					(thickness 0.1524)
				)
			)
		)
		(property "Device Type" "R402H16"
			(at 0.064008 -5.517896 90)
			(unlocked yes)
			(layer "F.Fab")
			(hide yes)
			(effects
				(font
					(size 1.016 1.016)
					(thickness 0.1524)
				)
			)
		)
		(duplicate_pad_numbers_are_jumpers no)
		(fp_line
			(start 0.508 -0.9398)
			(end -0.508 -0.9398)
			(stroke
				(width 0.1524)
				(type default)
			)
			(layer "F.SilkS")
		)
		(fp_line
			(start -0.508 -0.9398)
			(end -0.508 0.9398)
			(stroke
				(width 0.1524)
				(type default)
			)
			(layer "F.SilkS")
		)
		(fp_rect
			(start -0.508 0.9398)
			(end 0.508 -0.9398)
			(stroke
				(width 0)
				(type default)
			)
			(fill no)
			(layer "F.CrtYd")
		)
		(fp_rect
			(start -0.508 0.9398)
			(end 0.508 -0.9398)
			(stroke
				(width 0)
				(type default)
			)
			(fill no)
			(layer "F.Fab")
		)
		(pad "1" smd custom
			(at 0 -0.4445 90)
			(size 0.1397 0.1397)
			(layers "F.Cu" "F.Mask" "F.Paste")
			(net "GND")
			(options
				(clearance outline)
				(anchor circle)
			)
			(primitives
				(gr_poly
					(pts
						(arc
							(start -0.1778 -0.2794)
							(mid -0.249642 -0.249642)
							(end -0.2794 -0.1778)
						)
						(arc
							(start -0.2794 0.1778)
							(mid -0.249642 0.249642)
							(end -0.1778 0.2794)
						)
						(arc
							(start 0.1778 0.2794)
							(mid 0.249642 0.249642)
							(end 0.2794 0.1778)
						)
						(arc
							(start 0.2794 -0.1778)
							(mid 0.249642 -0.249642)
							(end 0.1778 -0.2794)
						)
					)
					(width 0)
					(fill yes)
				)
			)
		)
		(pad "2" smd custom
			(at 0 0.4445 90)
			(size 0.1397 0.1397)
			(layers "F.Cu" "F.Mask" "F.Paste")
			(net "SCC_TYPE_1")
			(options
				(clearance outline)
				(anchor circle)
			)
			(primitives
				(gr_poly
					(pts
						(arc
							(start -0.1778 -0.2794)
							(mid -0.249642 -0.249642)
							(end -0.2794 -0.1778)
						)
						(arc
							(start -0.2794 0.1778)
							(mid -0.249642 0.249642)
							(end -0.1778 0.2794)
						)
						(arc
							(start 0.1778 0.2794)
							(mid 0.249642 0.249642)
							(end 0.2794 0.1778)
						)
						(arc
							(start 0.2794 -0.1778)
							(mid 0.249642 -0.249642)
							(end 0.1778 -0.2794)
						)
					)
					(width 0)
					(fill yes)
				)
			)
		)
	)
	(footprint ""
		(layer "F.Cu")
		(at 11.668252 -59.360816 180)
		(property "Reference" "R13"
			(at 0 0 180)
			(layer "F.SilkS")
			(hide yes)
			(effects
				(font
					(size 1.27 1.27)
				)
			)
		)
		(property "Value" "0R2J-2-GP"
			(at 0.064008 -3.993896 180)
			(unlocked yes)
			(layer "F.Fab")
			(hide yes)
			(effects
				(font
					(size 1.016 1.016)
					(thickness 0.1524)
				)
			)
		)
		(property "Device Type" "R402H16"
			(at 0.064008 -5.517896 180)
			(unlocked yes)
			(layer "F.Fab")
			(hide yes)
			(effects
				(font
					(size 1.016 1.016)
					(thickness 0.1524)
				)
			)
		)
		(duplicate_pad_numbers_are_jumpers no)
		(fp_line
			(start 0.508 -0.9398)
			(end -0.508 -0.9398)
			(stroke
				(width 0.1524)
				(type default)
			)
			(layer "F.SilkS")
		)
		(fp_line
			(start -0.508 -0.9398)
			(end -0.508 0.9398)
			(stroke
				(width 0.1524)
				(type default)
			)
			(layer "F.SilkS")
		)
		(fp_rect
			(start -0.508 0.9398)
			(end 0.508 -0.9398)
			(stroke
				(width 0)
				(type default)
			)
			(fill no)
			(layer "F.CrtYd")
		)
		(fp_rect
			(start -0.508 0.9398)
			(end 0.508 -0.9398)
			(stroke
				(width 0)
				(type default)
			)
			(fill no)
			(layer "F.Fab")
		)
		(pad "1" smd custom
			(at 0 -0.4445 180)
			(size 0.1397 0.1397)
			(layers "F.Cu" "F.Mask" "F.Paste")
			(net "HSW_SDA_2")
			(options
				(clearance outline)
				(anchor circle)
			)
			(primitives
				(gr_poly
					(pts
						(arc
							(start -0.1778 -0.2794)
							(mid -0.249642 -0.249642)
							(end -0.2794 -0.1778)
						)
						(arc
							(start -0.2794 0.1778)
							(mid -0.249642 0.249642)
							(end -0.1778 0.2794)
						)
						(arc
							(start 0.1778 0.2794)
							(mid 0.249642 0.249642)
							(end 0.2794 0.1778)
						)
						(arc
							(start 0.2794 -0.1778)
							(mid 0.249642 -0.249642)
							(end 0.1778 -0.2794)
						)
					)
					(width 0)
					(fill yes)
				)
			)
		)
		(pad "2" smd custom
			(at 0 0.4445 180)
			(size 0.1397 0.1397)
			(layers "F.Cu" "F.Mask" "F.Paste")
			(net "I2C_SCC_SDA2")
			(options
				(clearance outline)
				(anchor circle)
			)
			(primitives
				(gr_poly
					(pts
						(arc
							(start -0.1778 -0.2794)
							(mid -0.249642 -0.249642)
							(end -0.2794 -0.1778)
						)
						(arc
							(start -0.2794 0.1778)
							(mid -0.249642 0.249642)
							(end -0.1778 0.2794)
						)
						(arc
							(start 0.1778 0.2794)
							(mid 0.249642 0.249642)
							(end 0.2794 0.1778)
						)
						(arc
							(start 0.2794 -0.1778)
							(mid 0.249642 -0.249642)
							(end 0.1778 -0.2794)
						)
					)
					(width 0)
					(fill yes)
				)
			)
		)
	)
	(footprint ""
		(layer "F.Cu")
		(at 94.615 -86.487 90)
		(property "Reference" "R561"
			(at 0 0 90)
			(layer "F.SilkS")
			(hide yes)
			(effects
				(font
					(size 1.27 1.27)
				)
			)
		)
		(property "Value" "10KR2F-2-GP"
			(at 0.064008 -3.993896 90)
			(unlocked yes)
			(layer "F.Fab")
			(hide yes)
			(effects
				(font
					(size 1.016 1.016)
					(thickness 0.1524)
				)
			)
		)
		(property "Device Type" "R402H16"
			(at 0.064008 -5.517896 90)
			(unlocked yes)
			(layer "F.Fab")
			(hide yes)
			(effects
				(font
					(size 1.016 1.016)
					(thickness 0.1524)
				)
			)
		)
		(duplicate_pad_numbers_are_jumpers no)
		(fp_line
			(start 0.508 -0.9398)
			(end -0.508 -0.9398)
			(stroke
				(width 0.1524)
				(type default)
			)
			(layer "F.SilkS")
		)
		(fp_line
			(start -0.508 -0.9398)
			(end -0.508 0.9398)
			(stroke
				(width 0.1524)
				(type default)
			)
			(layer "F.SilkS")
		)
		(fp_rect
			(start -0.508 0.9398)
			(end 0.508 -0.9398)
			(stroke
				(width 0)
				(type default)
			)
			(fill no)
			(layer "F.CrtYd")
		)
		(fp_rect
			(start -0.508 0.9398)
			(end 0.508 -0.9398)
			(stroke
				(width 0)
				(type default)
			)
			(fill no)
			(layer "F.Fab")
		)
		(pad "1" smd custom
			(at 0 -0.4445 90)
			(size 0.1397 0.1397)
			(layers "F.Cu" "F.Mask" "F.Paste")
			(net "BMC_LOC_HEARTBEAT_LS")
			(options
				(clearance outline)
				(anchor circle)
			)
			(primitives
				(gr_poly
					(pts
						(arc
							(start -0.1778 -0.2794)
							(mid -0.249642 -0.249642)
							(end -0.2794 -0.1778)
						)
						(arc
							(start -0.2794 0.1778)
							(mid -0.249642 0.249642)
							(end -0.1778 0.2794)
						)
						(arc
							(start 0.1778 0.2794)
							(mid 0.249642 0.249642)
							(end 0.2794 0.1778)
						)
						(arc
							(start 0.2794 -0.1778)
							(mid 0.249642 -0.249642)
							(end 0.1778 -0.2794)
						)
					)
					(width 0)
					(fill yes)
				)
			)
		)
		(pad "2" smd custom
			(at 0 0.4445 90)
			(size 0.1397 0.1397)
			(layers "F.Cu" "F.Mask" "F.Paste")
			(net "P1V8_E")
			(options
				(clearance outline)
				(anchor circle)
			)
			(primitives
				(gr_poly
					(pts
						(arc
							(start -0.1778 -0.2794)
							(mid -0.249642 -0.249642)
							(end -0.2794 -0.1778)
						)
						(arc
							(start -0.2794 0.1778)
							(mid -0.249642 0.249642)
							(end -0.1778 0.2794)
						)
						(arc
							(start 0.1778 0.2794)
							(mid 0.249642 0.249642)
							(end 0.2794 0.1778)
						)
						(arc
							(start 0.2794 -0.1778)
							(mid 0.249642 -0.249642)
							(end 0.1778 -0.2794)
						)
					)
					(width 0)
					(fill yes)
				)
			)
		)
	)
	(footprint ""
		(layer "F.Cu")
		(at 11.9126 -94.801182 180)
		(property "Reference" "C560"
			(at 0 0 180)
			(layer "F.SilkS")
			(hide yes)
			(effects
				(font
					(size 1.27 1.27)
				)
			)
		)
		(property "Value" "SCD1U16V2KX-3GP"
			(at 1.1811 -2.7051 180)
			(unlocked yes)
			(layer "F.Fab")
			(hide yes)
			(effects
				(font
					(size 1.016 1.016)
					(thickness 0.1524)
				)
			)
		)
		(property "Device Type" "C402H22"
			(at 1.1811 -4.2291 180)
			(unlocked yes)
			(layer "F.Fab")
			(hide yes)
			(effects
				(font
					(size 1.016 1.016)
					(thickness 0.1524)
				)
			)
		)
		(duplicate_pad_numbers_are_jumpers no)
		(fp_rect
			(start -0.4318 0.9525)
			(end 0.4318 -0.9525)
			(stroke
				(width 0)
				(type default)
			)
			(fill no)
			(layer "F.CrtYd")
		)
		(fp_rect
			(start -0.4318 0.9525)
			(end 0.4318 -0.9525)
			(stroke
				(width 0)
				(type default)
			)
			(fill no)
			(layer "F.Fab")
		)
		(pad "1" smd custom
			(at 0 -0.4445 180)
			(size 0.1524 0.1524)
			(layers "F.Cu" "F.Mask" "F.Paste")
			(net "VREF3")
			(options
				(clearance outline)
				(anchor circle)
			)
			(primitives
				(gr_poly
					(pts
						(arc
							(start 0.3048 -0.2032)
							(mid 0.275042 -0.275042)
							(end 0.2032 -0.3048)
						)
						(arc
							(start -0.2032 -0.3048)
							(mid -0.275042 -0.275042)
							(end -0.3048 -0.2032)
						)
						(arc
							(start -0.3048 0.2032)
							(mid -0.275042 0.275042)
							(end -0.2032 0.3048)
						)
						(arc
							(start 0.2032 0.3048)
							(mid 0.275042 0.275042)
							(end 0.3048 0.2032)
						)
					)
					(width 0)
					(fill yes)
				)
			)
		)
		(pad "2" smd custom
			(at 0 0.4445 180)
			(size 0.1524 0.1524)
			(layers "F.Cu" "F.Mask" "F.Paste")
			(net "GND")
			(options
				(clearance outline)
				(anchor circle)
			)
			(primitives
				(gr_poly
					(pts
						(arc
							(start 0.3048 -0.2032)
							(mid 0.275042 -0.275042)
							(end 0.2032 -0.3048)
						)
						(arc
							(start -0.2032 -0.3048)
							(mid -0.275042 -0.275042)
							(end -0.3048 -0.2032)
						)
						(arc
							(start -0.3048 0.2032)
							(mid -0.275042 0.275042)
							(end -0.2032 0.3048)
						)
						(arc
							(start 0.2032 0.3048)
							(mid 0.275042 0.275042)
							(end 0.3048 0.2032)
						)
					)
					(width 0)
					(fill yes)
				)
			)
		)
	)
	(footprint ""
		(layer "F.Cu")
		(at 173.11116 -107.30484)
		(property "Reference" "C664"
			(at 0 0 0)
			(layer "F.SilkS")
			(hide yes)
			(effects
				(font
					(size 1.27 1.27)
				)
			)
		)
		(property "Value" "SCD1U50V3KX-GP"
			(at 0 -2.8194 0)
			(unlocked yes)
			(layer "F.Fab")
			(hide yes)
			(effects
				(font
					(size 1.016 1.016)
					(thickness 0.1524)
				)
			)
		)
		(property "Device Type" "C603H36"
			(at 0 -4.3434 0)
			(unlocked yes)
			(layer "F.Fab")
			(hide yes)
			(effects
				(font
					(size 1.016 1.016)
					(thickness 0.1524)
				)
			)
		)
		(duplicate_pad_numbers_are_jumpers no)
		(fp_line
			(start 0.508 0)
			(end -0.508 0)
			(stroke
				(width 0.2032)
				(type default)
			)
			(layer "F.SilkS")
		)
		(fp_rect
			(start -0.5842 1.3335)
			(end 0.5842 -1.3335)
			(stroke
				(width 0)
				(type default)
			)
			(fill no)
			(layer "F.CrtYd")
		)
		(fp_rect
			(start -0.5842 1.3335)
			(end 0.5842 -1.3335)
			(stroke
				(width 0)
				(type default)
			)
			(fill no)
			(layer "F.Fab")
		)
		(pad "1" smd custom
			(at 0 -0.762)
			(size 0.2159 0.2159)
			(layers "F.Cu" "F.Mask" "F.Paste")
			(net "P3V3")
			(options
				(clearance outline)
				(anchor circle)
			)
			(primitives
				(gr_poly
					(pts
						(arc
							(start -0.3302 -0.4318)
							(mid -0.402042 -0.402042)
							(end -0.4318 -0.3302)
						)
						(arc
							(start -0.4318 0.3302)
							(mid -0.402042 0.402042)
							(end -0.3302 0.4318)
						)
						(arc
							(start 0.3302 0.4318)
							(mid 0.402042 0.402042)
							(end 0.4318 0.3302)
						)
						(arc
							(start 0.4318 -0.3302)
							(mid 0.402042 -0.402042)
							(end 0.3302 -0.4318)
						)
					)
					(width 0)
					(fill yes)
				)
			)
		)
		(pad "2" smd custom
			(at 0 0.762)
			(size 0.2159 0.2159)
			(layers "F.Cu" "F.Mask" "F.Paste")
			(net "GND")
			(options
				(clearance outline)
				(anchor circle)
			)
			(primitives
				(gr_poly
					(pts
						(arc
							(start -0.3302 -0.4318)
							(mid -0.402042 -0.402042)
							(end -0.4318 -0.3302)
						)
						(arc
							(start -0.4318 0.3302)
							(mid -0.402042 0.402042)
							(end -0.3302 0.4318)
						)
						(arc
							(start 0.3302 0.4318)
							(mid 0.402042 0.402042)
							(end 0.4318 0.3302)
						)
						(arc
							(start 0.4318 -0.3302)
							(mid 0.402042 -0.402042)
							(end 0.3302 -0.4318)
						)
					)
					(width 0)
					(fill yes)
				)
			)
		)
	)
	(footprint ""
		(layer "F.Cu")
		(at 8.1026 -67.5132 90)
		(property "Reference" "Q14"
			(at 0 0 90)
			(layer "F.SilkS")
			(hide yes)
			(effects
				(font
					(size 1.27 1.27)
				)
			)
		)
		(property "Value" "2N7002K-1-GP"
			(at 0.127 -8.9662 90)
			(unlocked yes)
			(layer "F.Fab")
			(hide yes)
			(effects
				(font
					(size 1.016 1.016)
					(thickness 0.1524)
				)
			)
		)
		(property "Device Type" "SOT23DGS2D4H44"
			(at 0.127 -10.4902 90)
			(unlocked yes)
			(layer "F.Fab")
			(hide yes)
			(effects
				(font
					(size 1.016 1.016)
					(thickness 0.1524)
				)
			)
		)
		(duplicate_pad_numbers_are_jumpers no)
		(fp_line
			(start 1.651 -1.778)
			(end -1.651 -1.778)
			(stroke
				(width 0.1524)
				(type default)
			)
			(layer "F.SilkS")
		)
		(fp_line
			(start -1.651 -1.778)
			(end -1.651 1.778)
			(stroke
				(width 0.1524)
				(type default)
			)
			(layer "F.SilkS")
		)
		(fp_line
			(start 1.651 1.778)
			(end 1.651 -1.778)
			(stroke
				(width 0.1524)
				(type default)
			)
			(layer "F.SilkS")
		)
		(fp_line
			(start -1.651 1.778)
			(end 1.651 1.778)
			(stroke
				(width 0.1524)
				(type default)
			)
			(layer "F.SilkS")
		)
		(fp_poly
			(pts
				(xy -1.778 1.8796) (xy -1.778 -1.8796) (xy 1.778 -1.8796) (xy 1.778 1.8796)
			)
			(stroke
				(width 0)
				(type default)
			)
			(fill no)
			(layer "F.CrtYd")
		)
		(fp_poly
			(pts
				(xy -1.778 1.8796) (xy -1.778 -1.8796) (xy 1.778 -1.8796) (xy 1.778 1.8796)
			)
			(stroke
				(width 0)
				(type default)
			)
			(fill no)
			(layer "F.Fab")
		)
		(pad "D" smd custom
			(at 0 -0.9525 90)
			(size 0.1905 0.1905)
			(layers "F.Cu" "F.Mask" "F.Paste")
			(net "MB0_HS_ENABLE_R")
			(options
				(clearance outline)
				(anchor circle)
			)
			(primitives
				(gr_poly
					(pts
						(arc
							(start -0.1778 0.5715)
							(mid -0.321484 0.511984)
							(end -0.381 0.3683)
						)
						(arc
							(start -0.381 -0.3683)
							(mid -0.321484 -0.511984)
							(end -0.1778 -0.5715)
						)
						(arc
							(start 0.1778 -0.5715)
							(mid 0.321484 -0.511984)
							(end 0.381 -0.3683)
						)
						(arc
							(start 0.381 0.3683)
							(mid 0.321484 0.511984)
							(end 0.1778 0.5715)
						)
					)
					(width 0)
					(fill yes)
				)
			)
		)
		(pad "G" smd custom
			(at -0.98425 0.9525 90)
			(size 0.1905 0.1905)
			(layers "F.Cu" "F.Mask" "F.Paste")
			(net "SCC_HSC_N")
			(options
				(clearance outline)
				(anchor circle)
			)
			(primitives
				(gr_poly
					(pts
						(arc
							(start -0.1778 0.5715)
							(mid -0.321484 0.511984)
							(end -0.381 0.3683)
						)
						(arc
							(start -0.381 -0.3683)
							(mid -0.321484 -0.511984)
							(end -0.1778 -0.5715)
						)
						(arc
							(start 0.1778 -0.5715)
							(mid 0.321484 -0.511984)
							(end 0.381 -0.3683)
						)
						(arc
							(start 0.381 0.3683)
							(mid 0.321484 0.511984)
							(end 0.1778 0.5715)
						)
					)
					(width 0)
					(fill yes)
				)
			)
		)
		(pad "S" smd custom
			(at 0.98425 0.9525 90)
			(size 0.1905 0.1905)
			(layers "F.Cu" "F.Mask" "F.Paste")
			(net "GND")
			(options
				(clearance outline)
				(anchor circle)
			)
			(primitives
				(gr_poly
					(pts
						(arc
							(start -0.1778 0.5715)
							(mid -0.321484 0.511984)
							(end -0.381 0.3683)
						)
						(arc
							(start -0.381 -0.3683)
							(mid -0.321484 -0.511984)
							(end -0.1778 -0.5715)
						)
						(arc
							(start 0.1778 -0.5715)
							(mid 0.321484 -0.511984)
							(end 0.381 -0.3683)
						)
						(arc
							(start 0.381 0.3683)
							(mid 0.321484 0.511984)
							(end 0.1778 0.5715)
						)
					)
					(width 0)
					(fill yes)
				)
			)
		)
	)
	(footprint ""
		(layer "F.Cu")
		(at 13.9192 -38.608 -90)
		(property "Reference" "R531"
			(at 0 0 270)
			(layer "F.SilkS")
			(hide yes)
			(effects
				(font
					(size 1.27 1.27)
				)
			)
		)
		(property "Value" "1KR2J-1-GP"
			(at 0.064008 -3.993896 270)
			(unlocked yes)
			(layer "F.Fab")
			(hide yes)
			(effects
				(font
					(size 1.016 1.016)
					(thickness 0.1524)
				)
			)
		)
		(property "Device Type" "R402H16"
			(at 0.064008 -5.517896 270)
			(unlocked yes)
			(layer "F.Fab")
			(hide yes)
			(effects
				(font
					(size 1.016 1.016)
					(thickness 0.1524)
				)
			)
		)
		(duplicate_pad_numbers_are_jumpers no)
		(fp_line
			(start -0.508 -0.9398)
			(end -0.508 0.9398)
			(stroke
				(width 0.1524)
				(type default)
			)
			(layer "F.SilkS")
		)
		(fp_line
			(start 0.508 -0.9398)
			(end -0.508 -0.9398)
			(stroke
				(width 0.1524)
				(type default)
			)
			(layer "F.SilkS")
		)
		(fp_rect
			(start -0.508 0.9398)
			(end 0.508 -0.9398)
			(stroke
				(width 0)
				(type default)
			)
			(fill no)
			(layer "F.CrtYd")
		)
		(fp_rect
			(start -0.508 0.9398)
			(end 0.508 -0.9398)
			(stroke
				(width 0)
				(type default)
			)
			(fill no)
			(layer "F.Fab")
		)
		(pad "1" smd custom
			(at 0 -0.4445 270)
			(size 0.1397 0.1397)
			(layers "F.Cu" "F.Mask" "F.Paste")
			(net "MB0_CM_VOUT_R")
			(options
				(clearance outline)
				(anchor circle)
			)
			(primitives
				(gr_poly
					(pts
						(arc
							(start -0.1778 -0.2794)
							(mid -0.249642 -0.249642)
							(end -0.2794 -0.1778)
						)
						(arc
							(start -0.2794 0.1778)
							(mid -0.249642 0.249642)
							(end -0.1778 0.2794)
						)
						(arc
							(start 0.1778 0.2794)
							(mid 0.249642 0.249642)
							(end 0.2794 0.1778)
						)
						(arc
							(start 0.2794 -0.1778)
							(mid 0.249642 -0.249642)
							(end 0.1778 -0.2794)
						)
					)
					(width 0)
					(fill yes)
				)
			)
		)
		(pad "2" smd custom
			(at 0 0.4445 270)
			(size 0.1397 0.1397)
			(layers "F.Cu" "F.Mask" "F.Paste")
			(net "P12V_STBY_SCC")
			(options
				(clearance outline)
				(anchor circle)
			)
			(primitives
				(gr_poly
					(pts
						(arc
							(start -0.1778 -0.2794)
							(mid -0.249642 -0.249642)
							(end -0.2794 -0.1778)
						)
						(arc
							(start -0.2794 0.1778)
							(mid -0.249642 0.249642)
							(end -0.1778 0.2794)
						)
						(arc
							(start 0.1778 0.2794)
							(mid 0.249642 0.249642)
							(end 0.2794 0.1778)
						)
						(arc
							(start 0.2794 -0.1778)
							(mid 0.249642 -0.249642)
							(end 0.1778 -0.2794)
						)
					)
					(width 0)
					(fill yes)
				)
			)
		)
	)
	(footprint ""
		(layer "F.Cu")
		(at 131.15798 -44.717716 180)
		(property "Reference" "C44"
			(at 0 0 180)
			(layer "F.SilkS")
			(hide yes)
			(effects
				(font
					(size 1.27 1.27)
				)
			)
		)
		(property "Value" "SCD01U16V1KX-GP"
			(at -2.8321 -1.7399 180)
			(unlocked yes)
			(layer "F.Fab")
			(hide yes)
			(effects
				(font
					(size 1.016 1.016)
					(thickness 0.1524)
				)
			)
		)
		(property "Device Type" "C0201H13"
			(at -2.8321 -3.2639 180)
			(unlocked yes)
			(layer "F.Fab")
			(hide yes)
			(effects
				(font
					(size 1.016 1.016)
					(thickness 0.1524)
				)
			)
		)
		(duplicate_pad_numbers_are_jumpers no)
		(fp_rect
			(start -0.2794 0.6477)
			(end 0.2794 -0.6477)
			(stroke
				(width 0)
				(type default)
			)
			(fill no)
			(layer "F.CrtYd")
		)
		(fp_rect
			(start -0.2794 0.6477)
			(end 0.2794 -0.6477)
			(stroke
				(width 0)
				(type default)
			)
			(fill no)
			(layer "F.Fab")
		)
		(pad "1" smd custom
			(at 0 -0.2794 180)
			(size 0.0762 0.0762)
			(layers "F.Cu" "F.Mask" "F.Paste")
			(net "PHY_IOC_TO_SCC_42_DN")
			(options
				(clearance outline)
				(anchor circle)
			)
			(primitives
				(gr_poly
					(pts
						(arc
							(start 0.1524 -0.127)
							(mid 0.137521 -0.162921)
							(end 0.1016 -0.1778)
						)
						(arc
							(start -0.1016 -0.1778)
							(mid -0.137521 -0.162921)
							(end -0.1524 -0.127)
						)
						(arc
							(start -0.1524 0.127)
							(mid -0.137521 0.162921)
							(end -0.1016 0.1778)
						)
						(arc
							(start 0.1016 0.1778)
							(mid 0.137521 0.162921)
							(end 0.1524 0.127)
						)
					)
					(width 0)
					(fill yes)
				)
			)
		)
		(pad "2" smd custom
			(at 0 0.2794 180)
			(size 0.0762 0.0762)
			(layers "F.Cu" "F.Mask" "F.Paste")
			(net "PHY_IOC_TO_SCC_C_42_DN")
			(options
				(clearance outline)
				(anchor circle)
			)
			(primitives
				(gr_poly
					(pts
						(arc
							(start 0.1524 -0.127)
							(mid 0.137521 -0.162921)
							(end 0.1016 -0.1778)
						)
						(arc
							(start -0.1016 -0.1778)
							(mid -0.137521 -0.162921)
							(end -0.1524 -0.127)
						)
						(arc
							(start -0.1524 0.127)
							(mid -0.137521 0.162921)
							(end -0.1016 0.1778)
						)
						(arc
							(start 0.1016 0.1778)
							(mid 0.137521 0.162921)
							(end 0.1524 0.127)
						)
					)
					(width 0)
					(fill yes)
				)
			)
		)
	)
	(footprint ""
		(layer "F.Cu")
		(at 190.6016 -33.2867)
		(property "Reference" "TP148"
			(at 0 0 0)
			(layer "F.SilkS")
			(hide yes)
			(effects
				(font
					(size 1.27 1.27)
				)
			)
		)
		(property "Value" "TPAD28-2-GP"
			(at -0.0127 -1.6637 0)
			(unlocked yes)
			(layer "F.Fab")
			(hide yes)
			(effects
				(font
					(size 1.016 1.016)
					(thickness 0.1524)
				)
			)
		)
		(property "Device Type" "TPAD28"
			(at -0.0127 -3.1877 0)
			(unlocked yes)
			(layer "F.Fab")
			(hide yes)
			(effects
				(font
					(size 1.016 1.016)
					(thickness 0.1524)
				)
			)
		)
		(duplicate_pad_numbers_are_jumpers no)
		(fp_poly
			(pts
				(arc
					(start 0.3556 0)
					(mid -0.3556 0)
					(end 0.3556 0)
				)
			)
			(stroke
				(width 0)
				(type default)
			)
			(fill no)
			(layer "F.CrtYd")
		)
		(fp_poly
			(pts
				(arc
					(start 0.6096 0)
					(mid -0.6096 0)
					(end 0.6096 0)
				)
			)
			(stroke
				(width 0)
				(type default)
			)
			(fill no)
			(layer "F.Fab")
		)
		(pad "1" smd circle
			(at 0 0)
			(size 0.7112 0.7112)
			(layers "F.Cu" "F.Mask" "F.Paste")
			(net "SPARE4")
		)
	)
	(footprint ""
		(layer "F.Cu")
		(at 185.138822 -90.409268 90)
		(property "Reference" "TC6"
			(at 0 0 90)
			(layer "F.SilkS")
			(hide yes)
			(effects
				(font
					(size 1.27 1.27)
				)
			)
		)
		(property "Value" "SE470UF2VDM-GP"
			(at 0 -9.6012 90)
			(unlocked yes)
			(layer "F.Fab")
			(hide yes)
			(effects
				(font
					(size 1.016 1.016)
					(thickness 0.1524)
				)
			)
		)
		(property "Device Type" "CT7343H83"
			(at 0 -11.1252 90)
			(unlocked yes)
			(layer "F.Fab")
			(hide yes)
			(effects
				(font
					(size 1.016 1.016)
					(thickness 0.1524)
				)
			)
		)
		(duplicate_pad_numbers_are_jumpers no)
		(fp_line
			(start 2.286 -4.8768)
			(end -2.286 -4.8768)
			(stroke
				(width 0.1524)
				(type default)
			)
			(layer "F.SilkS")
		)
		(fp_line
			(start -2.286 -4.8768)
			(end -2.286 -2.032)
			(stroke
				(width 0.1524)
				(type default)
			)
			(layer "F.SilkS")
		)
		(fp_line
			(start 2.1082 -4.699)
			(end -2.1082 -4.699)
			(stroke
				(width 0.508)
				(type default)
			)
			(layer "F.SilkS")
		)
		(fp_line
			(start 2.286 -2.032)
			(end 2.286 -4.8768)
			(stroke
				(width 0.1524)
				(type default)
			)
			(layer "F.SilkS")
		)
		(fp_line
			(start 2.286 2.032)
			(end 2.286 4.8768)
			(stroke
				(width 0.1524)
				(type default)
			)
			(layer "F.SilkS")
		)
		(fp_line
			(start 2.286 4.8768)
			(end -2.286 4.8768)
			(stroke
				(width 0.1524)
				(type default)
			)
			(layer "F.SilkS")
		)
		(fp_line
			(start -2.286 4.8768)
			(end -2.286 2.032)
			(stroke
				(width 0.1524)
				(type default)
			)
			(layer "F.SilkS")
		)
		(fp_rect
			(start -2.1463 3.6449)
			(end 2.1463 -3.6449)
			(stroke
				(width 0)
				(type default)
			)
			(fill no)
			(layer "F.CrtYd")
		)
		(fp_poly
			(pts
				(xy -2.54 4.953) (xy -2.54 4.2926) (xy -3.81 4.2926) (xy -3.81 -4.2926) (xy -2.54 -4.2926) (xy -2.54 -4.953)
				(xy 2.54 -4.953) (xy 2.54 -4.2926) (xy 3.81 -4.2926) (xy 3.81 -1.6256) (xy 2.1463 -1.6256) (xy 2.1463 -3.6449)
				(xy -2.1463 -3.6449) (xy -2.1463 3.6449) (xy 2.1463 3.6449) (xy 2.1463 -1.6129) (xy 3.81 -1.6129)
				(xy 3.81 4.2926) (xy 2.54 4.2926) (xy 2.54 4.953)
			)
			(stroke
				(width 0)
				(type default)
			)
			(fill no)
			(layer "F.CrtYd")
		)
		(fp_rect
			(start 2.54 4.2926)
			(end 3.81 -4.2926)
			(stroke
				(width 0)
				(type default)
			)
			(fill no)
			(layer "F.Fab")
		)
		(fp_rect
			(start -3.81 4.2926)
			(end -2.54 -4.2926)
			(stroke
				(width 0)
				(type default)
			)
			(fill no)
			(layer "F.Fab")
		)
		(fp_rect
			(start -2.54 4.953)
			(end 2.54 -4.953)
			(stroke
				(width 0)
				(type default)
			)
			(fill no)
			(layer "F.Fab")
		)
		(pad "1" smd rect
			(at 0 -3.1496 90)
			(size 2.413 2.286)
			(layers "F.Cu" "F.Mask" "F.Paste")
			(net "P0V975")
		)
		(pad "2" smd rect
			(at 0 3.1496 90)
			(size 2.413 2.286)
			(layers "F.Cu" "F.Mask" "F.Paste")
			(net "GND")
		)
		(zone
			(layer "F.Cu")
			(hatch none 0.5)
			(connect_pads
				(clearance 0)
			)
			(min_thickness 0.25)
			(keepout
				(tracks allowed)
				(vias not_allowed)
				(pads allowed)
				(copperpour not_allowed)
				(footprints allowed)
			)
			(placement
				(enabled no)
				(sheetname "")
			)
			(fill
				(thermal_gap 0.5)
				(thermal_bridge_width 0.5)
				(island_removal_mode 0)
			)
			(polygon
				(pts
					(xy 183.449722 -91.920568) (xy 180.541422 -91.920568) (xy 180.541422 -88.897968) (xy 183.437022 -88.897968)
					(xy 183.767222 -88.897968) (xy 183.767222 -91.920568)
				)
			)
		)
		(zone
			(layer "F.Cu")
			(hatch none 0.5)
			(connect_pads
				(clearance 0)
			)
			(min_thickness 0.25)
			(keepout
				(tracks allowed)
				(vias not_allowed)
				(pads allowed)
				(copperpour not_allowed)
				(footprints allowed)
			)
			(placement
				(enabled no)
				(sheetname "")
			)
			(fill
				(thermal_gap 0.5)
				(thermal_bridge_width 0.5)
				(island_removal_mode 0)
			)
			(polygon
				(pts
					(xy 189.736222 -88.897968) (xy 189.736222 -91.920568) (xy 186.840622 -91.920568) (xy 186.510422 -91.920568)
					(xy 186.510422 -88.897968) (xy 186.840622 -88.897968)
				)
			)
		)
	)
	(footprint ""
		(layer "F.Cu")
		(at 142.35176 -62.448186 -90)
		(property "Reference" "C36"
			(at 0 0 270)
			(layer "F.SilkS")
			(hide yes)
			(effects
				(font
					(size 1.27 1.27)
				)
			)
		)
		(property "Value" "SCD01U16V1KX-GP"
			(at -2.8321 -1.7399 270)
			(unlocked yes)
			(layer "F.Fab")
			(hide yes)
			(effects
				(font
					(size 1.016 1.016)
					(thickness 0.1524)
				)
			)
		)
		(property "Device Type" "C0201H13"
			(at -2.8321 -3.2639 270)
			(unlocked yes)
			(layer "F.Fab")
			(hide yes)
			(effects
				(font
					(size 1.016 1.016)
					(thickness 0.1524)
				)
			)
		)
		(duplicate_pad_numbers_are_jumpers no)
		(fp_rect
			(start -0.2794 0.6477)
			(end 0.2794 -0.6477)
			(stroke
				(width 0)
				(type default)
			)
			(fill no)
			(layer "F.CrtYd")
		)
		(fp_rect
			(start -0.2794 0.6477)
			(end 0.2794 -0.6477)
			(stroke
				(width 0)
				(type default)
			)
			(fill no)
			(layer "F.Fab")
		)
		(pad "1" smd custom
			(at 0 -0.2794 270)
			(size 0.0762 0.0762)
			(layers "F.Cu" "F.Mask" "F.Paste")
			(net "PHY_IOC_TO_SCC_46_DN")
			(options
				(clearance outline)
				(anchor circle)
			)
			(primitives
				(gr_poly
					(pts
						(arc
							(start 0.1524 -0.127)
							(mid 0.137521 -0.162921)
							(end 0.1016 -0.1778)
						)
						(arc
							(start -0.1016 -0.1778)
							(mid -0.137521 -0.162921)
							(end -0.1524 -0.127)
						)
						(arc
							(start -0.1524 0.127)
							(mid -0.137521 0.162921)
							(end -0.1016 0.1778)
						)
						(arc
							(start 0.1016 0.1778)
							(mid 0.137521 0.162921)
							(end 0.1524 0.127)
						)
					)
					(width 0)
					(fill yes)
				)
			)
		)
		(pad "2" smd custom
			(at 0 0.2794 270)
			(size 0.0762 0.0762)
			(layers "F.Cu" "F.Mask" "F.Paste")
			(net "PHY_IOC_TO_SCC_C_46_DN")
			(options
				(clearance outline)
				(anchor circle)
			)
			(primitives
				(gr_poly
					(pts
						(arc
							(start 0.1524 -0.127)
							(mid 0.137521 -0.162921)
							(end 0.1016 -0.1778)
						)
						(arc
							(start -0.1016 -0.1778)
							(mid -0.137521 -0.162921)
							(end -0.1524 -0.127)
						)
						(arc
							(start -0.1524 0.127)
							(mid -0.137521 0.162921)
							(end -0.1016 0.1778)
						)
						(arc
							(start 0.1016 0.1778)
							(mid 0.137521 0.162921)
							(end 0.1524 0.127)
						)
					)
					(width 0)
					(fill yes)
				)
			)
		)
	)
	(footprint ""
		(layer "F.Cu")
		(at 131.57708 -87.282528)
		(property "Reference" "TP35"
			(at 0 0 0)
			(layer "F.SilkS")
			(hide yes)
			(effects
				(font
					(size 1.27 1.27)
				)
			)
		)
		(property "Value" "TPAD28-2-GP"
			(at -0.0127 -1.6637 0)
			(unlocked yes)
			(layer "F.Fab")
			(hide yes)
			(effects
				(font
					(size 1.016 1.016)
					(thickness 0.1524)
				)
			)
		)
		(property "Device Type" "TPAD28"
			(at -0.0127 -3.1877 0)
			(unlocked yes)
			(layer "F.Fab")
			(hide yes)
			(effects
				(font
					(size 1.016 1.016)
					(thickness 0.1524)
				)
			)
		)
		(duplicate_pad_numbers_are_jumpers no)
		(fp_poly
			(pts
				(arc
					(start 0.3556 0)
					(mid -0.3556 0)
					(end 0.3556 0)
				)
			)
			(stroke
				(width 0)
				(type default)
			)
			(fill no)
			(layer "F.CrtYd")
		)
		(fp_poly
			(pts
				(arc
					(start 0.6096 0)
					(mid -0.6096 0)
					(end 0.6096 0)
				)
			)
			(stroke
				(width 0)
				(type default)
			)
			(fill no)
			(layer "F.Fab")
		)
		(pad "1" smd circle
			(at 0 0)
			(size 0.7112 0.7112)
			(layers "F.Cu" "F.Mask" "F.Paste")
			(net "UART_CTS")
		)
	)
	(footprint ""
		(layer "F.Cu")
		(at 73.533 -46.736)
		(property "Reference" "C277"
			(at 0 0 0)
			(layer "F.SilkS")
			(hide yes)
			(effects
				(font
					(size 1.27 1.27)
				)
			)
		)
		(property "Value" "SC100U6D3V6MX-GP"
			(at -0.0762 -5.1308 0)
			(unlocked yes)
			(layer "F.Fab")
			(hide yes)
			(effects
				(font
					(size 1.016 1.016)
					(thickness 0.1524)
				)
			)
		)
		(property "Device Type" "C1206H71"
			(at -0.127 -6.6548 0)
			(unlocked yes)
			(layer "F.Fab")
			(hide yes)
			(effects
				(font
					(size 1.016 1.016)
					(thickness 0.1524)
				)
			)
		)
		(duplicate_pad_numbers_are_jumpers no)
		(fp_line
			(start -1.016 -2.2352)
			(end 1.016 -2.2352)
			(stroke
				(width 0.1524)
				(type default)
			)
			(layer "F.SilkS")
		)
		(fp_line
			(start -1.016 -0.8382)
			(end -1.016 -2.2352)
			(stroke
				(width 0.1524)
				(type default)
			)
			(layer "F.SilkS")
		)
		(fp_line
			(start -1.016 2.2352)
			(end -1.016 0.8382)
			(stroke
				(width 0.1524)
				(type default)
			)
			(layer "F.SilkS")
		)
		(fp_line
			(start 1.016 -2.2352)
			(end 1.016 -0.8382)
			(stroke
				(width 0.1524)
				(type default)
			)
			(layer "F.SilkS")
		)
		(fp_line
			(start 1.016 0.8382)
			(end 1.016 2.2352)
			(stroke
				(width 0.1524)
				(type default)
			)
			(layer "F.SilkS")
		)
		(fp_line
			(start 1.016 2.2352)
			(end -1.016 2.2352)
			(stroke
				(width 0.1524)
				(type default)
			)
			(layer "F.SilkS")
		)
		(fp_rect
			(start -1.0922 2.3114)
			(end 1.0922 -2.3114)
			(stroke
				(width 0)
				(type default)
			)
			(fill no)
			(layer "F.CrtYd")
		)
		(fp_poly
			(pts
				(xy 1.0922 -2.3114) (xy 1.0922 2.3114) (xy -1.0922 2.3114) (xy -1.0922 -2.3114)
			)
			(stroke
				(width 0)
				(type default)
			)
			(fill no)
			(layer "F.Fab")
		)
		(pad "1" smd rect
			(at 0 -1.397)
			(size 1.651 1.27)
			(layers "F.Cu" "F.Mask" "F.Paste")
			(net "GB_VDDA")
		)
		(pad "2" smd rect
			(at 0 1.397)
			(size 1.651 1.27)
			(layers "F.Cu" "F.Mask" "F.Paste")
			(net "GND")
		)
	)
	(footprint ""
		(layer "F.Cu")
		(at 73.533 -57.277)
		(property "Reference" "C290"
			(at 0 0 0)
			(layer "F.SilkS")
			(hide yes)
			(effects
				(font
					(size 1.27 1.27)
				)
			)
		)
		(property "Value" "SC100U6D3V6MX-GP"
			(at -0.0762 -5.1308 0)
			(unlocked yes)
			(layer "F.Fab")
			(hide yes)
			(effects
				(font
					(size 1.016 1.016)
					(thickness 0.1524)
				)
			)
		)
		(property "Device Type" "C1206H71"
			(at -0.127 -6.6548 0)
			(unlocked yes)
			(layer "F.Fab")
			(hide yes)
			(effects
				(font
					(size 1.016 1.016)
					(thickness 0.1524)
				)
			)
		)
		(duplicate_pad_numbers_are_jumpers no)
		(fp_line
			(start -1.016 -2.2352)
			(end 1.016 -2.2352)
			(stroke
				(width 0.1524)
				(type default)
			)
			(layer "F.SilkS")
		)
		(fp_line
			(start -1.016 -0.8382)
			(end -1.016 -2.2352)
			(stroke
				(width 0.1524)
				(type default)
			)
			(layer "F.SilkS")
		)
		(fp_line
			(start -1.016 2.2352)
			(end -1.016 0.8382)
			(stroke
				(width 0.1524)
				(type default)
			)
			(layer "F.SilkS")
		)
		(fp_line
			(start 1.016 -2.2352)
			(end 1.016 -0.8382)
			(stroke
				(width 0.1524)
				(type default)
			)
			(layer "F.SilkS")
		)
		(fp_line
			(start 1.016 0.8382)
			(end 1.016 2.2352)
			(stroke
				(width 0.1524)
				(type default)
			)
			(layer "F.SilkS")
		)
		(fp_line
			(start 1.016 2.2352)
			(end -1.016 2.2352)
			(stroke
				(width 0.1524)
				(type default)
			)
			(layer "F.SilkS")
		)
		(fp_rect
			(start -1.0922 2.3114)
			(end 1.0922 -2.3114)
			(stroke
				(width 0)
				(type default)
			)
			(fill no)
			(layer "F.CrtYd")
		)
		(fp_poly
			(pts
				(xy 1.0922 -2.3114) (xy 1.0922 2.3114) (xy -1.0922 2.3114) (xy -1.0922 -2.3114)
			)
			(stroke
				(width 0)
				(type default)
			)
			(fill no)
			(layer "F.Fab")
		)
		(pad "1" smd rect
			(at 0 -1.397)
			(size 1.651 1.27)
			(layers "F.Cu" "F.Mask" "F.Paste")
			(net "GB_VDDA")
		)
		(pad "2" smd rect
			(at 0 1.397)
			(size 1.651 1.27)
			(layers "F.Cu" "F.Mask" "F.Paste")
			(net "GND")
		)
	)
	(footprint ""
		(layer "F.Cu")
		(at 158.369 -73.34123 -90)
		(property "Reference" "C534"
			(at 0 0 270)
			(layer "F.SilkS")
			(hide yes)
			(effects
				(font
					(size 1.27 1.27)
				)
			)
		)
		(property "Value" "SCD1U16V2KX-3GP"
			(at 1.1811 -2.7051 270)
			(unlocked yes)
			(layer "F.Fab")
			(hide yes)
			(effects
				(font
					(size 1.016 1.016)
					(thickness 0.1524)
				)
			)
		)
		(property "Device Type" "C402H22"
			(at 1.1811 -4.2291 270)
			(unlocked yes)
			(layer "F.Fab")
			(hide yes)
			(effects
				(font
					(size 1.016 1.016)
					(thickness 0.1524)
				)
			)
		)
		(duplicate_pad_numbers_are_jumpers no)
		(fp_rect
			(start -0.4318 0.9525)
			(end 0.4318 -0.9525)
			(stroke
				(width 0)
				(type default)
			)
			(fill no)
			(layer "F.CrtYd")
		)
		(fp_rect
			(start -0.4318 0.9525)
			(end 0.4318 -0.9525)
			(stroke
				(width 0)
				(type default)
			)
			(fill no)
			(layer "F.Fab")
		)
		(pad "1" smd custom
			(at 0 -0.4445 270)
			(size 0.1524 0.1524)
			(layers "F.Cu" "F.Mask" "F.Paste")
			(net "P1V5_C_SENSE")
			(options
				(clearance outline)
				(anchor circle)
			)
			(primitives
				(gr_poly
					(pts
						(arc
							(start 0.3048 -0.2032)
							(mid 0.275042 -0.275042)
							(end 0.2032 -0.3048)
						)
						(arc
							(start -0.2032 -0.3048)
							(mid -0.275042 -0.275042)
							(end -0.3048 -0.2032)
						)
						(arc
							(start -0.3048 0.2032)
							(mid -0.275042 0.275042)
							(end -0.2032 0.3048)
						)
						(arc
							(start 0.2032 0.3048)
							(mid 0.275042 0.275042)
							(end 0.3048 0.2032)
						)
					)
					(width 0)
					(fill yes)
				)
			)
		)
		(pad "2" smd custom
			(at 0 0.4445 270)
			(size 0.1524 0.1524)
			(layers "F.Cu" "F.Mask" "F.Paste")
			(net "GND")
			(options
				(clearance outline)
				(anchor circle)
			)
			(primitives
				(gr_poly
					(pts
						(arc
							(start 0.3048 -0.2032)
							(mid 0.275042 -0.275042)
							(end 0.2032 -0.3048)
						)
						(arc
							(start -0.2032 -0.3048)
							(mid -0.275042 -0.275042)
							(end -0.3048 -0.2032)
						)
						(arc
							(start -0.3048 0.2032)
							(mid -0.275042 0.275042)
							(end -0.2032 0.3048)
						)
						(arc
							(start 0.2032 0.3048)
							(mid 0.275042 0.275042)
							(end 0.3048 0.2032)
						)
					)
					(width 0)
					(fill yes)
				)
			)
		)
	)
	(footprint ""
		(layer "F.Cu")
		(at 82.825082 -104.359964 180)
		(property "Reference" "R553"
			(at 0 0 180)
			(layer "F.SilkS")
			(hide yes)
			(effects
				(font
					(size 1.27 1.27)
				)
			)
		)
		(property "Value" "0R2J-2-GP"
			(at 0.064008 -3.993896 180)
			(unlocked yes)
			(layer "F.Fab")
			(hide yes)
			(effects
				(font
					(size 1.016 1.016)
					(thickness 0.1524)
				)
			)
		)
		(property "Device Type" "R402H16"
			(at 0.064008 -5.517896 180)
			(unlocked yes)
			(layer "F.Fab")
			(hide yes)
			(effects
				(font
					(size 1.016 1.016)
					(thickness 0.1524)
				)
			)
		)
		(duplicate_pad_numbers_are_jumpers no)
		(fp_line
			(start 0.508 -0.9398)
			(end -0.508 -0.9398)
			(stroke
				(width 0.1524)
				(type default)
			)
			(layer "F.SilkS")
		)
		(fp_line
			(start -0.508 -0.9398)
			(end -0.508 0.9398)
			(stroke
				(width 0.1524)
				(type default)
			)
			(layer "F.SilkS")
		)
		(fp_rect
			(start -0.508 0.9398)
			(end 0.508 -0.9398)
			(stroke
				(width 0)
				(type default)
			)
			(fill no)
			(layer "F.CrtYd")
		)
		(fp_rect
			(start -0.508 0.9398)
			(end 0.508 -0.9398)
			(stroke
				(width 0)
				(type default)
			)
			(fill no)
			(layer "F.Fab")
		)
		(pad "1" smd custom
			(at 0 -0.4445 180)
			(size 0.1397 0.1397)
			(layers "F.Cu" "F.Mask" "F.Paste")
			(net "SCC_FULL_PWR_BUF_EN")
			(options
				(clearance outline)
				(anchor circle)
			)
			(primitives
				(gr_poly
					(pts
						(arc
							(start -0.1778 -0.2794)
							(mid -0.249642 -0.249642)
							(end -0.2794 -0.1778)
						)
						(arc
							(start -0.2794 0.1778)
							(mid -0.249642 0.249642)
							(end -0.1778 0.2794)
						)
						(arc
							(start 0.1778 0.2794)
							(mid 0.249642 0.249642)
							(end 0.2794 0.1778)
						)
						(arc
							(start 0.2794 -0.1778)
							(mid 0.249642 -0.249642)
							(end 0.1778 -0.2794)
						)
					)
					(width 0)
					(fill yes)
				)
			)
		)
		(pad "2" smd custom
			(at 0 0.4445 180)
			(size 0.1397 0.1397)
			(layers "F.Cu" "F.Mask" "F.Paste")
			(net "SCC_FULL_PWR_BUF_EN_U48")
			(options
				(clearance outline)
				(anchor circle)
			)
			(primitives
				(gr_poly
					(pts
						(arc
							(start -0.1778 -0.2794)
							(mid -0.249642 -0.249642)
							(end -0.2794 -0.1778)
						)
						(arc
							(start -0.2794 0.1778)
							(mid -0.249642 0.249642)
							(end -0.1778 0.2794)
						)
						(arc
							(start 0.1778 0.2794)
							(mid 0.249642 0.249642)
							(end 0.2794 0.1778)
						)
						(arc
							(start 0.2794 -0.1778)
							(mid 0.249642 -0.249642)
							(end 0.1778 -0.2794)
						)
					)
					(width 0)
					(fill yes)
				)
			)
		)
	)
	(footprint ""
		(layer "F.Cu")
		(at 170.171618 -100.629974 -90)
		(property "Reference" "C625"
			(at 0 0 270)
			(layer "F.SilkS")
			(hide yes)
			(effects
				(font
					(size 1.27 1.27)
				)
			)
		)
		(property "Value" "SC1KP50V2KX-1GP"
			(at 1.1811 -2.7051 270)
			(unlocked yes)
			(layer "F.Fab")
			(hide yes)
			(effects
				(font
					(size 1.016 1.016)
					(thickness 0.1524)
				)
			)
		)
		(property "Device Type" "C402H22"
			(at 1.1811 -4.2291 270)
			(unlocked yes)
			(layer "F.Fab")
			(hide yes)
			(effects
				(font
					(size 1.016 1.016)
					(thickness 0.1524)
				)
			)
		)
		(duplicate_pad_numbers_are_jumpers no)
		(fp_rect
			(start -0.4318 0.9525)
			(end 0.4318 -0.9525)
			(stroke
				(width 0)
				(type default)
			)
			(fill no)
			(layer "F.CrtYd")
		)
		(fp_rect
			(start -0.4318 0.9525)
			(end 0.4318 -0.9525)
			(stroke
				(width 0)
				(type default)
			)
			(fill no)
			(layer "F.Fab")
		)
		(pad "1" smd custom
			(at 0 -0.4445 270)
			(size 0.1524 0.1524)
			(layers "F.Cu" "F.Mask" "F.Paste")
			(net "VT235_VREF")
			(options
				(clearance outline)
				(anchor circle)
			)
			(primitives
				(gr_poly
					(pts
						(arc
							(start 0.3048 -0.2032)
							(mid 0.275042 -0.275042)
							(end 0.2032 -0.3048)
						)
						(arc
							(start -0.2032 -0.3048)
							(mid -0.275042 -0.275042)
							(end -0.3048 -0.2032)
						)
						(arc
							(start -0.3048 0.2032)
							(mid -0.275042 0.275042)
							(end -0.2032 0.3048)
						)
						(arc
							(start 0.2032 0.3048)
							(mid 0.275042 0.275042)
							(end 0.3048 0.2032)
						)
					)
					(width 0)
					(fill yes)
				)
			)
		)
		(pad "2" smd custom
			(at 0 0.4445 270)
			(size 0.1524 0.1524)
			(layers "F.Cu" "F.Mask" "F.Paste")
			(net "VT235_VDES_RCC")
			(options
				(clearance outline)
				(anchor circle)
			)
			(primitives
				(gr_poly
					(pts
						(arc
							(start 0.3048 -0.2032)
							(mid 0.275042 -0.275042)
							(end 0.2032 -0.3048)
						)
						(arc
							(start -0.2032 -0.3048)
							(mid -0.275042 -0.275042)
							(end -0.3048 -0.2032)
						)
						(arc
							(start -0.3048 0.2032)
							(mid -0.275042 0.275042)
							(end -0.2032 0.3048)
						)
						(arc
							(start 0.2032 0.3048)
							(mid 0.275042 0.275042)
							(end 0.3048 0.2032)
						)
					)
					(width 0)
					(fill yes)
				)
			)
		)
	)
	(footprint ""
		(layer "F.Cu")
		(at 136.248902 -75.35672 90)
		(property "Reference" "C682"
			(at 0 0 90)
			(layer "F.SilkS")
			(hide yes)
			(effects
				(font
					(size 1.27 1.27)
				)
			)
		)
		(property "Value" "SCD01U16V1KX-GP"
			(at -2.8321 -1.7399 90)
			(unlocked yes)
			(layer "F.Fab")
			(hide yes)
			(effects
				(font
					(size 1.016 1.016)
					(thickness 0.1524)
				)
			)
		)
		(property "Device Type" "C0201H13"
			(at -2.8321 -3.2639 90)
			(unlocked yes)
			(layer "F.Fab")
			(hide yes)
			(effects
				(font
					(size 1.016 1.016)
					(thickness 0.1524)
				)
			)
		)
		(duplicate_pad_numbers_are_jumpers no)
		(fp_rect
			(start -0.2794 0.6477)
			(end 0.2794 -0.6477)
			(stroke
				(width 0)
				(type default)
			)
			(fill no)
			(layer "F.CrtYd")
		)
		(fp_rect
			(start -0.2794 0.6477)
			(end 0.2794 -0.6477)
			(stroke
				(width 0)
				(type default)
			)
			(fill no)
			(layer "F.Fab")
		)
		(pad "1" smd custom
			(at 0 -0.2794 90)
			(size 0.0762 0.0762)
			(layers "F.Cu" "F.Mask" "F.Paste")
			(net "PHY_EXP_TO_CONN_C_8_DP")
			(options
				(clearance outline)
				(anchor circle)
			)
			(primitives
				(gr_poly
					(pts
						(arc
							(start 0.1524 -0.127)
							(mid 0.137521 -0.162921)
							(end 0.1016 -0.1778)
						)
						(arc
							(start -0.1016 -0.1778)
							(mid -0.137521 -0.162921)
							(end -0.1524 -0.127)
						)
						(arc
							(start -0.1524 0.127)
							(mid -0.137521 0.162921)
							(end -0.1016 0.1778)
						)
						(arc
							(start 0.1016 0.1778)
							(mid 0.137521 0.162921)
							(end 0.1524 0.127)
						)
					)
					(width 0)
					(fill yes)
				)
			)
		)
		(pad "2" smd custom
			(at 0 0.2794 90)
			(size 0.0762 0.0762)
			(layers "F.Cu" "F.Mask" "F.Paste")
			(net "PHY_EXP_TO_CONN_8_DP")
			(options
				(clearance outline)
				(anchor circle)
			)
			(primitives
				(gr_poly
					(pts
						(arc
							(start 0.1524 -0.127)
							(mid 0.137521 -0.162921)
							(end 0.1016 -0.1778)
						)
						(arc
							(start -0.1016 -0.1778)
							(mid -0.137521 -0.162921)
							(end -0.1524 -0.127)
						)
						(arc
							(start -0.1524 0.127)
							(mid -0.137521 0.162921)
							(end -0.1016 0.1778)
						)
						(arc
							(start 0.1016 0.1778)
							(mid 0.137521 0.162921)
							(end 0.1524 0.127)
						)
					)
					(width 0)
					(fill yes)
				)
			)
		)
	)
	(footprint ""
		(layer "F.Cu")
		(at 68.274438 -77.560424 180)
		(property "Reference" "U39"
			(at 0 0 180)
			(layer "F.SilkS")
			(hide yes)
			(effects
				(font
					(size 1.27 1.27)
				)
			)
		)
		(property "Value" "PCA9306DCTR-GP"
			(at 0 -11.6332 180)
			(unlocked yes)
			(layer "F.Fab")
			(hide yes)
			(effects
				(font
					(size 1.016 1.016)
					(thickness 0.1524)
				)
			)
		)
		(property "Device Type" "SSOIC8H52"
			(at 0 -13.1572 180)
			(unlocked yes)
			(layer "F.Fab")
			(hide yes)
			(effects
				(font
					(size 1.016 1.016)
					(thickness 0.1524)
				)
			)
		)
		(duplicate_pad_numbers_are_jumpers no)
		(fp_line
			(start 1.0668 0.5842)
			(end -1.524 0.5842)
			(stroke
				(width 0.1524)
				(type default)
			)
			(layer "F.SilkS")
		)
		(fp_line
			(start 1.0668 -0.5842)
			(end 1.0668 0.5842)
			(stroke
				(width 0.1524)
				(type default)
			)
			(layer "F.SilkS")
		)
		(fp_line
			(start -1.397 0)
			(end -1.7018 0.3048)
			(stroke
				(width 0.1524)
				(type default)
			)
			(layer "F.SilkS")
		)
		(fp_line
			(start -1.397 0)
			(end -1.7018 -0.3048)
			(stroke
				(width 0.1524)
				(type default)
			)
			(layer "F.SilkS")
		)
		(fp_line
			(start -1.524 0.5842)
			(end -1.524 2.286)
			(stroke
				(width 0.508)
				(type default)
			)
			(layer "F.SilkS")
		)
		(fp_line
			(start -1.7018 -0.5842)
			(end 1.0668 -0.5842)
			(stroke
				(width 0.1524)
				(type default)
			)
			(layer "F.SilkS")
		)
		(fp_line
			(start -1.7018 -0.5842)
			(end -1.7018 2.286)
			(stroke
				(width 0.1524)
				(type default)
			)
			(layer "F.SilkS")
		)
		(fp_poly
			(pts
				(xy -1.1684 -0.5842) (xy 1.0668 -0.5842) (xy 1.0668 0.5842) (xy -1.1684 0.5842)
			)
			(stroke
				(width 0)
				(type default)
			)
			(fill yes)
			(layer "F.SilkS")
		)
		(fp_poly
			(pts
				(xy -1.778 2.54) (xy 1.778 2.54) (xy 1.778 -2.54) (xy -1.778 -2.54)
			)
			(stroke
				(width 0)
				(type default)
			)
			(fill no)
			(layer "F.CrtYd")
		)
		(fp_poly
			(pts
				(xy -1.778 -2.54) (xy 1.778 -2.54) (xy 1.778 2.54) (xy -1.778 2.54)
			)
			(stroke
				(width 0)
				(type default)
			)
			(fill no)
			(layer "F.Fab")
		)
		(pad "1" smd rect
			(at -0.97536 1.6256 180)
			(size 0.3556 1.524)
			(layers "F.Cu" "F.Mask" "F.Paste")
			(net "GND")
		)
		(pad "2" smd rect
			(at -0.32512 1.6256 180)
			(size 0.3556 1.524)
			(layers "F.Cu" "F.Mask" "F.Paste")
			(net "P1V8_E")
		)
		(pad "3" smd rect
			(at 0.32512 1.6256 180)
			(size 0.3556 1.524)
			(layers "F.Cu" "F.Mask" "F.Paste")
			(net "I2C_DRIVE_FLT_LED_SCL6_LS")
		)
		(pad "4" smd rect
			(at 0.97536 1.6256 180)
			(size 0.3556 1.524)
			(layers "F.Cu" "F.Mask" "F.Paste")
			(net "I2C_DRIVE_FLT_LED_SDA6_LS")
		)
		(pad "5" smd rect
			(at 0.97536 -1.6256 180)
			(size 0.3556 1.524)
			(layers "F.Cu" "F.Mask" "F.Paste")
			(net "I2C_DRIVE_FLT_LED_SDA6")
		)
		(pad "6" smd rect
			(at 0.32512 -1.6256 180)
			(size 0.3556 1.524)
			(layers "F.Cu" "F.Mask" "F.Paste")
			(net "I2C_DRIVE_FLT_LED_SCL6")
		)
		(pad "7" smd rect
			(at -0.32512 -1.6256 180)
			(size 0.3556 1.524)
			(layers "F.Cu" "F.Mask" "F.Paste")
			(net "VREF6")
		)
		(pad "8" smd rect
			(at -0.97536 -1.6256 180)
			(size 0.3556 1.524)
			(layers "F.Cu" "F.Mask" "F.Paste")
			(net "LS_EN_U39")
		)
	)
	(footprint ""
		(layer "F.Cu")
		(at 94.615 -77.0128 90)
		(property "Reference" "R125"
			(at 0 0 90)
			(layer "F.SilkS")
			(hide yes)
			(effects
				(font
					(size 1.27 1.27)
				)
			)
		)
		(property "Value" "4K75R2F-1-GP"
			(at 0.064008 -3.993896 90)
			(unlocked yes)
			(layer "F.Fab")
			(hide yes)
			(effects
				(font
					(size 1.016 1.016)
					(thickness 0.1524)
				)
			)
		)
		(property "Device Type" "R402H16"
			(at 0.064008 -5.517896 90)
			(unlocked yes)
			(layer "F.Fab")
			(hide yes)
			(effects
				(font
					(size 1.016 1.016)
					(thickness 0.1524)
				)
			)
		)
		(duplicate_pad_numbers_are_jumpers no)
		(fp_line
			(start 0.508 -0.9398)
			(end -0.508 -0.9398)
			(stroke
				(width 0.1524)
				(type default)
			)
			(layer "F.SilkS")
		)
		(fp_line
			(start -0.508 -0.9398)
			(end -0.508 0.9398)
			(stroke
				(width 0.1524)
				(type default)
			)
			(layer "F.SilkS")
		)
		(fp_rect
			(start -0.508 0.9398)
			(end 0.508 -0.9398)
			(stroke
				(width 0)
				(type default)
			)
			(fill no)
			(layer "F.CrtYd")
		)
		(fp_rect
			(start -0.508 0.9398)
			(end 0.508 -0.9398)
			(stroke
				(width 0)
				(type default)
			)
			(fill no)
			(layer "F.Fab")
		)
		(pad "1" smd custom
			(at 0 -0.4445 90)
			(size 0.1397 0.1397)
			(layers "F.Cu" "F.Mask" "F.Paste")
			(net "EXP_CLK_SEL1")
			(options
				(clearance outline)
				(anchor circle)
			)
			(primitives
				(gr_poly
					(pts
						(arc
							(start -0.1778 -0.2794)
							(mid -0.249642 -0.249642)
							(end -0.2794 -0.1778)
						)
						(arc
							(start -0.2794 0.1778)
							(mid -0.249642 0.249642)
							(end -0.1778 0.2794)
						)
						(arc
							(start 0.1778 0.2794)
							(mid 0.249642 0.249642)
							(end 0.2794 0.1778)
						)
						(arc
							(start 0.2794 -0.1778)
							(mid 0.249642 -0.249642)
							(end 0.1778 -0.2794)
						)
					)
					(width 0)
					(fill yes)
				)
			)
		)
		(pad "2" smd custom
			(at 0 0.4445 90)
			(size 0.1397 0.1397)
			(layers "F.Cu" "F.Mask" "F.Paste")
			(net "GND")
			(options
				(clearance outline)
				(anchor circle)
			)
			(primitives
				(gr_poly
					(pts
						(arc
							(start -0.1778 -0.2794)
							(mid -0.249642 -0.249642)
							(end -0.2794 -0.1778)
						)
						(arc
							(start -0.2794 0.1778)
							(mid -0.249642 0.249642)
							(end -0.1778 0.2794)
						)
						(arc
							(start 0.1778 0.2794)
							(mid 0.249642 0.249642)
							(end 0.2794 0.1778)
						)
						(arc
							(start 0.2794 -0.1778)
							(mid 0.249642 -0.249642)
							(end 0.1778 -0.2794)
						)
					)
					(width 0)
					(fill yes)
				)
			)
		)
	)
	(footprint ""
		(layer "F.Cu")
		(at 116.923058 -86.995254 180)
		(property "Reference" "R144"
			(at 0 0 180)
			(layer "F.SilkS")
			(hide yes)
			(effects
				(font
					(size 1.27 1.27)
				)
			)
		)
		(property "Value" "4K7R2F-GP"
			(at 0.064008 -3.993896 180)
			(unlocked yes)
			(layer "F.Fab")
			(hide yes)
			(effects
				(font
					(size 1.016 1.016)
					(thickness 0.1524)
				)
			)
		)
		(property "Device Type" "R402H16"
			(at 0.064008 -5.517896 180)
			(unlocked yes)
			(layer "F.Fab")
			(hide yes)
			(effects
				(font
					(size 1.016 1.016)
					(thickness 0.1524)
				)
			)
		)
		(duplicate_pad_numbers_are_jumpers no)
		(fp_line
			(start 0.508 -0.9398)
			(end -0.508 -0.9398)
			(stroke
				(width 0.1524)
				(type default)
			)
			(layer "F.SilkS")
		)
		(fp_line
			(start -0.508 -0.9398)
			(end -0.508 0.9398)
			(stroke
				(width 0.1524)
				(type default)
			)
			(layer "F.SilkS")
		)
		(fp_rect
			(start -0.508 0.9398)
			(end 0.508 -0.9398)
			(stroke
				(width 0)
				(type default)
			)
			(fill no)
			(layer "F.CrtYd")
		)
		(fp_rect
			(start -0.508 0.9398)
			(end 0.508 -0.9398)
			(stroke
				(width 0)
				(type default)
			)
			(fill no)
			(layer "F.Fab")
		)
		(pad "1" smd custom
			(at 0 -0.4445 180)
			(size 0.1397 0.1397)
			(layers "F.Cu" "F.Mask" "F.Paste")
			(net "EXP_XM_ADDR_18")
			(options
				(clearance outline)
				(anchor circle)
			)
			(primitives
				(gr_poly
					(pts
						(arc
							(start -0.1778 -0.2794)
							(mid -0.249642 -0.249642)
							(end -0.2794 -0.1778)
						)
						(arc
							(start -0.2794 0.1778)
							(mid -0.249642 0.249642)
							(end -0.1778 0.2794)
						)
						(arc
							(start 0.1778 0.2794)
							(mid 0.249642 0.249642)
							(end 0.2794 0.1778)
						)
						(arc
							(start 0.2794 -0.1778)
							(mid 0.249642 -0.249642)
							(end 0.1778 -0.2794)
						)
					)
					(width 0)
					(fill yes)
				)
			)
		)
		(pad "2" smd custom
			(at 0 0.4445 180)
			(size 0.1397 0.1397)
			(layers "F.Cu" "F.Mask" "F.Paste")
			(net "GND")
			(options
				(clearance outline)
				(anchor circle)
			)
			(primitives
				(gr_poly
					(pts
						(arc
							(start -0.1778 -0.2794)
							(mid -0.249642 -0.249642)
							(end -0.2794 -0.1778)
						)
						(arc
							(start -0.2794 0.1778)
							(mid -0.249642 0.249642)
							(end -0.1778 0.2794)
						)
						(arc
							(start 0.1778 0.2794)
							(mid 0.249642 0.249642)
							(end 0.2794 0.1778)
						)
						(arc
							(start 0.2794 -0.1778)
							(mid 0.249642 -0.249642)
							(end 0.1778 -0.2794)
						)
					)
					(width 0)
					(fill yes)
				)
			)
		)
	)
	(footprint ""
		(layer "F.Cu")
		(at 40.2082 -30.988 -90)
		(property "Reference" "R400"
			(at 0 0 270)
			(layer "F.SilkS")
			(hide yes)
			(effects
				(font
					(size 1.27 1.27)
				)
			)
		)
		(property "Value" "1KR2F-3-GP"
			(at 0.064008 -3.993896 270)
			(unlocked yes)
			(layer "F.Fab")
			(hide yes)
			(effects
				(font
					(size 1.016 1.016)
					(thickness 0.1524)
				)
			)
		)
		(property "Device Type" "R402H16"
			(at 0.064008 -5.517896 270)
			(unlocked yes)
			(layer "F.Fab")
			(hide yes)
			(effects
				(font
					(size 1.016 1.016)
					(thickness 0.1524)
				)
			)
		)
		(duplicate_pad_numbers_are_jumpers no)
		(fp_line
			(start -0.508 -0.9398)
			(end -0.508 0.9398)
			(stroke
				(width 0.1524)
				(type default)
			)
			(layer "F.SilkS")
		)
		(fp_line
			(start 0.508 -0.9398)
			(end -0.508 -0.9398)
			(stroke
				(width 0.1524)
				(type default)
			)
			(layer "F.SilkS")
		)
		(fp_rect
			(start -0.508 0.9398)
			(end 0.508 -0.9398)
			(stroke
				(width 0)
				(type default)
			)
			(fill no)
			(layer "F.CrtYd")
		)
		(fp_rect
			(start -0.508 0.9398)
			(end 0.508 -0.9398)
			(stroke
				(width 0)
				(type default)
			)
			(fill no)
			(layer "F.Fab")
		)
		(pad "1" smd custom
			(at 0 -0.4445 270)
			(size 0.1397 0.1397)
			(layers "F.Cu" "F.Mask" "F.Paste")
			(net "P0V9_MODE")
			(options
				(clearance outline)
				(anchor circle)
			)
			(primitives
				(gr_poly
					(pts
						(arc
							(start -0.1778 -0.2794)
							(mid -0.249642 -0.249642)
							(end -0.2794 -0.1778)
						)
						(arc
							(start -0.2794 0.1778)
							(mid -0.249642 0.249642)
							(end -0.1778 0.2794)
						)
						(arc
							(start 0.1778 0.2794)
							(mid 0.249642 0.249642)
							(end 0.2794 0.1778)
						)
						(arc
							(start 0.2794 -0.1778)
							(mid 0.249642 -0.249642)
							(end 0.1778 -0.2794)
						)
					)
					(width 0)
					(fill yes)
				)
			)
		)
		(pad "2" smd custom
			(at 0 0.4445 270)
			(size 0.1397 0.1397)
			(layers "F.Cu" "F.Mask" "F.Paste")
			(net "AGND_P0V9")
			(options
				(clearance outline)
				(anchor circle)
			)
			(primitives
				(gr_poly
					(pts
						(arc
							(start -0.1778 -0.2794)
							(mid -0.249642 -0.249642)
							(end -0.2794 -0.1778)
						)
						(arc
							(start -0.2794 0.1778)
							(mid -0.249642 0.249642)
							(end -0.1778 0.2794)
						)
						(arc
							(start 0.1778 0.2794)
							(mid 0.249642 0.249642)
							(end 0.2794 0.1778)
						)
						(arc
							(start 0.2794 -0.1778)
							(mid 0.249642 -0.249642)
							(end 0.1778 -0.2794)
						)
					)
					(width 0)
					(fill yes)
				)
			)
		)
	)
	(footprint ""
		(layer "F.Cu")
		(at 165.6588 -93.5482)
		(property "Reference" "C658"
			(at 0 0 0)
			(layer "F.SilkS")
			(hide yes)
			(effects
				(font
					(size 1.27 1.27)
				)
			)
		)
		(property "Value" "SC4700P25V2KX-3-GP"
			(at 1.1811 -2.7051 0)
			(unlocked yes)
			(layer "F.Fab")
			(hide yes)
			(effects
				(font
					(size 1.016 1.016)
					(thickness 0.1524)
				)
			)
		)
		(property "Device Type" "C402H24"
			(at 1.1811 -4.2291 0)
			(unlocked yes)
			(layer "F.Fab")
			(hide yes)
			(effects
				(font
					(size 1.016 1.016)
					(thickness 0.1524)
				)
			)
		)
		(duplicate_pad_numbers_are_jumpers no)
		(fp_rect
			(start -0.4318 0.9525)
			(end 0.4318 -0.9525)
			(stroke
				(width 0)
				(type default)
			)
			(fill no)
			(layer "F.CrtYd")
		)
		(fp_rect
			(start -0.4318 0.9525)
			(end 0.4318 -0.9525)
			(stroke
				(width 0)
				(type default)
			)
			(fill no)
			(layer "F.Fab")
		)
		(pad "1" smd custom
			(at 0 -0.4445)
			(size 0.1524 0.1524)
			(layers "F.Cu" "F.Mask" "F.Paste")
			(net "P12V_SYBY_VDD_U6")
			(options
				(clearance outline)
				(anchor circle)
			)
			(primitives
				(gr_poly
					(pts
						(arc
							(start 0.3048 -0.2032)
							(mid 0.275042 -0.275042)
							(end 0.2032 -0.3048)
						)
						(arc
							(start -0.2032 -0.3048)
							(mid -0.275042 -0.275042)
							(end -0.3048 -0.2032)
						)
						(arc
							(start -0.3048 0.2032)
							(mid -0.275042 0.275042)
							(end -0.2032 0.3048)
						)
						(arc
							(start 0.2032 0.3048)
							(mid 0.275042 0.275042)
							(end 0.3048 0.2032)
						)
					)
					(width 0)
					(fill yes)
				)
			)
		)
		(pad "2" smd custom
			(at 0 0.4445)
			(size 0.1524 0.1524)
			(layers "F.Cu" "F.Mask" "F.Paste")
			(net "GND")
			(options
				(clearance outline)
				(anchor circle)
			)
			(primitives
				(gr_poly
					(pts
						(arc
							(start 0.3048 -0.2032)
							(mid 0.275042 -0.275042)
							(end 0.2032 -0.3048)
						)
						(arc
							(start -0.2032 -0.3048)
							(mid -0.275042 -0.275042)
							(end -0.3048 -0.2032)
						)
						(arc
							(start -0.3048 0.2032)
							(mid -0.275042 0.275042)
							(end -0.2032 0.3048)
						)
						(arc
							(start 0.2032 0.3048)
							(mid 0.275042 0.275042)
							(end 0.3048 0.2032)
						)
					)
					(width 0)
					(fill yes)
				)
			)
		)
	)
	(footprint ""
		(layer "F.Cu")
		(at 149.4409 -122.6566 90)
		(property "Reference" "C611"
			(at 0 0 90)
			(layer "F.SilkS")
			(hide yes)
			(effects
				(font
					(size 1.27 1.27)
				)
			)
		)
		(property "Value" "SC1KP50V2KX-1GP"
			(at 1.1811 -2.7051 90)
			(unlocked yes)
			(layer "F.Fab")
			(hide yes)
			(effects
				(font
					(size 1.016 1.016)
					(thickness 0.1524)
				)
			)
		)
		(property "Device Type" "C402H22"
			(at 1.1811 -4.2291 90)
			(unlocked yes)
			(layer "F.Fab")
			(hide yes)
			(effects
				(font
					(size 1.016 1.016)
					(thickness 0.1524)
				)
			)
		)
		(duplicate_pad_numbers_are_jumpers no)
		(fp_rect
			(start -0.4318 0.9525)
			(end 0.4318 -0.9525)
			(stroke
				(width 0)
				(type default)
			)
			(fill no)
			(layer "F.CrtYd")
		)
		(fp_rect
			(start -0.4318 0.9525)
			(end 0.4318 -0.9525)
			(stroke
				(width 0)
				(type default)
			)
			(fill no)
			(layer "F.Fab")
		)
		(pad "1" smd custom
			(at 0 -0.4445 90)
			(size 0.1524 0.1524)
			(layers "F.Cu" "F.Mask" "F.Paste")
			(net "P1V5_E_LL_R")
			(options
				(clearance outline)
				(anchor circle)
			)
			(primitives
				(gr_poly
					(pts
						(arc
							(start 0.3048 -0.2032)
							(mid 0.275042 -0.275042)
							(end 0.2032 -0.3048)
						)
						(arc
							(start -0.2032 -0.3048)
							(mid -0.275042 -0.275042)
							(end -0.3048 -0.2032)
						)
						(arc
							(start -0.3048 0.2032)
							(mid -0.275042 0.275042)
							(end -0.2032 0.3048)
						)
						(arc
							(start 0.2032 0.3048)
							(mid 0.275042 0.275042)
							(end 0.3048 0.2032)
						)
					)
					(width 0)
					(fill yes)
				)
			)
		)
		(pad "2" smd custom
			(at 0 0.4445 90)
			(size 0.1524 0.1524)
			(layers "F.Cu" "F.Mask" "F.Paste")
			(net "P1V5_E_VFB")
			(options
				(clearance outline)
				(anchor circle)
			)
			(primitives
				(gr_poly
					(pts
						(arc
							(start 0.3048 -0.2032)
							(mid 0.275042 -0.275042)
							(end 0.2032 -0.3048)
						)
						(arc
							(start -0.2032 -0.3048)
							(mid -0.275042 -0.275042)
							(end -0.3048 -0.2032)
						)
						(arc
							(start -0.3048 0.2032)
							(mid -0.275042 0.275042)
							(end -0.2032 0.3048)
						)
						(arc
							(start 0.2032 0.3048)
							(mid 0.275042 0.275042)
							(end 0.3048 0.2032)
						)
					)
					(width 0)
					(fill yes)
				)
			)
		)
	)
	(footprint ""
		(layer "F.Cu")
		(at 160.274 -75.969114 90)
		(property "Reference" "C521"
			(at 0 0 90)
			(layer "F.SilkS")
			(hide yes)
			(effects
				(font
					(size 1.27 1.27)
				)
			)
		)
		(property "Value" "SCD1U16V2KX-3GP"
			(at 1.1811 -2.7051 90)
			(unlocked yes)
			(layer "F.Fab")
			(hide yes)
			(effects
				(font
					(size 1.016 1.016)
					(thickness 0.1524)
				)
			)
		)
		(property "Device Type" "C402H22"
			(at 1.1811 -4.2291 90)
			(unlocked yes)
			(layer "F.Fab")
			(hide yes)
			(effects
				(font
					(size 1.016 1.016)
					(thickness 0.1524)
				)
			)
		)
		(duplicate_pad_numbers_are_jumpers no)
		(fp_rect
			(start -0.4318 0.9525)
			(end 0.4318 -0.9525)
			(stroke
				(width 0)
				(type default)
			)
			(fill no)
			(layer "F.CrtYd")
		)
		(fp_rect
			(start -0.4318 0.9525)
			(end 0.4318 -0.9525)
			(stroke
				(width 0)
				(type default)
			)
			(fill no)
			(layer "F.Fab")
		)
		(pad "1" smd custom
			(at 0 -0.4445 90)
			(size 0.1524 0.1524)
			(layers "F.Cu" "F.Mask" "F.Paste")
			(net "P3V3")
			(options
				(clearance outline)
				(anchor circle)
			)
			(primitives
				(gr_poly
					(pts
						(arc
							(start 0.3048 -0.2032)
							(mid 0.275042 -0.275042)
							(end 0.2032 -0.3048)
						)
						(arc
							(start -0.2032 -0.3048)
							(mid -0.275042 -0.275042)
							(end -0.3048 -0.2032)
						)
						(arc
							(start -0.3048 0.2032)
							(mid -0.275042 0.275042)
							(end -0.2032 0.3048)
						)
						(arc
							(start 0.2032 0.3048)
							(mid 0.275042 0.275042)
							(end 0.3048 0.2032)
						)
					)
					(width 0)
					(fill yes)
				)
			)
		)
		(pad "2" smd custom
			(at 0 0.4445 90)
			(size 0.1524 0.1524)
			(layers "F.Cu" "F.Mask" "F.Paste")
			(net "GND")
			(options
				(clearance outline)
				(anchor circle)
			)
			(primitives
				(gr_poly
					(pts
						(arc
							(start 0.3048 -0.2032)
							(mid 0.275042 -0.275042)
							(end 0.2032 -0.3048)
						)
						(arc
							(start -0.2032 -0.3048)
							(mid -0.275042 -0.275042)
							(end -0.3048 -0.2032)
						)
						(arc
							(start -0.3048 0.2032)
							(mid -0.275042 0.275042)
							(end -0.2032 0.3048)
						)
						(arc
							(start 0.2032 0.3048)
							(mid 0.275042 0.275042)
							(end 0.3048 0.2032)
						)
					)
					(width 0)
					(fill yes)
				)
			)
		)
	)
	(footprint ""
		(layer "F.Cu")
		(at 75.311 -62.2681 180)
		(property "Reference" "C263"
			(at 0 0 180)
			(layer "F.SilkS")
			(hide yes)
			(effects
				(font
					(size 1.27 1.27)
				)
			)
		)
		(property "Value" "SC22U6D3V3MX-9-GP-U"
			(at 0 -2.8194 180)
			(unlocked yes)
			(layer "F.Fab")
			(hide yes)
			(effects
				(font
					(size 1.016 1.016)
					(thickness 0.1524)
				)
			)
		)
		(property "Device Type" "C603H40"
			(at 0 -4.3434 180)
			(unlocked yes)
			(layer "F.Fab")
			(hide yes)
			(effects
				(font
					(size 1.016 1.016)
					(thickness 0.1524)
				)
			)
		)
		(duplicate_pad_numbers_are_jumpers no)
		(fp_line
			(start 0.508 0)
			(end -0.508 0)
			(stroke
				(width 0.2032)
				(type default)
			)
			(layer "F.SilkS")
		)
		(fp_rect
			(start -0.5842 1.3335)
			(end 0.5842 -1.3335)
			(stroke
				(width 0)
				(type default)
			)
			(fill no)
			(layer "F.CrtYd")
		)
		(fp_rect
			(start -0.5842 1.3335)
			(end 0.5842 -1.3335)
			(stroke
				(width 0)
				(type default)
			)
			(fill no)
			(layer "F.Fab")
		)
		(pad "1" smd custom
			(at 0 -0.762 180)
			(size 0.2159 0.2159)
			(layers "F.Cu" "F.Mask" "F.Paste")
			(net "GB_VDDA")
			(options
				(clearance outline)
				(anchor circle)
			)
			(primitives
				(gr_poly
					(pts
						(arc
							(start -0.3302 -0.4318)
							(mid -0.402042 -0.402042)
							(end -0.4318 -0.3302)
						)
						(arc
							(start -0.4318 0.3302)
							(mid -0.402042 0.402042)
							(end -0.3302 0.4318)
						)
						(arc
							(start 0.3302 0.4318)
							(mid 0.402042 0.402042)
							(end 0.4318 0.3302)
						)
						(arc
							(start 0.4318 -0.3302)
							(mid 0.402042 -0.402042)
							(end 0.3302 -0.4318)
						)
					)
					(width 0)
					(fill yes)
				)
			)
		)
		(pad "2" smd custom
			(at 0 0.762 180)
			(size 0.2159 0.2159)
			(layers "F.Cu" "F.Mask" "F.Paste")
			(net "GND")
			(options
				(clearance outline)
				(anchor circle)
			)
			(primitives
				(gr_poly
					(pts
						(arc
							(start -0.3302 -0.4318)
							(mid -0.402042 -0.402042)
							(end -0.4318 -0.3302)
						)
						(arc
							(start -0.4318 0.3302)
							(mid -0.402042 0.402042)
							(end -0.3302 0.4318)
						)
						(arc
							(start 0.3302 0.4318)
							(mid 0.402042 0.402042)
							(end 0.4318 0.3302)
						)
						(arc
							(start 0.4318 -0.3302)
							(mid 0.402042 -0.402042)
							(end 0.3302 -0.4318)
						)
					)
					(width 0)
					(fill yes)
				)
			)
		)
	)
	(footprint ""
		(layer "F.Cu")
		(at 71.612252 -78.140306 180)
		(property "Reference" "U122"
			(at 0 0 180)
			(layer "F.SilkS")
			(hide yes)
			(effects
				(font
					(size 1.27 1.27)
				)
			)
		)
		(property "Value" "NX3L1G66GW-GP"
			(at -2.3368 -8.6868 180)
			(unlocked yes)
			(layer "F.Fab")
			(hide yes)
			(effects
				(font
					(size 1.016 1.016)
					(thickness 0.1524)
				)
			)
		)
		(property "Device Type" "SC70-5H44"
			(at -2.3114 -10.414 180)
			(unlocked yes)
			(layer "F.Fab")
			(hide yes)
			(effects
				(font
					(size 1.016 1.016)
					(thickness 0.1524)
				)
			)
		)
		(duplicate_pad_numbers_are_jumpers no)
		(fp_line
			(start 1.3843 -1.8034)
			(end 1.3843 -1.1176)
			(stroke
				(width 0.3302)
				(type default)
			)
			(layer "F.SilkS")
		)
		(fp_line
			(start 1.27 1.7018)
			(end -1.27 1.7018)
			(stroke
				(width 0.1524)
				(type default)
			)
			(layer "F.SilkS")
		)
		(fp_line
			(start 1.27 -1.7018)
			(end 1.27 1.7018)
			(stroke
				(width 0.1524)
				(type default)
			)
			(layer "F.SilkS")
		)
		(fp_line
			(start 0.6604 -1.8034)
			(end 1.3843 -1.8034)
			(stroke
				(width 0.3302)
				(type default)
			)
			(layer "F.SilkS")
		)
		(fp_line
			(start -1.27 1.7018)
			(end -1.27 -1.7018)
			(stroke
				(width 0.1524)
				(type default)
			)
			(layer "F.SilkS")
		)
		(fp_line
			(start -1.27 -1.7018)
			(end 1.27 -1.7018)
			(stroke
				(width 0.1524)
				(type default)
			)
			(layer "F.SilkS")
		)
		(fp_rect
			(start -1.524 1.9558)
			(end 1.524 -1.9558)
			(stroke
				(width 0)
				(type default)
			)
			(fill no)
			(layer "F.CrtYd")
		)
		(fp_poly
			(pts
				(xy -1.524 -1.9558) (xy 1.524 -1.9558) (xy 1.524 1.9558) (xy -1.524 1.9558)
			)
			(stroke
				(width 0)
				(type default)
			)
			(fill no)
			(layer "F.Fab")
		)
		(pad "1" smd rect
			(at 0.65024 -0.8255 180)
			(size 0.4064 1.2192)
			(layers "F.Cu" "F.Mask" "F.Paste")
			(net "I2C_EXP_IOC_SDA8")
		)
		(pad "2" smd rect
			(at 0 -0.8255 180)
			(size 0.4064 1.2192)
			(layers "F.Cu" "F.Mask" "F.Paste")
			(net "I2C_IOC_4_R_SDA")
		)
		(pad "3" smd rect
			(at -0.65024 -0.8255 180)
			(size 0.4064 1.2192)
			(layers "F.Cu" "F.Mask" "F.Paste")
			(net "GND")
		)
		(pad "4" smd rect
			(at -0.65024 0.8255 180)
			(size 0.4064 1.2192)
			(layers "F.Cu" "F.Mask" "F.Paste")
			(net "PCIE_COMP_TO_SCC_RST_R_0")
		)
		(pad "5" smd rect
			(at 0.65024 0.8255 180)
			(size 0.4064 1.2192)
			(layers "F.Cu" "F.Mask" "F.Paste")
			(net "U122_VCC")
		)
	)
	(footprint ""
		(layer "F.Cu")
		(at 70.485 -37.465 90)
		(property "Reference" "L11"
			(at 0 0 90)
			(layer "F.SilkS")
			(hide yes)
			(effects
				(font
					(size 1.27 1.27)
				)
			)
		)
		(property "Value" "MPZ2012S300AT-GP"
			(at 0 -4.2418 90)
			(unlocked yes)
			(layer "F.Fab")
			(hide yes)
			(effects
				(font
					(size 1.016 1.016)
					(thickness 0.1524)
				)
			)
		)
		(property "Device Type" "L805H42"
			(at 0 -5.7912 90)
			(unlocked yes)
			(layer "F.Fab")
			(hide yes)
			(effects
				(font
					(size 1.016 1.016)
					(thickness 0.1524)
				)
			)
		)
		(duplicate_pad_numbers_are_jumpers no)
		(fp_line
			(start 0.889 -1.7018)
			(end 0.889 1.7018)
			(stroke
				(width 0.1524)
				(type default)
			)
			(layer "F.SilkS")
		)
		(fp_line
			(start -0.889 -1.7018)
			(end 0.889 -1.7018)
			(stroke
				(width 0.1524)
				(type default)
			)
			(layer "F.SilkS")
		)
		(fp_line
			(start 0.889 1.7018)
			(end -0.889 1.7018)
			(stroke
				(width 0.1524)
				(type default)
			)
			(layer "F.SilkS")
		)
		(fp_line
			(start -0.889 1.7018)
			(end -0.889 -1.7018)
			(stroke
				(width 0.1524)
				(type default)
			)
			(layer "F.SilkS")
		)
		(fp_rect
			(start -0.9652 1.778)
			(end 0.9652 -1.778)
			(stroke
				(width 0)
				(type default)
			)
			(fill no)
			(layer "F.CrtYd")
		)
		(fp_rect
			(start -0.9652 1.778)
			(end 0.9652 -1.778)
			(stroke
				(width 0)
				(type default)
			)
			(fill no)
			(layer "F.Fab")
		)
		(pad "1" smd rect
			(at 0 -0.9652 90)
			(size 1.397 1.143)
			(layers "F.Cu" "F.Mask" "F.Paste")
			(net "P0V9")
		)
		(pad "2" smd rect
			(at 0 0.9652 90)
			(size 1.397 1.143)
			(layers "F.Cu" "F.Mask" "F.Paste")
			(net "GB_VDDA")
		)
	)
	(footprint ""
		(layer "F.Cu")
		(at 146.249898 -47.0408 102)
		(property "Reference" "C339"
			(at 0 0 102)
			(layer "F.SilkS")
			(hide yes)
			(effects
				(font
					(size 1.27 1.27)
				)
			)
		)
		(property "Value" "SCD01U16V1KX-GP"
			(at -2.832048 -1.739777 102)
			(unlocked yes)
			(layer "F.Fab")
			(hide yes)
			(effects
				(font
					(size 1.016 1.016)
					(thickness 0.1524)
				)
			)
		)
		(property "Device Type" "C0201H13"
			(at -2.831925 -3.263781 102)
			(unlocked yes)
			(layer "F.Fab")
			(hide yes)
			(effects
				(font
					(size 1.016 1.016)
					(thickness 0.1524)
				)
			)
		)
		(duplicate_pad_numbers_are_jumpers no)
		(fp_poly
			(pts
				(xy -0.279454 -0.647706) (xy 0.279346 -0.647706) (xy 0.279346 0.647694) (xy -0.279454 0.647694)
			)
			(stroke
				(width 0)
				(type default)
			)
			(fill no)
			(layer "F.CrtYd")
		)
		(fp_poly
			(pts
				(xy -0.279454 -0.647706) (xy 0.279346 -0.647706) (xy 0.279346 0.647694) (xy -0.279454 0.647694)
			)
			(stroke
				(width 0)
				(type default)
			)
			(fill no)
			(layer "F.Fab")
		)
		(pad "1" smd custom
			(at -0.000001 -0.2794 102)
			(size 0.0762 0.0762)
			(layers "F.Cu" "F.Mask" "F.Paste")
			(net "PHY_SCC_TO_IOC_45_DP")
			(options
				(clearance outline)
				(anchor circle)
			)
			(primitives
				(gr_poly
					(pts
						(arc
							(start 0.1524 -0.127)
							(mid 0.137521 -0.162921)
							(end 0.1016 -0.1778)
						)
						(arc
							(start -0.1016 -0.1778)
							(mid -0.137521 -0.162921)
							(end -0.1524 -0.127)
						)
						(arc
							(start -0.1524 0.127)
							(mid -0.137521 0.162921)
							(end -0.1016 0.1778)
						)
						(arc
							(start 0.1016 0.1778)
							(mid 0.137521 0.162921)
							(end 0.1524 0.127)
						)
					)
					(width 0)
					(fill yes)
				)
			)
		)
		(pad "2" smd custom
			(at 0.000001 0.2794 102)
			(size 0.0762 0.0762)
			(layers "F.Cu" "F.Mask" "F.Paste")
			(net "PHY_SCC_TO_IOC_C_45_DP")
			(options
				(clearance outline)
				(anchor circle)
			)
			(primitives
				(gr_poly
					(pts
						(arc
							(start 0.1524 -0.127)
							(mid 0.137521 -0.162921)
							(end 0.1016 -0.1778)
						)
						(arc
							(start -0.1016 -0.1778)
							(mid -0.137521 -0.162921)
							(end -0.1524 -0.127)
						)
						(arc
							(start -0.1524 0.127)
							(mid -0.137521 0.162921)
							(end -0.1016 0.1778)
						)
						(arc
							(start 0.1016 0.1778)
							(mid 0.137521 0.162921)
							(end 0.1524 0.127)
						)
					)
					(width 0)
					(fill yes)
				)
			)
		)
	)
	(footprint ""
		(layer "F.Cu")
		(at 174.314866 -23.556976 90)
		(property "Reference" "VIA5"
			(at 0 0 90)
			(layer "F.SilkS")
			(hide yes)
			(effects
				(font
					(size 1.27 1.27)
				)
			)
		)
		(property "Value" "85OHM-8L-1D6MM-L16L18-GP"
			(at 4.064 0.6096 90)
			(unlocked yes)
			(layer "F.Fab")
			(hide yes)
			(effects
				(font
					(size 1.016 1.016)
					(thickness 0.1524)
				)
			)
		)
		(property "Device Type" "VIA-PCIE-4P-368076"
			(at 4.064 -0.9144 90)
			(unlocked yes)
			(layer "F.Fab")
			(hide yes)
			(effects
				(font
					(size 1.016 1.016)
					(thickness 0.1524)
				)
			)
		)
		(duplicate_pad_numbers_are_jumpers no)
		(fp_rect
			(start -1.8415 0.381)
			(end 1.8415 -0.381)
			(stroke
				(width 0)
				(type default)
			)
			(fill no)
			(layer "F.CrtYd")
		)
		(fp_rect
			(start -1.8415 0.381)
			(end 1.8415 -0.381)
			(stroke
				(width 0)
				(type default)
			)
			(fill no)
			(layer "F.Fab")
		)
		(pad "1" thru_hole circle
			(at -1.4605 0 90)
			(size 0.508 0.508)
			(drill 0.254)
			(layers "*.Cu" "*.Mask")
			(remove_unused_layers no)
			(net "GND")
			(clearance 0.127)
			(thermal_gap 0.127)
		)
		(pad "2" thru_hole circle
			(at -0.4445 0 90)
			(size 0.508 0.508)
			(drill 0.254)
			(layers "*.Cu" "*.Mask")
			(remove_unused_layers no)
			(net "PCIE_COMP_TO_SCC_4_DP")
			(clearance 0.127)
			(thermal_gap 0.127)
		)
		(pad "3" thru_hole circle
			(at 0.4445 0 90)
			(size 0.508 0.508)
			(drill 0.254)
			(layers "*.Cu" "*.Mask")
			(remove_unused_layers no)
			(net "PCIE_COMP_TO_SCC_4_DN")
			(clearance 0.127)
			(thermal_gap 0.127)
		)
		(pad "4" thru_hole circle
			(at 1.4605 0 90)
			(size 0.508 0.508)
			(drill 0.254)
			(layers "*.Cu" "*.Mask")
			(remove_unused_layers no)
			(net "GND")
			(clearance 0.127)
			(thermal_gap 0.127)
		)
	)
	(footprint ""
		(layer "F.Cu")
		(at 165.273736 -56.29402)
		(property "Reference" "TP125"
			(at 0 0 0)
			(layer "F.SilkS")
			(hide yes)
			(effects
				(font
					(size 1.27 1.27)
				)
			)
		)
		(property "Value" "TPAD28-2-GP"
			(at -0.0127 -1.6637 0)
			(unlocked yes)
			(layer "F.Fab")
			(hide yes)
			(effects
				(font
					(size 1.016 1.016)
					(thickness 0.1524)
				)
			)
		)
		(property "Device Type" "TPAD28"
			(at -0.0127 -3.1877 0)
			(unlocked yes)
			(layer "F.Fab")
			(hide yes)
			(effects
				(font
					(size 1.016 1.016)
					(thickness 0.1524)
				)
			)
		)
		(duplicate_pad_numbers_are_jumpers no)
		(fp_poly
			(pts
				(arc
					(start 0.3556 0)
					(mid -0.3556 0)
					(end 0.3556 0)
				)
			)
			(stroke
				(width 0)
				(type default)
			)
			(fill no)
			(layer "F.CrtYd")
		)
		(fp_poly
			(pts
				(arc
					(start 0.6096 0)
					(mid -0.6096 0)
					(end 0.6096 0)
				)
			)
			(stroke
				(width 0)
				(type default)
			)
			(fill no)
			(layer "F.Fab")
		)
		(pad "1" smd circle
			(at 0 0)
			(size 0.7112 0.7112)
			(layers "F.Cu" "F.Mask" "F.Paste")
			(net "ICE1_TMS")
		)
	)
	(footprint ""
		(layer "F.Cu")
		(at 62.61862 -17.408144)
		(property "Reference" "R576"
			(at 0 0 0)
			(layer "F.SilkS")
			(hide yes)
			(effects
				(font
					(size 1.27 1.27)
				)
			)
		)
		(property "Value" "0R2J-2-GP"
			(at 0.064008 -3.993896 0)
			(unlocked yes)
			(layer "F.Fab")
			(hide yes)
			(effects
				(font
					(size 1.016 1.016)
					(thickness 0.1524)
				)
			)
		)
		(property "Device Type" "R402H16"
			(at 0.064008 -5.517896 0)
			(unlocked yes)
			(layer "F.Fab")
			(hide yes)
			(effects
				(font
					(size 1.016 1.016)
					(thickness 0.1524)
				)
			)
		)
		(duplicate_pad_numbers_are_jumpers no)
		(fp_line
			(start -0.508 -0.9398)
			(end -0.508 0.9398)
			(stroke
				(width 0.1524)
				(type default)
			)
			(layer "F.SilkS")
		)
		(fp_line
			(start 0.508 -0.9398)
			(end -0.508 -0.9398)
			(stroke
				(width 0.1524)
				(type default)
			)
			(layer "F.SilkS")
		)
		(fp_rect
			(start -0.508 0.9398)
			(end 0.508 -0.9398)
			(stroke
				(width 0)
				(type default)
			)
			(fill no)
			(layer "F.CrtYd")
		)
		(fp_rect
			(start -0.508 0.9398)
			(end 0.508 -0.9398)
			(stroke
				(width 0)
				(type default)
			)
			(fill no)
			(layer "F.Fab")
		)
		(pad "1" smd custom
			(at 0 -0.4445)
			(size 0.1397 0.1397)
			(layers "F.Cu" "F.Mask" "F.Paste")
			(net "SCC_STBY_PGOOD_U49")
			(options
				(clearance outline)
				(anchor circle)
			)
			(primitives
				(gr_poly
					(pts
						(arc
							(start -0.1778 -0.2794)
							(mid -0.249642 -0.249642)
							(end -0.2794 -0.1778)
						)
						(arc
							(start -0.2794 0.1778)
							(mid -0.249642 0.249642)
							(end -0.1778 0.2794)
						)
						(arc
							(start 0.1778 0.2794)
							(mid 0.249642 0.249642)
							(end 0.2794 0.1778)
						)
						(arc
							(start 0.2794 -0.1778)
							(mid 0.249642 -0.249642)
							(end 0.1778 -0.2794)
						)
					)
					(width 0)
					(fill yes)
				)
			)
		)
		(pad "2" smd custom
			(at 0 0.4445)
			(size 0.1397 0.1397)
			(layers "F.Cu" "F.Mask" "F.Paste")
			(net "SCC_STBY_PGOOD")
			(options
				(clearance outline)
				(anchor circle)
			)
			(primitives
				(gr_poly
					(pts
						(arc
							(start -0.1778 -0.2794)
							(mid -0.249642 -0.249642)
							(end -0.2794 -0.1778)
						)
						(arc
							(start -0.2794 0.1778)
							(mid -0.249642 0.249642)
							(end -0.1778 0.2794)
						)
						(arc
							(start 0.1778 0.2794)
							(mid 0.249642 0.249642)
							(end 0.2794 0.1778)
						)
						(arc
							(start 0.2794 -0.1778)
							(mid 0.249642 -0.249642)
							(end 0.1778 -0.2794)
						)
					)
					(width 0)
					(fill yes)
				)
			)
		)
	)
	(footprint ""
		(layer "F.Cu")
		(at 177.5206 -122.7836 90)
		(property "Reference" "R84"
			(at 0 0 90)
			(layer "F.SilkS")
			(hide yes)
			(effects
				(font
					(size 1.27 1.27)
				)
			)
		)
		(property "Value" "0R5J-5-GP"
			(at 0 -8.9535 90)
			(unlocked yes)
			(layer "F.Fab")
			(hide yes)
			(effects
				(font
					(size 1.27 1.016)
					(thickness 0.1524)
				)
			)
		)
		(property "Device Type" "R805H24"
			(at 0 -10.6299 90)
			(unlocked yes)
			(layer "F.Fab")
			(hide yes)
			(effects
				(font
					(size 1.27 1.016)
					(thickness 0.1524)
				)
			)
		)
		(duplicate_pad_numbers_are_jumpers no)
		(fp_line
			(start 0.889 -1.7018)
			(end -0.889 -1.7018)
			(stroke
				(width 0.1524)
				(type default)
			)
			(layer "F.SilkS")
		)
		(fp_line
			(start 0.889 -1.7018)
			(end 0.889 -0.381)
			(stroke
				(width 0.1524)
				(type default)
			)
			(layer "F.SilkS")
		)
		(fp_line
			(start -0.889 -1.7018)
			(end -0.889 0.2794)
			(stroke
				(width 0.1524)
				(type default)
			)
			(layer "F.SilkS")
		)
		(fp_line
			(start -0.889 0.0762)
			(end -0.889 1.7018)
			(stroke
				(width 0.1524)
				(type default)
			)
			(layer "F.SilkS")
		)
		(fp_line
			(start 0.889 1.7018)
			(end 0.889 -0.508)
			(stroke
				(width 0.1524)
				(type default)
			)
			(layer "F.SilkS")
		)
		(fp_line
			(start -0.889 1.7018)
			(end 0.889 1.7018)
			(stroke
				(width 0.1524)
				(type default)
			)
			(layer "F.SilkS")
		)
		(fp_poly
			(pts
				(xy 0.9652 -1.778) (xy 0.9652 1.778) (xy -0.9652 1.778) (xy -0.9652 -1.778)
			)
			(stroke
				(width 0)
				(type default)
			)
			(fill no)
			(layer "F.CrtYd")
		)
		(fp_rect
			(start -0.9652 1.778)
			(end 0.9652 -1.778)
			(stroke
				(width 0)
				(type default)
			)
			(fill no)
			(layer "F.Fab")
		)
		(pad "1" smd rect
			(at 0 -0.9652 90)
			(size 1.397 1.143)
			(layers "F.Cu" "F.Mask" "F.Paste")
			(net "P1V8_E")
		)
		(pad "2" smd rect
			(at 0 0.9652 90)
			(size 1.397 1.143)
			(layers "F.Cu" "F.Mask" "F.Paste")
			(net "P1V8_E_OUT")
		)
	)
	(footprint ""
		(layer "F.Cu")
		(at 148.315172 -54.99735 102)
		(property "Reference" "C343"
			(at 0 0 102)
			(layer "F.SilkS")
			(hide yes)
			(effects
				(font
					(size 1.27 1.27)
				)
			)
		)
		(property "Value" "SCD01U16V1KX-GP"
			(at -2.832048 -1.739777 102)
			(unlocked yes)
			(layer "F.Fab")
			(hide yes)
			(effects
				(font
					(size 1.016 1.016)
					(thickness 0.1524)
				)
			)
		)
		(property "Device Type" "C0201H13"
			(at -2.831925 -3.263781 102)
			(unlocked yes)
			(layer "F.Fab")
			(hide yes)
			(effects
				(font
					(size 1.016 1.016)
					(thickness 0.1524)
				)
			)
		)
		(duplicate_pad_numbers_are_jumpers no)
		(fp_poly
			(pts
				(xy -0.279454 -0.647706) (xy 0.279346 -0.647706) (xy 0.279346 0.647694) (xy -0.279454 0.647694)
			)
			(stroke
				(width 0)
				(type default)
			)
			(fill no)
			(layer "F.CrtYd")
		)
		(fp_poly
			(pts
				(xy -0.279454 -0.647706) (xy 0.279346 -0.647706) (xy 0.279346 0.647694) (xy -0.279454 0.647694)
			)
			(stroke
				(width 0)
				(type default)
			)
			(fill no)
			(layer "F.Fab")
		)
		(pad "1" smd custom
			(at -0.000001 -0.2794 102)
			(size 0.0762 0.0762)
			(layers "F.Cu" "F.Mask" "F.Paste")
			(net "PHY_SCC_TO_IOC_47_DP")
			(options
				(clearance outline)
				(anchor circle)
			)
			(primitives
				(gr_poly
					(pts
						(arc
							(start 0.1524 -0.127)
							(mid 0.137521 -0.162921)
							(end 0.1016 -0.1778)
						)
						(arc
							(start -0.1016 -0.1778)
							(mid -0.137521 -0.162921)
							(end -0.1524 -0.127)
						)
						(arc
							(start -0.1524 0.127)
							(mid -0.137521 0.162921)
							(end -0.1016 0.1778)
						)
						(arc
							(start 0.1016 0.1778)
							(mid 0.137521 0.162921)
							(end 0.1524 0.127)
						)
					)
					(width 0)
					(fill yes)
				)
			)
		)
		(pad "2" smd custom
			(at 0.000001 0.2794 102)
			(size 0.0762 0.0762)
			(layers "F.Cu" "F.Mask" "F.Paste")
			(net "PHY_SCC_TO_IOC_C_47_DP")
			(options
				(clearance outline)
				(anchor circle)
			)
			(primitives
				(gr_poly
					(pts
						(arc
							(start 0.1524 -0.127)
							(mid 0.137521 -0.162921)
							(end 0.1016 -0.1778)
						)
						(arc
							(start -0.1016 -0.1778)
							(mid -0.137521 -0.162921)
							(end -0.1524 -0.127)
						)
						(arc
							(start -0.1524 0.127)
							(mid -0.137521 0.162921)
							(end -0.1016 0.1778)
						)
						(arc
							(start 0.1016 0.1778)
							(mid 0.137521 0.162921)
							(end 0.1524 0.127)
						)
					)
					(width 0)
					(fill yes)
				)
			)
		)
	)
	(footprint ""
		(layer "F.Cu")
		(at 85.8266 -108.204 180)
		(property "Reference" "C731"
			(at 0 0 180)
			(layer "F.SilkS")
			(hide yes)
			(effects
				(font
					(size 1.27 1.27)
				)
			)
		)
		(property "Value" "SCD1U16V2KX-3GP"
			(at 1.1811 -2.7051 180)
			(unlocked yes)
			(layer "F.Fab")
			(hide yes)
			(effects
				(font
					(size 1.016 1.016)
					(thickness 0.1524)
				)
			)
		)
		(property "Device Type" "C402H22"
			(at 1.1811 -4.2291 180)
			(unlocked yes)
			(layer "F.Fab")
			(hide yes)
			(effects
				(font
					(size 1.016 1.016)
					(thickness 0.1524)
				)
			)
		)
		(duplicate_pad_numbers_are_jumpers no)
		(fp_rect
			(start -0.4318 0.9525)
			(end 0.4318 -0.9525)
			(stroke
				(width 0)
				(type default)
			)
			(fill no)
			(layer "F.CrtYd")
		)
		(fp_rect
			(start -0.4318 0.9525)
			(end 0.4318 -0.9525)
			(stroke
				(width 0)
				(type default)
			)
			(fill no)
			(layer "F.Fab")
		)
		(pad "1" smd custom
			(at 0 -0.4445 180)
			(size 0.1524 0.1524)
			(layers "F.Cu" "F.Mask" "F.Paste")
			(net "P3V3")
			(options
				(clearance outline)
				(anchor circle)
			)
			(primitives
				(gr_poly
					(pts
						(arc
							(start 0.3048 -0.2032)
							(mid 0.275042 -0.275042)
							(end 0.2032 -0.3048)
						)
						(arc
							(start -0.2032 -0.3048)
							(mid -0.275042 -0.275042)
							(end -0.3048 -0.2032)
						)
						(arc
							(start -0.3048 0.2032)
							(mid -0.275042 0.275042)
							(end -0.2032 0.3048)
						)
						(arc
							(start 0.2032 0.3048)
							(mid 0.275042 0.275042)
							(end 0.3048 0.2032)
						)
					)
					(width 0)
					(fill yes)
				)
			)
		)
		(pad "2" smd custom
			(at 0 0.4445 180)
			(size 0.1524 0.1524)
			(layers "F.Cu" "F.Mask" "F.Paste")
			(net "GND")
			(options
				(clearance outline)
				(anchor circle)
			)
			(primitives
				(gr_poly
					(pts
						(arc
							(start 0.3048 -0.2032)
							(mid 0.275042 -0.275042)
							(end 0.2032 -0.3048)
						)
						(arc
							(start -0.2032 -0.3048)
							(mid -0.275042 -0.275042)
							(end -0.3048 -0.2032)
						)
						(arc
							(start -0.3048 0.2032)
							(mid -0.275042 0.275042)
							(end -0.2032 0.3048)
						)
						(arc
							(start 0.2032 0.3048)
							(mid 0.275042 0.275042)
							(end 0.3048 0.2032)
						)
					)
					(width 0)
					(fill yes)
				)
			)
		)
	)
	(footprint ""
		(layer "F.Cu")
		(at 168.732454 -8.52551 180)
		(property "Reference" "R80"
			(at 0 0 180)
			(layer "F.SilkS")
			(hide yes)
			(effects
				(font
					(size 1.27 1.27)
				)
			)
		)
		(property "Value" "0R2J-2-GP"
			(at 0.064008 -3.993896 180)
			(unlocked yes)
			(layer "F.Fab")
			(hide yes)
			(effects
				(font
					(size 1.016 1.016)
					(thickness 0.1524)
				)
			)
		)
		(property "Device Type" "R402H16"
			(at 0.064008 -5.517896 180)
			(unlocked yes)
			(layer "F.Fab")
			(hide yes)
			(effects
				(font
					(size 1.016 1.016)
					(thickness 0.1524)
				)
			)
		)
		(duplicate_pad_numbers_are_jumpers no)
		(fp_line
			(start 0.508 -0.9398)
			(end -0.508 -0.9398)
			(stroke
				(width 0.1524)
				(type default)
			)
			(layer "F.SilkS")
		)
		(fp_line
			(start -0.508 -0.9398)
			(end -0.508 0.9398)
			(stroke
				(width 0.1524)
				(type default)
			)
			(layer "F.SilkS")
		)
		(fp_rect
			(start -0.508 0.9398)
			(end 0.508 -0.9398)
			(stroke
				(width 0)
				(type default)
			)
			(fill no)
			(layer "F.CrtYd")
		)
		(fp_rect
			(start -0.508 0.9398)
			(end 0.508 -0.9398)
			(stroke
				(width 0)
				(type default)
			)
			(fill no)
			(layer "F.Fab")
		)
		(pad "1" smd custom
			(at 0 -0.4445 180)
			(size 0.1397 0.1397)
			(layers "F.Cu" "F.Mask" "F.Paste")
			(net "LS_EN_U12")
			(options
				(clearance outline)
				(anchor circle)
			)
			(primitives
				(gr_poly
					(pts
						(arc
							(start -0.1778 -0.2794)
							(mid -0.249642 -0.249642)
							(end -0.2794 -0.1778)
						)
						(arc
							(start -0.2794 0.1778)
							(mid -0.249642 0.249642)
							(end -0.1778 0.2794)
						)
						(arc
							(start 0.1778 0.2794)
							(mid 0.249642 0.249642)
							(end 0.2794 0.1778)
						)
						(arc
							(start 0.2794 -0.1778)
							(mid 0.249642 -0.249642)
							(end 0.1778 -0.2794)
						)
					)
					(width 0)
					(fill yes)
				)
			)
		)
		(pad "2" smd custom
			(at 0 0.4445 180)
			(size 0.1397 0.1397)
			(layers "F.Cu" "F.Mask" "F.Paste")
			(net "LS_EN_N")
			(options
				(clearance outline)
				(anchor circle)
			)
			(primitives
				(gr_poly
					(pts
						(arc
							(start -0.1778 -0.2794)
							(mid -0.249642 -0.249642)
							(end -0.2794 -0.1778)
						)
						(arc
							(start -0.2794 0.1778)
							(mid -0.249642 0.249642)
							(end -0.1778 0.2794)
						)
						(arc
							(start 0.1778 0.2794)
							(mid 0.249642 0.249642)
							(end 0.2794 0.1778)
						)
						(arc
							(start 0.2794 -0.1778)
							(mid 0.249642 -0.249642)
							(end 0.1778 -0.2794)
						)
					)
					(width 0)
					(fill yes)
				)
			)
		)
	)
	(footprint ""
		(layer "F.Cu")
		(at 176.86147 -82.652108)
		(property "Reference" "C630"
			(at 0 0 0)
			(layer "F.SilkS")
			(hide yes)
			(effects
				(font
					(size 1.27 1.27)
				)
			)
		)
		(property "Value" "SC10U6D3V5KX-4GP"
			(at -0.0762 -6.1214 0)
			(unlocked yes)
			(layer "F.Fab")
			(hide yes)
			(effects
				(font
					(size 1.016 1.016)
					(thickness 0.1524)
				)
			)
		)
		(property "Device Type" "C805H58"
			(at -0.0762 -8.1534 0)
			(unlocked yes)
			(layer "F.Fab")
			(hide yes)
			(effects
				(font
					(size 1.016 1.016)
					(thickness 0.1524)
				)
			)
		)
		(duplicate_pad_numbers_are_jumpers no)
		(fp_line
			(start 0.635 0)
			(end -0.635 0)
			(stroke
				(width 0.508)
				(type default)
			)
			(layer "F.SilkS")
		)
		(fp_rect
			(start -0.9652 1.778)
			(end 0.9652 -1.778)
			(stroke
				(width 0)
				(type default)
			)
			(fill no)
			(layer "F.CrtYd")
		)
		(fp_poly
			(pts
				(xy -0.9652 -1.778) (xy 0.9652 -1.778) (xy 0.9652 1.778) (xy -0.9652 1.778)
			)
			(stroke
				(width 0)
				(type default)
			)
			(fill no)
			(layer "F.Fab")
		)
		(pad "1" smd rect
			(at 0 -0.9652)
			(size 1.397 1.143)
			(layers "F.Cu" "F.Mask" "F.Paste")
			(net "P0V975")
		)
		(pad "2" smd rect
			(at 0 0.9652)
			(size 1.397 1.143)
			(layers "F.Cu" "F.Mask" "F.Paste")
			(net "GND")
		)
	)
	(footprint ""
		(layer "F.Cu")
		(at 145.669 -100.584 180)
		(property "Reference" "C720"
			(at 0 0 180)
			(layer "F.SilkS")
			(hide yes)
			(effects
				(font
					(size 1.27 1.27)
				)
			)
		)
		(property "Value" "SC100U6D3V6MX-GP"
			(at -0.0762 -5.1308 180)
			(unlocked yes)
			(layer "F.Fab")
			(hide yes)
			(effects
				(font
					(size 1.016 1.016)
					(thickness 0.1524)
				)
			)
		)
		(property "Device Type" "C1206H71"
			(at -0.127 -6.6548 180)
			(unlocked yes)
			(layer "F.Fab")
			(hide yes)
			(effects
				(font
					(size 1.016 1.016)
					(thickness 0.1524)
				)
			)
		)
		(duplicate_pad_numbers_are_jumpers no)
		(fp_line
			(start 1.016 2.2352)
			(end -1.016 2.2352)
			(stroke
				(width 0.1524)
				(type default)
			)
			(layer "F.SilkS")
		)
		(fp_line
			(start 1.016 0.8382)
			(end 1.016 2.2352)
			(stroke
				(width 0.1524)
				(type default)
			)
			(layer "F.SilkS")
		)
		(fp_line
			(start 1.016 -2.2352)
			(end 1.016 -0.8382)
			(stroke
				(width 0.1524)
				(type default)
			)
			(layer "F.SilkS")
		)
		(fp_line
			(start -1.016 2.2352)
			(end -1.016 0.8382)
			(stroke
				(width 0.1524)
				(type default)
			)
			(layer "F.SilkS")
		)
		(fp_line
			(start -1.016 -0.8382)
			(end -1.016 -2.2352)
			(stroke
				(width 0.1524)
				(type default)
			)
			(layer "F.SilkS")
		)
		(fp_line
			(start -1.016 -2.2352)
			(end 1.016 -2.2352)
			(stroke
				(width 0.1524)
				(type default)
			)
			(layer "F.SilkS")
		)
		(fp_rect
			(start -1.0922 2.3114)
			(end 1.0922 -2.3114)
			(stroke
				(width 0)
				(type default)
			)
			(fill no)
			(layer "F.CrtYd")
		)
		(fp_poly
			(pts
				(xy 1.0922 -2.3114) (xy 1.0922 2.3114) (xy -1.0922 2.3114) (xy -1.0922 -2.3114)
			)
			(stroke
				(width 0)
				(type default)
			)
			(fill no)
			(layer "F.Fab")
		)
		(pad "1" smd rect
			(at 0 -1.397 180)
			(size 1.651 1.27)
			(layers "F.Cu" "F.Mask" "F.Paste")
			(net "GB_VDDH")
		)
		(pad "2" smd rect
			(at 0 1.397 180)
			(size 1.651 1.27)
			(layers "F.Cu" "F.Mask" "F.Paste")
			(net "GND")
		)
	)
	(footprint ""
		(layer "F.Cu")
		(at 191.516 -27.8384 -90)
		(property "Reference" "TP59"
			(at 0 0 270)
			(layer "F.SilkS")
			(hide yes)
			(effects
				(font
					(size 1.27 1.27)
				)
			)
		)
		(property "Value" "TPAD28-2-GP"
			(at -0.0127 -1.6637 270)
			(unlocked yes)
			(layer "F.Fab")
			(hide yes)
			(effects
				(font
					(size 1.016 1.016)
					(thickness 0.1524)
				)
			)
		)
		(property "Device Type" "TPAD28"
			(at -0.0127 -3.1877 270)
			(unlocked yes)
			(layer "F.Fab")
			(hide yes)
			(effects
				(font
					(size 1.016 1.016)
					(thickness 0.1524)
				)
			)
		)
		(duplicate_pad_numbers_are_jumpers no)
		(fp_poly
			(pts
				(arc
					(start 0 -0.3556)
					(mid 0 0.3556)
					(end 0 -0.3556)
				)
			)
			(stroke
				(width 0)
				(type default)
			)
			(fill no)
			(layer "F.CrtYd")
		)
		(fp_poly
			(pts
				(arc
					(start 0 -0.6096)
					(mid 0 0.6096)
					(end 0 -0.6096)
				)
			)
			(stroke
				(width 0)
				(type default)
			)
			(fill no)
			(layer "F.Fab")
		)
		(pad "1" smd circle
			(at 0 0 270)
			(size 0.7112 0.7112)
			(layers "F.Cu" "F.Mask" "F.Paste")
			(net "IOC_GPIO_4")
		)
	)
	(footprint ""
		(layer "F.Cu")
		(at 45.5422 -29.083 -90)
		(property "Reference" "C612"
			(at 0 0 270)
			(layer "F.SilkS")
			(hide yes)
			(effects
				(font
					(size 1.27 1.27)
				)
			)
		)
		(property "Value" "SCD01U25V2KX-3GP"
			(at 1.1811 -2.7051 270)
			(unlocked yes)
			(layer "F.Fab")
			(hide yes)
			(effects
				(font
					(size 1.016 1.016)
					(thickness 0.1524)
				)
			)
		)
		(property "Device Type" "C402H22"
			(at 1.1811 -4.2291 270)
			(unlocked yes)
			(layer "F.Fab")
			(hide yes)
			(effects
				(font
					(size 1.016 1.016)
					(thickness 0.1524)
				)
			)
		)
		(duplicate_pad_numbers_are_jumpers no)
		(fp_rect
			(start -0.4318 0.9525)
			(end 0.4318 -0.9525)
			(stroke
				(width 0)
				(type default)
			)
			(fill no)
			(layer "F.CrtYd")
		)
		(fp_rect
			(start -0.4318 0.9525)
			(end 0.4318 -0.9525)
			(stroke
				(width 0)
				(type default)
			)
			(fill no)
			(layer "F.Fab")
		)
		(pad "1" smd custom
			(at 0 -0.4445 270)
			(size 0.1524 0.1524)
			(layers "F.Cu" "F.Mask" "F.Paste")
			(net "P0V9_GSNS")
			(options
				(clearance outline)
				(anchor circle)
			)
			(primitives
				(gr_poly
					(pts
						(arc
							(start 0.3048 -0.2032)
							(mid 0.275042 -0.275042)
							(end 0.2032 -0.3048)
						)
						(arc
							(start -0.2032 -0.3048)
							(mid -0.275042 -0.275042)
							(end -0.3048 -0.2032)
						)
						(arc
							(start -0.3048 0.2032)
							(mid -0.275042 0.275042)
							(end -0.2032 0.3048)
						)
						(arc
							(start 0.2032 0.3048)
							(mid 0.275042 0.275042)
							(end 0.3048 0.2032)
						)
					)
					(width 0)
					(fill yes)
				)
			)
		)
		(pad "2" smd custom
			(at 0 0.4445 270)
			(size 0.1524 0.1524)
			(layers "F.Cu" "F.Mask" "F.Paste")
			(net "P0V9_REFIN")
			(options
				(clearance outline)
				(anchor circle)
			)
			(primitives
				(gr_poly
					(pts
						(arc
							(start 0.3048 -0.2032)
							(mid 0.275042 -0.275042)
							(end 0.2032 -0.3048)
						)
						(arc
							(start -0.2032 -0.3048)
							(mid -0.275042 -0.275042)
							(end -0.3048 -0.2032)
						)
						(arc
							(start -0.3048 0.2032)
							(mid -0.275042 0.275042)
							(end -0.2032 0.3048)
						)
						(arc
							(start 0.2032 0.3048)
							(mid 0.275042 0.275042)
							(end 0.3048 0.2032)
						)
					)
					(width 0)
					(fill yes)
				)
			)
		)
	)
	(footprint ""
		(layer "F.Cu")
		(at 54.9148 -80.518 90)
		(property "Reference" "C561"
			(at 0 0 90)
			(layer "F.SilkS")
			(hide yes)
			(effects
				(font
					(size 1.27 1.27)
				)
			)
		)
		(property "Value" "SCD1U16V2KX-3GP"
			(at 1.1811 -2.7051 90)
			(unlocked yes)
			(layer "F.Fab")
			(hide yes)
			(effects
				(font
					(size 1.016 1.016)
					(thickness 0.1524)
				)
			)
		)
		(property "Device Type" "C402H22"
			(at 1.1811 -4.2291 90)
			(unlocked yes)
			(layer "F.Fab")
			(hide yes)
			(effects
				(font
					(size 1.016 1.016)
					(thickness 0.1524)
				)
			)
		)
		(duplicate_pad_numbers_are_jumpers no)
		(fp_rect
			(start -0.4318 0.9525)
			(end 0.4318 -0.9525)
			(stroke
				(width 0)
				(type default)
			)
			(fill no)
			(layer "F.CrtYd")
		)
		(fp_rect
			(start -0.4318 0.9525)
			(end 0.4318 -0.9525)
			(stroke
				(width 0)
				(type default)
			)
			(fill no)
			(layer "F.Fab")
		)
		(pad "1" smd custom
			(at 0 -0.4445 90)
			(size 0.1524 0.1524)
			(layers "F.Cu" "F.Mask" "F.Paste")
			(net "P1V8_E")
			(options
				(clearance outline)
				(anchor circle)
			)
			(primitives
				(gr_poly
					(pts
						(arc
							(start 0.3048 -0.2032)
							(mid 0.275042 -0.275042)
							(end 0.2032 -0.3048)
						)
						(arc
							(start -0.2032 -0.3048)
							(mid -0.275042 -0.275042)
							(end -0.3048 -0.2032)
						)
						(arc
							(start -0.3048 0.2032)
							(mid -0.275042 0.275042)
							(end -0.2032 0.3048)
						)
						(arc
							(start 0.2032 0.3048)
							(mid 0.275042 0.275042)
							(end 0.3048 0.2032)
						)
					)
					(width 0)
					(fill yes)
				)
			)
		)
		(pad "2" smd custom
			(at 0 0.4445 90)
			(size 0.1524 0.1524)
			(layers "F.Cu" "F.Mask" "F.Paste")
			(net "GND")
			(options
				(clearance outline)
				(anchor circle)
			)
			(primitives
				(gr_poly
					(pts
						(arc
							(start 0.3048 -0.2032)
							(mid 0.275042 -0.275042)
							(end 0.2032 -0.3048)
						)
						(arc
							(start -0.2032 -0.3048)
							(mid -0.275042 -0.275042)
							(end -0.3048 -0.2032)
						)
						(arc
							(start -0.3048 0.2032)
							(mid -0.275042 0.275042)
							(end -0.2032 0.3048)
						)
						(arc
							(start 0.2032 0.3048)
							(mid 0.275042 0.275042)
							(end 0.3048 0.2032)
						)
					)
					(width 0)
					(fill yes)
				)
			)
		)
	)
	(footprint ""
		(layer "F.Cu")
		(at 134.52221 -84.246466 -90)
		(property "Reference" "R60"
			(at 0 0 270)
			(layer "F.SilkS")
			(hide yes)
			(effects
				(font
					(size 1.27 1.27)
				)
			)
		)
		(property "Value" "4K7R2F-GP"
			(at 0.064008 -3.993896 270)
			(unlocked yes)
			(layer "F.Fab")
			(hide yes)
			(effects
				(font
					(size 1.016 1.016)
					(thickness 0.1524)
				)
			)
		)
		(property "Device Type" "R402H16"
			(at 0.064008 -5.517896 270)
			(unlocked yes)
			(layer "F.Fab")
			(hide yes)
			(effects
				(font
					(size 1.016 1.016)
					(thickness 0.1524)
				)
			)
		)
		(duplicate_pad_numbers_are_jumpers no)
		(fp_line
			(start -0.508 -0.9398)
			(end -0.508 0.9398)
			(stroke
				(width 0.1524)
				(type default)
			)
			(layer "F.SilkS")
		)
		(fp_line
			(start 0.508 -0.9398)
			(end -0.508 -0.9398)
			(stroke
				(width 0.1524)
				(type default)
			)
			(layer "F.SilkS")
		)
		(fp_rect
			(start -0.508 0.9398)
			(end 0.508 -0.9398)
			(stroke
				(width 0)
				(type default)
			)
			(fill no)
			(layer "F.CrtYd")
		)
		(fp_rect
			(start -0.508 0.9398)
			(end 0.508 -0.9398)
			(stroke
				(width 0)
				(type default)
			)
			(fill no)
			(layer "F.Fab")
		)
		(pad "1" smd custom
			(at 0 -0.4445 270)
			(size 0.1397 0.1397)
			(layers "F.Cu" "F.Mask" "F.Paste")
			(net "P1V8_E")
			(options
				(clearance outline)
				(anchor circle)
			)
			(primitives
				(gr_poly
					(pts
						(arc
							(start -0.1778 -0.2794)
							(mid -0.249642 -0.249642)
							(end -0.2794 -0.1778)
						)
						(arc
							(start -0.2794 0.1778)
							(mid -0.249642 0.249642)
							(end -0.1778 0.2794)
						)
						(arc
							(start 0.1778 0.2794)
							(mid 0.249642 0.249642)
							(end 0.2794 0.1778)
						)
						(arc
							(start 0.2794 -0.1778)
							(mid 0.249642 -0.249642)
							(end 0.1778 -0.2794)
						)
					)
					(width 0)
					(fill yes)
				)
			)
		)
		(pad "2" smd custom
			(at 0 0.4445 270)
			(size 0.1397 0.1397)
			(layers "F.Cu" "F.Mask" "F.Paste")
			(net "I2C_DRIVE_FLT_LED_SCL6_LS")
			(options
				(clearance outline)
				(anchor circle)
			)
			(primitives
				(gr_poly
					(pts
						(arc
							(start -0.1778 -0.2794)
							(mid -0.249642 -0.249642)
							(end -0.2794 -0.1778)
						)
						(arc
							(start -0.2794 0.1778)
							(mid -0.249642 0.249642)
							(end -0.1778 0.2794)
						)
						(arc
							(start 0.1778 0.2794)
							(mid 0.249642 0.249642)
							(end 0.2794 0.1778)
						)
						(arc
							(start 0.2794 -0.1778)
							(mid 0.249642 -0.249642)
							(end 0.1778 -0.2794)
						)
					)
					(width 0)
					(fill yes)
				)
			)
		)
	)
	(footprint ""
		(layer "F.Cu")
		(at 126.9238 -89.916)
		(property "Reference" "R116"
			(at 0 0 0)
			(layer "F.SilkS")
			(hide yes)
			(effects
				(font
					(size 1.27 1.27)
				)
			)
		)
		(property "Value" "4K75R2F-1-GP"
			(at 0.064008 -3.993896 0)
			(unlocked yes)
			(layer "F.Fab")
			(hide yes)
			(effects
				(font
					(size 1.016 1.016)
					(thickness 0.1524)
				)
			)
		)
		(property "Device Type" "R402H16"
			(at 0.064008 -5.517896 0)
			(unlocked yes)
			(layer "F.Fab")
			(hide yes)
			(effects
				(font
					(size 1.016 1.016)
					(thickness 0.1524)
				)
			)
		)
		(duplicate_pad_numbers_are_jumpers no)
		(fp_line
			(start -0.508 -0.9398)
			(end -0.508 0.9398)
			(stroke
				(width 0.1524)
				(type default)
			)
			(layer "F.SilkS")
		)
		(fp_line
			(start 0.508 -0.9398)
			(end -0.508 -0.9398)
			(stroke
				(width 0.1524)
				(type default)
			)
			(layer "F.SilkS")
		)
		(fp_rect
			(start -0.508 0.9398)
			(end 0.508 -0.9398)
			(stroke
				(width 0)
				(type default)
			)
			(fill no)
			(layer "F.CrtYd")
		)
		(fp_rect
			(start -0.508 0.9398)
			(end 0.508 -0.9398)
			(stroke
				(width 0)
				(type default)
			)
			(fill no)
			(layer "F.Fab")
		)
		(pad "1" smd custom
			(at 0 -0.4445)
			(size 0.1397 0.1397)
			(layers "F.Cu" "F.Mask" "F.Paste")
			(net "P1V8_E")
			(options
				(clearance outline)
				(anchor circle)
			)
			(primitives
				(gr_poly
					(pts
						(arc
							(start -0.1778 -0.2794)
							(mid -0.249642 -0.249642)
							(end -0.2794 -0.1778)
						)
						(arc
							(start -0.2794 0.1778)
							(mid -0.249642 0.249642)
							(end -0.1778 0.2794)
						)
						(arc
							(start 0.1778 0.2794)
							(mid 0.249642 0.249642)
							(end 0.2794 0.1778)
						)
						(arc
							(start 0.2794 -0.1778)
							(mid 0.249642 -0.249642)
							(end 0.1778 -0.2794)
						)
					)
					(width 0)
					(fill yes)
				)
			)
		)
		(pad "2" smd custom
			(at 0 0.4445)
			(size 0.1397 0.1397)
			(layers "F.Cu" "F.Mask" "F.Paste")
			(net "SDB_TX")
			(options
				(clearance outline)
				(anchor circle)
			)
			(primitives
				(gr_poly
					(pts
						(arc
							(start -0.1778 -0.2794)
							(mid -0.249642 -0.249642)
							(end -0.2794 -0.1778)
						)
						(arc
							(start -0.2794 0.1778)
							(mid -0.249642 0.249642)
							(end -0.1778 0.2794)
						)
						(arc
							(start 0.1778 0.2794)
							(mid 0.249642 0.249642)
							(end 0.2794 0.1778)
						)
						(arc
							(start 0.2794 -0.1778)
							(mid 0.249642 -0.249642)
							(end 0.1778 -0.2794)
						)
					)
					(width 0)
					(fill yes)
				)
			)
		)
	)
	(footprint ""
		(layer "F.Cu")
		(at 140.0175 -58.9026)
		(property "Reference" "VIA13"
			(at 0 0 0)
			(layer "F.SilkS")
			(hide yes)
			(effects
				(font
					(size 1.27 1.27)
				)
			)
		)
		(property "Value" "100OHM-8L-1D6MM-L13-GP"
			(at 3.2893 0.0508 0)
			(unlocked yes)
			(layer "F.Fab")
			(hide yes)
			(effects
				(font
					(size 1.016 1.016)
					(thickness 0.1524)
				)
			)
		)
		(property "Device Type" "VIA-PCIE-4P-409091"
			(at 3.2893 -1.4732 0)
			(unlocked yes)
			(layer "F.Fab")
			(hide yes)
			(effects
				(font
					(size 1.016 1.016)
					(thickness 0.1524)
				)
			)
		)
		(duplicate_pad_numbers_are_jumpers no)
		(fp_rect
			(start -2.0447 0.4572)
			(end 2.0447 -0.4572)
			(stroke
				(width 0)
				(type default)
			)
			(fill no)
			(layer "F.CrtYd")
		)
		(fp_rect
			(start -2.0447 0.4572)
			(end 2.0447 -0.4572)
			(stroke
				(width 0)
				(type default)
			)
			(fill no)
			(layer "F.Fab")
		)
		(pad "1" thru_hole circle
			(at -1.5875 0)
			(size 0.508 0.508)
			(drill 0.254)
			(layers "*.Cu" "*.Mask")
			(remove_unused_layers no)
			(net "GND")
			(clearance 0.2032)
			(thermal_gap 0.2032)
		)
		(pad "2" thru_hole circle
			(at -0.5715 0)
			(size 0.508 0.508)
			(drill 0.254)
			(layers "*.Cu" "*.Mask")
			(remove_unused_layers no)
			(net "PHY_IOC_TO_SCC_C_44_DP")
			(clearance 0.2032)
			(thermal_gap 0.2032)
		)
		(pad "3" thru_hole circle
			(at 0.5715 0)
			(size 0.508 0.508)
			(drill 0.254)
			(layers "*.Cu" "*.Mask")
			(remove_unused_layers no)
			(net "PHY_IOC_TO_SCC_C_44_DN")
			(clearance 0.2032)
			(thermal_gap 0.2032)
		)
		(pad "4" thru_hole circle
			(at 1.5875 0)
			(size 0.508 0.508)
			(drill 0.254)
			(layers "*.Cu" "*.Mask")
			(remove_unused_layers no)
			(net "GND")
			(clearance 0.2032)
			(thermal_gap 0.2032)
		)
	)
	(footprint ""
		(layer "F.Cu")
		(at 10.9728 -66.5226 90)
		(property "Reference" "R608"
			(at 0 0 90)
			(layer "F.SilkS")
			(hide yes)
			(effects
				(font
					(size 1.27 1.27)
				)
			)
		)
		(property "Value" "10KR2F-2-GP"
			(at 0.064008 -3.993896 90)
			(unlocked yes)
			(layer "F.Fab")
			(hide yes)
			(effects
				(font
					(size 1.016 1.016)
					(thickness 0.1524)
				)
			)
		)
		(property "Device Type" "R402H16"
			(at 0.064008 -5.517896 90)
			(unlocked yes)
			(layer "F.Fab")
			(hide yes)
			(effects
				(font
					(size 1.016 1.016)
					(thickness 0.1524)
				)
			)
		)
		(duplicate_pad_numbers_are_jumpers no)
		(fp_line
			(start 0.508 -0.9398)
			(end -0.508 -0.9398)
			(stroke
				(width 0.1524)
				(type default)
			)
			(layer "F.SilkS")
		)
		(fp_line
			(start -0.508 -0.9398)
			(end -0.508 0.9398)
			(stroke
				(width 0.1524)
				(type default)
			)
			(layer "F.SilkS")
		)
		(fp_rect
			(start -0.508 0.9398)
			(end 0.508 -0.9398)
			(stroke
				(width 0)
				(type default)
			)
			(fill no)
			(layer "F.CrtYd")
		)
		(fp_rect
			(start -0.508 0.9398)
			(end 0.508 -0.9398)
			(stroke
				(width 0)
				(type default)
			)
			(fill no)
			(layer "F.Fab")
		)
		(pad "1" smd custom
			(at 0 -0.4445 90)
			(size 0.1397 0.1397)
			(layers "F.Cu" "F.Mask" "F.Paste")
			(net "SCC_HSC_N")
			(options
				(clearance outline)
				(anchor circle)
			)
			(primitives
				(gr_poly
					(pts
						(arc
							(start -0.1778 -0.2794)
							(mid -0.249642 -0.249642)
							(end -0.2794 -0.1778)
						)
						(arc
							(start -0.2794 0.1778)
							(mid -0.249642 0.249642)
							(end -0.1778 0.2794)
						)
						(arc
							(start 0.1778 0.2794)
							(mid 0.249642 0.249642)
							(end 0.2794 0.1778)
						)
						(arc
							(start 0.2794 -0.1778)
							(mid 0.249642 -0.249642)
							(end 0.1778 -0.2794)
						)
					)
					(width 0)
					(fill yes)
				)
			)
		)
		(pad "2" smd custom
			(at 0 0.4445 90)
			(size 0.1397 0.1397)
			(layers "F.Cu" "F.Mask" "F.Paste")
			(net "P12V_MAIN")
			(options
				(clearance outline)
				(anchor circle)
			)
			(primitives
				(gr_poly
					(pts
						(arc
							(start -0.1778 -0.2794)
							(mid -0.249642 -0.249642)
							(end -0.2794 -0.1778)
						)
						(arc
							(start -0.2794 0.1778)
							(mid -0.249642 0.249642)
							(end -0.1778 0.2794)
						)
						(arc
							(start 0.1778 0.2794)
							(mid 0.249642 0.249642)
							(end 0.2794 0.1778)
						)
						(arc
							(start 0.2794 -0.1778)
							(mid 0.249642 -0.249642)
							(end 0.1778 -0.2794)
						)
					)
					(width 0)
					(fill yes)
				)
			)
		)
	)
	(footprint ""
		(layer "F.Cu")
		(at 13.9192 -93.5736)
		(property "Reference" "R432"
			(at 0 0 0)
			(layer "F.SilkS")
			(hide yes)
			(effects
				(font
					(size 1.27 1.27)
				)
			)
		)
		(property "Value" "1KR2F-3-GP"
			(at 0.064008 -3.993896 0)
			(unlocked yes)
			(layer "F.Fab")
			(hide yes)
			(effects
				(font
					(size 1.016 1.016)
					(thickness 0.1524)
				)
			)
		)
		(property "Device Type" "R402H16"
			(at 0.064008 -5.517896 0)
			(unlocked yes)
			(layer "F.Fab")
			(hide yes)
			(effects
				(font
					(size 1.016 1.016)
					(thickness 0.1524)
				)
			)
		)
		(duplicate_pad_numbers_are_jumpers no)
		(fp_line
			(start -0.508 -0.9398)
			(end -0.508 0.9398)
			(stroke
				(width 0.1524)
				(type default)
			)
			(layer "F.SilkS")
		)
		(fp_line
			(start 0.508 -0.9398)
			(end -0.508 -0.9398)
			(stroke
				(width 0.1524)
				(type default)
			)
			(layer "F.SilkS")
		)
		(fp_rect
			(start -0.508 0.9398)
			(end 0.508 -0.9398)
			(stroke
				(width 0)
				(type default)
			)
			(fill no)
			(layer "F.CrtYd")
		)
		(fp_rect
			(start -0.508 0.9398)
			(end 0.508 -0.9398)
			(stroke
				(width 0)
				(type default)
			)
			(fill no)
			(layer "F.Fab")
		)
		(pad "1" smd custom
			(at 0 -0.4445)
			(size 0.1397 0.1397)
			(layers "F.Cu" "F.Mask" "F.Paste")
			(net "P3V3")
			(options
				(clearance outline)
				(anchor circle)
			)
			(primitives
				(gr_poly
					(pts
						(arc
							(start -0.1778 -0.2794)
							(mid -0.249642 -0.249642)
							(end -0.2794 -0.1778)
						)
						(arc
							(start -0.2794 0.1778)
							(mid -0.249642 0.249642)
							(end -0.1778 0.2794)
						)
						(arc
							(start 0.1778 0.2794)
							(mid 0.249642 0.249642)
							(end 0.2794 0.1778)
						)
						(arc
							(start 0.2794 -0.1778)
							(mid 0.249642 -0.249642)
							(end 0.1778 -0.2794)
						)
					)
					(width 0)
					(fill yes)
				)
			)
		)
		(pad "2" smd custom
			(at 0 0.4445)
			(size 0.1397 0.1397)
			(layers "F.Cu" "F.Mask" "F.Paste")
			(net "I2C_DPB_SCL3")
			(options
				(clearance outline)
				(anchor circle)
			)
			(primitives
				(gr_poly
					(pts
						(arc
							(start -0.1778 -0.2794)
							(mid -0.249642 -0.249642)
							(end -0.2794 -0.1778)
						)
						(arc
							(start -0.2794 0.1778)
							(mid -0.249642 0.249642)
							(end -0.1778 0.2794)
						)
						(arc
							(start 0.1778 0.2794)
							(mid 0.249642 0.249642)
							(end 0.2794 0.1778)
						)
						(arc
							(start 0.2794 -0.1778)
							(mid 0.249642 -0.249642)
							(end 0.1778 -0.2794)
						)
					)
					(width 0)
					(fill yes)
				)
			)
		)
	)
	(footprint ""
		(layer "F.Cu")
		(at 190.759842 -23.32101 180)
		(property "Reference" "R249"
			(at 0 0 180)
			(layer "F.SilkS")
			(hide yes)
			(effects
				(font
					(size 1.27 1.27)
				)
			)
		)
		(property "Value" "10KR2F-2-GP"
			(at 0.064008 -3.993896 180)
			(unlocked yes)
			(layer "F.Fab")
			(hide yes)
			(effects
				(font
					(size 1.016 1.016)
					(thickness 0.1524)
				)
			)
		)
		(property "Device Type" "R402H16"
			(at 0.064008 -5.517896 180)
			(unlocked yes)
			(layer "F.Fab")
			(hide yes)
			(effects
				(font
					(size 1.016 1.016)
					(thickness 0.1524)
				)
			)
		)
		(duplicate_pad_numbers_are_jumpers no)
		(fp_line
			(start 0.508 -0.9398)
			(end -0.508 -0.9398)
			(stroke
				(width 0.1524)
				(type default)
			)
			(layer "F.SilkS")
		)
		(fp_line
			(start -0.508 -0.9398)
			(end -0.508 0.9398)
			(stroke
				(width 0.1524)
				(type default)
			)
			(layer "F.SilkS")
		)
		(fp_rect
			(start -0.508 0.9398)
			(end 0.508 -0.9398)
			(stroke
				(width 0)
				(type default)
			)
			(fill no)
			(layer "F.CrtYd")
		)
		(fp_rect
			(start -0.508 0.9398)
			(end 0.508 -0.9398)
			(stroke
				(width 0)
				(type default)
			)
			(fill no)
			(layer "F.Fab")
		)
		(pad "1" smd custom
			(at 0 -0.4445 180)
			(size 0.1397 0.1397)
			(layers "F.Cu" "F.Mask" "F.Paste")
			(net "P1V8_C")
			(options
				(clearance outline)
				(anchor circle)
			)
			(primitives
				(gr_poly
					(pts
						(arc
							(start -0.1778 -0.2794)
							(mid -0.249642 -0.249642)
							(end -0.2794 -0.1778)
						)
						(arc
							(start -0.2794 0.1778)
							(mid -0.249642 0.249642)
							(end -0.1778 0.2794)
						)
						(arc
							(start 0.1778 0.2794)
							(mid 0.249642 0.249642)
							(end 0.2794 0.1778)
						)
						(arc
							(start 0.2794 -0.1778)
							(mid 0.249642 -0.249642)
							(end 0.1778 -0.2794)
						)
					)
					(width 0)
					(fill yes)
				)
			)
		)
		(pad "2" smd custom
			(at 0 0.4445 180)
			(size 0.1397 0.1397)
			(layers "F.Cu" "F.Mask" "F.Paste")
			(net "SYS_DBMODE2")
			(options
				(clearance outline)
				(anchor circle)
			)
			(primitives
				(gr_poly
					(pts
						(arc
							(start -0.1778 -0.2794)
							(mid -0.249642 -0.249642)
							(end -0.2794 -0.1778)
						)
						(arc
							(start -0.2794 0.1778)
							(mid -0.249642 0.249642)
							(end -0.1778 0.2794)
						)
						(arc
							(start 0.1778 0.2794)
							(mid 0.249642 0.249642)
							(end 0.2794 0.1778)
						)
						(arc
							(start 0.2794 -0.1778)
							(mid 0.249642 -0.249642)
							(end 0.1778 -0.2794)
						)
					)
					(width 0)
					(fill yes)
				)
			)
		)
	)
	(footprint ""
		(layer "F.Cu")
		(at 66.04 -72.6948 180)
		(property "Reference" "R428"
			(at 0 0 180)
			(layer "F.SilkS")
			(hide yes)
			(effects
				(font
					(size 1.27 1.27)
				)
			)
		)
		(property "Value" "1KR2F-3-GP"
			(at 0.064008 -3.993896 180)
			(unlocked yes)
			(layer "F.Fab")
			(hide yes)
			(effects
				(font
					(size 1.016 1.016)
					(thickness 0.1524)
				)
			)
		)
		(property "Device Type" "R402H16"
			(at 0.064008 -5.517896 180)
			(unlocked yes)
			(layer "F.Fab")
			(hide yes)
			(effects
				(font
					(size 1.016 1.016)
					(thickness 0.1524)
				)
			)
		)
		(duplicate_pad_numbers_are_jumpers no)
		(fp_line
			(start 0.508 -0.9398)
			(end -0.508 -0.9398)
			(stroke
				(width 0.1524)
				(type default)
			)
			(layer "F.SilkS")
		)
		(fp_line
			(start -0.508 -0.9398)
			(end -0.508 0.9398)
			(stroke
				(width 0.1524)
				(type default)
			)
			(layer "F.SilkS")
		)
		(fp_rect
			(start -0.508 0.9398)
			(end 0.508 -0.9398)
			(stroke
				(width 0)
				(type default)
			)
			(fill no)
			(layer "F.CrtYd")
		)
		(fp_rect
			(start -0.508 0.9398)
			(end 0.508 -0.9398)
			(stroke
				(width 0)
				(type default)
			)
			(fill no)
			(layer "F.Fab")
		)
		(pad "1" smd custom
			(at 0 -0.4445 180)
			(size 0.1397 0.1397)
			(layers "F.Cu" "F.Mask" "F.Paste")
			(net "P3V3")
			(options
				(clearance outline)
				(anchor circle)
			)
			(primitives
				(gr_poly
					(pts
						(arc
							(start -0.1778 -0.2794)
							(mid -0.249642 -0.249642)
							(end -0.2794 -0.1778)
						)
						(arc
							(start -0.2794 0.1778)
							(mid -0.249642 0.249642)
							(end -0.1778 0.2794)
						)
						(arc
							(start 0.1778 0.2794)
							(mid 0.249642 0.249642)
							(end 0.2794 0.1778)
						)
						(arc
							(start 0.2794 -0.1778)
							(mid 0.249642 -0.249642)
							(end 0.1778 -0.2794)
						)
					)
					(width 0)
					(fill yes)
				)
			)
		)
		(pad "2" smd custom
			(at 0 0.4445 180)
			(size 0.1397 0.1397)
			(layers "F.Cu" "F.Mask" "F.Paste")
			(net "I2C_DRIVE_FLT_LED_SDA6")
			(options
				(clearance outline)
				(anchor circle)
			)
			(primitives
				(gr_poly
					(pts
						(arc
							(start -0.1778 -0.2794)
							(mid -0.249642 -0.249642)
							(end -0.2794 -0.1778)
						)
						(arc
							(start -0.2794 0.1778)
							(mid -0.249642 0.249642)
							(end -0.1778 0.2794)
						)
						(arc
							(start 0.1778 0.2794)
							(mid 0.249642 0.249642)
							(end 0.2794 0.1778)
						)
						(arc
							(start 0.2794 -0.1778)
							(mid 0.249642 -0.249642)
							(end 0.1778 -0.2794)
						)
					)
					(width 0)
					(fill yes)
				)
			)
		)
	)
	(footprint ""
		(layer "F.Cu")
		(at 94.661228 -83.439762 -90)
		(property "Reference" "R309"
			(at 0 0 270)
			(layer "F.SilkS")
			(hide yes)
			(effects
				(font
					(size 1.27 1.27)
				)
			)
		)
		(property "Value" "10KR2F-2-GP"
			(at 0.064008 -3.993896 270)
			(unlocked yes)
			(layer "F.Fab")
			(hide yes)
			(effects
				(font
					(size 1.016 1.016)
					(thickness 0.1524)
				)
			)
		)
		(property "Device Type" "R402H16"
			(at 0.064008 -5.517896 270)
			(unlocked yes)
			(layer "F.Fab")
			(hide yes)
			(effects
				(font
					(size 1.016 1.016)
					(thickness 0.1524)
				)
			)
		)
		(duplicate_pad_numbers_are_jumpers no)
		(fp_line
			(start -0.508 -0.9398)
			(end -0.508 0.9398)
			(stroke
				(width 0.1524)
				(type default)
			)
			(layer "F.SilkS")
		)
		(fp_line
			(start 0.508 -0.9398)
			(end -0.508 -0.9398)
			(stroke
				(width 0.1524)
				(type default)
			)
			(layer "F.SilkS")
		)
		(fp_rect
			(start -0.508 0.9398)
			(end 0.508 -0.9398)
			(stroke
				(width 0)
				(type default)
			)
			(fill no)
			(layer "F.CrtYd")
		)
		(fp_rect
			(start -0.508 0.9398)
			(end 0.508 -0.9398)
			(stroke
				(width 0)
				(type default)
			)
			(fill no)
			(layer "F.Fab")
		)
		(pad "1" smd custom
			(at 0 -0.4445 270)
			(size 0.1397 0.1397)
			(layers "F.Cu" "F.Mask" "F.Paste")
			(net "P1V8_E")
			(options
				(clearance outline)
				(anchor circle)
			)
			(primitives
				(gr_poly
					(pts
						(arc
							(start -0.1778 -0.2794)
							(mid -0.249642 -0.249642)
							(end -0.2794 -0.1778)
						)
						(arc
							(start -0.2794 0.1778)
							(mid -0.249642 0.249642)
							(end -0.1778 0.2794)
						)
						(arc
							(start 0.1778 0.2794)
							(mid 0.249642 0.249642)
							(end 0.2794 0.1778)
						)
						(arc
							(start 0.2794 -0.1778)
							(mid 0.249642 -0.249642)
							(end 0.1778 -0.2794)
						)
					)
					(width 0)
					(fill yes)
				)
			)
		)
		(pad "2" smd custom
			(at 0 0.4445 270)
			(size 0.1397 0.1397)
			(layers "F.Cu" "F.Mask" "F.Paste")
			(net "SCC_RESET_LS_N")
			(options
				(clearance outline)
				(anchor circle)
			)
			(primitives
				(gr_poly
					(pts
						(arc
							(start -0.1778 -0.2794)
							(mid -0.249642 -0.249642)
							(end -0.2794 -0.1778)
						)
						(arc
							(start -0.2794 0.1778)
							(mid -0.249642 0.249642)
							(end -0.1778 0.2794)
						)
						(arc
							(start 0.1778 0.2794)
							(mid 0.249642 0.249642)
							(end 0.2794 0.1778)
						)
						(arc
							(start 0.2794 -0.1778)
							(mid 0.249642 -0.249642)
							(end 0.1778 -0.2794)
						)
					)
					(width 0)
					(fill yes)
				)
			)
		)
	)
	(footprint ""
		(layer "F.Cu")
		(at 190.155576 -48.526954 90)
		(property "Reference" "TP103"
			(at 0 0 90)
			(layer "F.SilkS")
			(hide yes)
			(effects
				(font
					(size 1.27 1.27)
				)
			)
		)
		(property "Value" "TPAD28-2-GP"
			(at -0.0127 -1.6637 90)
			(unlocked yes)
			(layer "F.Fab")
			(hide yes)
			(effects
				(font
					(size 1.016 1.016)
					(thickness 0.1524)
				)
			)
		)
		(property "Device Type" "TPAD28"
			(at -0.0127 -3.1877 90)
			(unlocked yes)
			(layer "F.Fab")
			(hide yes)
			(effects
				(font
					(size 1.016 1.016)
					(thickness 0.1524)
				)
			)
		)
		(duplicate_pad_numbers_are_jumpers no)
		(fp_poly
			(pts
				(arc
					(start 0 0.3556)
					(mid 0 -0.3556)
					(end 0 0.3556)
				)
			)
			(stroke
				(width 0)
				(type default)
			)
			(fill no)
			(layer "F.CrtYd")
		)
		(fp_poly
			(pts
				(arc
					(start 0 0.6096)
					(mid 0 -0.6096)
					(end 0 0.6096)
				)
			)
			(stroke
				(width 0)
				(type default)
			)
			(fill no)
			(layer "F.Fab")
		)
		(pad "1" smd circle
			(at 0 0 90)
			(size 0.7112 0.7112)
			(layers "F.Cu" "F.Mask" "F.Paste")
			(net "XM_ADDR_16")
		)
	)
	(footprint ""
		(layer "F.Cu")
		(at 191.85382 -50.0888 -90)
		(property "Reference" "R396"
			(at 0 0 270)
			(layer "F.SilkS")
			(hide yes)
			(effects
				(font
					(size 1.27 1.27)
				)
			)
		)
		(property "Value" "10KR2F-2-GP"
			(at 0.064008 -3.993896 270)
			(unlocked yes)
			(layer "F.Fab")
			(hide yes)
			(effects
				(font
					(size 1.016 1.016)
					(thickness 0.1524)
				)
			)
		)
		(property "Device Type" "R402H16"
			(at 0.064008 -5.517896 270)
			(unlocked yes)
			(layer "F.Fab")
			(hide yes)
			(effects
				(font
					(size 1.016 1.016)
					(thickness 0.1524)
				)
			)
		)
		(duplicate_pad_numbers_are_jumpers no)
		(fp_line
			(start -0.508 -0.9398)
			(end -0.508 0.9398)
			(stroke
				(width 0.1524)
				(type default)
			)
			(layer "F.SilkS")
		)
		(fp_line
			(start 0.508 -0.9398)
			(end -0.508 -0.9398)
			(stroke
				(width 0.1524)
				(type default)
			)
			(layer "F.SilkS")
		)
		(fp_rect
			(start -0.508 0.9398)
			(end 0.508 -0.9398)
			(stroke
				(width 0)
				(type default)
			)
			(fill no)
			(layer "F.CrtYd")
		)
		(fp_rect
			(start -0.508 0.9398)
			(end 0.508 -0.9398)
			(stroke
				(width 0)
				(type default)
			)
			(fill no)
			(layer "F.Fab")
		)
		(pad "1" smd custom
			(at 0 -0.4445 270)
			(size 0.1397 0.1397)
			(layers "F.Cu" "F.Mask" "F.Paste")
			(net "P1V8_C")
			(options
				(clearance outline)
				(anchor circle)
			)
			(primitives
				(gr_poly
					(pts
						(arc
							(start -0.1778 -0.2794)
							(mid -0.249642 -0.249642)
							(end -0.2794 -0.1778)
						)
						(arc
							(start -0.2794 0.1778)
							(mid -0.249642 0.249642)
							(end -0.1778 0.2794)
						)
						(arc
							(start 0.1778 0.2794)
							(mid 0.249642 0.249642)
							(end 0.2794 0.1778)
						)
						(arc
							(start 0.2794 -0.1778)
							(mid 0.249642 -0.249642)
							(end 0.1778 -0.2794)
						)
					)
					(width 0)
					(fill yes)
				)
			)
		)
		(pad "2" smd custom
			(at 0 0.4445 270)
			(size 0.1397 0.1397)
			(layers "F.Cu" "F.Mask" "F.Paste")
			(net "XM_ADDR_11")
			(options
				(clearance outline)
				(anchor circle)
			)
			(primitives
				(gr_poly
					(pts
						(arc
							(start -0.1778 -0.2794)
							(mid -0.249642 -0.249642)
							(end -0.2794 -0.1778)
						)
						(arc
							(start -0.2794 0.1778)
							(mid -0.249642 0.249642)
							(end -0.1778 0.2794)
						)
						(arc
							(start 0.1778 0.2794)
							(mid 0.249642 0.249642)
							(end 0.2794 0.1778)
						)
						(arc
							(start 0.2794 -0.1778)
							(mid 0.249642 -0.249642)
							(end 0.1778 -0.2794)
						)
					)
					(width 0)
					(fill yes)
				)
			)
		)
	)
	(footprint ""
		(layer "F.Cu")
		(at 184.65038 -107.67822 -90)
		(property "Reference" "R8"
			(at 0 0 270)
			(layer "F.SilkS")
			(hide yes)
			(effects
				(font
					(size 1.27 1.27)
				)
			)
		)
		(property "Value" "4K53R2F-1-GP"
			(at 0.064008 -3.993896 270)
			(unlocked yes)
			(layer "F.Fab")
			(hide yes)
			(effects
				(font
					(size 1.016 1.016)
					(thickness 0.1524)
				)
			)
		)
		(property "Device Type" "R402H16"
			(at 0.064008 -5.517896 270)
			(unlocked yes)
			(layer "F.Fab")
			(hide yes)
			(effects
				(font
					(size 1.016 1.016)
					(thickness 0.1524)
				)
			)
		)
		(duplicate_pad_numbers_are_jumpers no)
		(fp_line
			(start -0.508 -0.9398)
			(end -0.508 0.9398)
			(stroke
				(width 0.1524)
				(type default)
			)
			(layer "F.SilkS")
		)
		(fp_line
			(start 0.508 -0.9398)
			(end -0.508 -0.9398)
			(stroke
				(width 0.1524)
				(type default)
			)
			(layer "F.SilkS")
		)
		(fp_rect
			(start -0.508 0.9398)
			(end 0.508 -0.9398)
			(stroke
				(width 0)
				(type default)
			)
			(fill no)
			(layer "F.CrtYd")
		)
		(fp_rect
			(start -0.508 0.9398)
			(end 0.508 -0.9398)
			(stroke
				(width 0)
				(type default)
			)
			(fill no)
			(layer "F.Fab")
		)
		(pad "1" smd custom
			(at 0 -0.4445 270)
			(size 0.1397 0.1397)
			(layers "F.Cu" "F.Mask" "F.Paste")
			(net "P0V9_G_PG")
			(options
				(clearance outline)
				(anchor circle)
			)
			(primitives
				(gr_poly
					(pts
						(arc
							(start -0.1778 -0.2794)
							(mid -0.249642 -0.249642)
							(end -0.2794 -0.1778)
						)
						(arc
							(start -0.2794 0.1778)
							(mid -0.249642 0.249642)
							(end -0.1778 0.2794)
						)
						(arc
							(start 0.1778 0.2794)
							(mid 0.249642 0.249642)
							(end 0.2794 0.1778)
						)
						(arc
							(start 0.2794 -0.1778)
							(mid 0.249642 -0.249642)
							(end 0.1778 -0.2794)
						)
					)
					(width 0)
					(fill yes)
				)
			)
		)
		(pad "2" smd custom
			(at 0 0.4445 270)
			(size 0.1397 0.1397)
			(layers "F.Cu" "F.Mask" "F.Paste")
			(net "P3V3")
			(options
				(clearance outline)
				(anchor circle)
			)
			(primitives
				(gr_poly
					(pts
						(arc
							(start -0.1778 -0.2794)
							(mid -0.249642 -0.249642)
							(end -0.2794 -0.1778)
						)
						(arc
							(start -0.2794 0.1778)
							(mid -0.249642 0.249642)
							(end -0.1778 0.2794)
						)
						(arc
							(start 0.1778 0.2794)
							(mid 0.249642 0.249642)
							(end 0.2794 0.1778)
						)
						(arc
							(start 0.2794 -0.1778)
							(mid 0.249642 -0.249642)
							(end 0.1778 -0.2794)
						)
					)
					(width 0)
					(fill yes)
				)
			)
		)
	)
	(footprint ""
		(layer "F.Cu")
		(at 12.6238 -100.6856)
		(property "Reference" "C733"
			(at 0 0 0)
			(layer "F.SilkS")
			(hide yes)
			(effects
				(font
					(size 1.27 1.27)
				)
			)
		)
		(property "Value" "SCD1U16V2KX-3GP"
			(at 1.1811 -2.7051 0)
			(unlocked yes)
			(layer "F.Fab")
			(hide yes)
			(effects
				(font
					(size 1.016 1.016)
					(thickness 0.1524)
				)
			)
		)
		(property "Device Type" "C402H22"
			(at 1.1811 -4.2291 0)
			(unlocked yes)
			(layer "F.Fab")
			(hide yes)
			(effects
				(font
					(size 1.016 1.016)
					(thickness 0.1524)
				)
			)
		)
		(duplicate_pad_numbers_are_jumpers no)
		(fp_rect
			(start -0.4318 0.9525)
			(end 0.4318 -0.9525)
			(stroke
				(width 0)
				(type default)
			)
			(fill no)
			(layer "F.CrtYd")
		)
		(fp_rect
			(start -0.4318 0.9525)
			(end 0.4318 -0.9525)
			(stroke
				(width 0)
				(type default)
			)
			(fill no)
			(layer "F.Fab")
		)
		(pad "1" smd custom
			(at 0 -0.4445)
			(size 0.1524 0.1524)
			(layers "F.Cu" "F.Mask" "F.Paste")
			(net "P3V3")
			(options
				(clearance outline)
				(anchor circle)
			)
			(primitives
				(gr_poly
					(pts
						(arc
							(start 0.3048 -0.2032)
							(mid 0.275042 -0.275042)
							(end 0.2032 -0.3048)
						)
						(arc
							(start -0.2032 -0.3048)
							(mid -0.275042 -0.275042)
							(end -0.3048 -0.2032)
						)
						(arc
							(start -0.3048 0.2032)
							(mid -0.275042 0.275042)
							(end -0.2032 0.3048)
						)
						(arc
							(start 0.2032 0.3048)
							(mid 0.275042 0.275042)
							(end 0.3048 0.2032)
						)
					)
					(width 0)
					(fill yes)
				)
			)
		)
		(pad "2" smd custom
			(at 0 0.4445)
			(size 0.1524 0.1524)
			(layers "F.Cu" "F.Mask" "F.Paste")
			(net "GND")
			(options
				(clearance outline)
				(anchor circle)
			)
			(primitives
				(gr_poly
					(pts
						(arc
							(start 0.3048 -0.2032)
							(mid 0.275042 -0.275042)
							(end 0.2032 -0.3048)
						)
						(arc
							(start -0.2032 -0.3048)
							(mid -0.275042 -0.275042)
							(end -0.3048 -0.2032)
						)
						(arc
							(start -0.3048 0.2032)
							(mid -0.275042 0.275042)
							(end -0.2032 0.3048)
						)
						(arc
							(start 0.2032 0.3048)
							(mid 0.275042 0.275042)
							(end 0.3048 0.2032)
						)
					)
					(width 0)
					(fill yes)
				)
			)
		)
	)
	(footprint ""
		(layer "F.Cu")
		(at 155.74518 -85.775292 -90)
		(property "Reference" "U25"
			(at 0 0 270)
			(layer "F.SilkS")
			(hide yes)
			(effects
				(font
					(size 1.27 1.27)
				)
			)
		)
		(property "Value" "ADS1015IDGSR-GP"
			(at 0 -11.1252 270)
			(unlocked yes)
			(layer "F.Fab")
			(hide yes)
			(effects
				(font
					(size 1.016 1.016)
					(thickness 0.1524)
				)
			)
		)
		(property "Device Type" "MSOP10H44"
			(at 0 -12.6492 270)
			(unlocked yes)
			(layer "F.Fab")
			(hide yes)
			(effects
				(font
					(size 1.016 1.016)
					(thickness 0.1524)
				)
			)
		)
		(duplicate_pad_numbers_are_jumpers no)
		(fp_line
			(start -2.0066 1.016)
			(end -2.0066 -1.016)
			(stroke
				(width 0.1524)
				(type default)
			)
			(layer "F.SilkS")
		)
		(fp_line
			(start -1.8288 1.016)
			(end -1.8288 3.048)
			(stroke
				(width 0.508)
				(type default)
			)
			(layer "F.SilkS")
		)
		(fp_line
			(start 1.143 1.016)
			(end -2.0066 1.016)
			(stroke
				(width 0.1524)
				(type default)
			)
			(layer "F.SilkS")
		)
		(fp_line
			(start -1.5748 0)
			(end -1.9558 0.381)
			(stroke
				(width 0.1524)
				(type default)
			)
			(layer "F.SilkS")
		)
		(fp_line
			(start -1.5748 0)
			(end -1.9558 -0.381)
			(stroke
				(width 0.1524)
				(type default)
			)
			(layer "F.SilkS")
		)
		(fp_line
			(start -2.0066 -1.016)
			(end 1.143 -1.016)
			(stroke
				(width 0.1524)
				(type default)
			)
			(layer "F.SilkS")
		)
		(fp_line
			(start 1.143 -1.016)
			(end 1.143 1.016)
			(stroke
				(width 0.1524)
				(type default)
			)
			(layer "F.SilkS")
		)
		(fp_poly
			(pts
				(xy -2.0828 3.3401) (xy 2.0828 3.3401) (xy 2.0828 -3.3401) (xy -2.0828 -3.3401)
			)
			(stroke
				(width 0)
				(type default)
			)
			(fill no)
			(layer "F.CrtYd")
		)
		(fp_poly
			(pts
				(xy -2.0828 3.3401) (xy 2.0828 3.3401) (xy 2.0828 -3.3401) (xy -2.0828 -3.3401)
			)
			(stroke
				(width 0)
				(type default)
			)
			(fill no)
			(layer "F.Fab")
		)
		(pad "1" smd rect
			(at -0.99949 2.0701 270)
			(size 0.3048 1.524)
			(layers "F.Cu" "F.Mask" "F.Paste")
			(net "VOL_SEN1_ADDR")
		)
		(pad "2" smd rect
			(at -0.50038 2.0701 270)
			(size 0.3048 1.524)
			(layers "F.Cu" "F.Mask" "F.Paste")
			(net "VOL_SEN1_ALERT")
		)
		(pad "3" smd rect
			(at 0 2.0701 270)
			(size 0.3048 1.524)
			(layers "F.Cu" "F.Mask" "F.Paste")
			(net "GND")
		)
		(pad "4" smd rect
			(at 0.50038 2.0701 270)
			(size 0.3048 1.524)
			(layers "F.Cu" "F.Mask" "F.Paste")
			(net "P3V3_SENSE")
		)
		(pad "5" smd rect
			(at 0.99949 2.0701 270)
			(size 0.3048 1.524)
			(layers "F.Cu" "F.Mask" "F.Paste")
			(net "P1V8_E_SENSE")
		)
		(pad "6" smd rect
			(at 0.99949 -2.0701 270)
			(size 0.3048 1.524)
			(layers "F.Cu" "F.Mask" "F.Paste")
			(net "P1V5_E_SENSE")
		)
		(pad "7" smd rect
			(at 0.50038 -2.0701 270)
			(size 0.3048 1.524)
			(layers "F.Cu" "F.Mask" "F.Paste")
			(net "P0V9_SENSE")
		)
		(pad "8" smd rect
			(at 0 -2.0701 270)
			(size 0.3048 1.524)
			(layers "F.Cu" "F.Mask" "F.Paste")
			(net "P3V3")
		)
		(pad "9" smd rect
			(at -0.50038 -2.0701 270)
			(size 0.3048 1.524)
			(layers "F.Cu" "F.Mask" "F.Paste")
			(net "VOL_SEN1_SDA")
		)
		(pad "10" smd rect
			(at -0.99949 -2.0701 270)
			(size 0.3048 1.524)
			(layers "F.Cu" "F.Mask" "F.Paste")
			(net "VOL_SEN1_SCL")
		)
	)
	(footprint ""
		(layer "F.Cu")
		(at 149.02688 -120.56872 180)
		(property "Reference" "R25"
			(at 0 0 180)
			(layer "F.SilkS")
			(hide yes)
			(effects
				(font
					(size 1.27 1.27)
				)
			)
		)
		(property "Value" "0R2J-2-GP"
			(at 0.064008 -3.993896 180)
			(unlocked yes)
			(layer "F.Fab")
			(hide yes)
			(effects
				(font
					(size 1.016 1.016)
					(thickness 0.1524)
				)
			)
		)
		(property "Device Type" "R402H16"
			(at 0.064008 -5.517896 180)
			(unlocked yes)
			(layer "F.Fab")
			(hide yes)
			(effects
				(font
					(size 1.016 1.016)
					(thickness 0.1524)
				)
			)
		)
		(duplicate_pad_numbers_are_jumpers no)
		(fp_line
			(start 0.508 -0.9398)
			(end -0.508 -0.9398)
			(stroke
				(width 0.1524)
				(type default)
			)
			(layer "F.SilkS")
		)
		(fp_line
			(start -0.508 -0.9398)
			(end -0.508 0.9398)
			(stroke
				(width 0.1524)
				(type default)
			)
			(layer "F.SilkS")
		)
		(fp_rect
			(start -0.508 0.9398)
			(end 0.508 -0.9398)
			(stroke
				(width 0)
				(type default)
			)
			(fill no)
			(layer "F.CrtYd")
		)
		(fp_rect
			(start -0.508 0.9398)
			(end 0.508 -0.9398)
			(stroke
				(width 0)
				(type default)
			)
			(fill no)
			(layer "F.Fab")
		)
		(pad "1" smd custom
			(at 0 -0.4445 180)
			(size 0.1397 0.1397)
			(layers "F.Cu" "F.Mask" "F.Paste")
			(net "P1V5_E_EN")
			(options
				(clearance outline)
				(anchor circle)
			)
			(primitives
				(gr_poly
					(pts
						(arc
							(start -0.1778 -0.2794)
							(mid -0.249642 -0.249642)
							(end -0.2794 -0.1778)
						)
						(arc
							(start -0.2794 0.1778)
							(mid -0.249642 0.249642)
							(end -0.1778 0.2794)
						)
						(arc
							(start 0.1778 0.2794)
							(mid 0.249642 0.249642)
							(end 0.2794 0.1778)
						)
						(arc
							(start 0.2794 -0.1778)
							(mid 0.249642 -0.249642)
							(end 0.1778 -0.2794)
						)
					)
					(width 0)
					(fill yes)
				)
			)
		)
		(pad "2" smd custom
			(at 0 0.4445 180)
			(size 0.1397 0.1397)
			(layers "F.Cu" "F.Mask" "F.Paste")
			(net "P1V8_E_PG")
			(options
				(clearance outline)
				(anchor circle)
			)
			(primitives
				(gr_poly
					(pts
						(arc
							(start -0.1778 -0.2794)
							(mid -0.249642 -0.249642)
							(end -0.2794 -0.1778)
						)
						(arc
							(start -0.2794 0.1778)
							(mid -0.249642 0.249642)
							(end -0.1778 0.2794)
						)
						(arc
							(start 0.1778 0.2794)
							(mid 0.249642 0.249642)
							(end 0.2794 0.1778)
						)
						(arc
							(start 0.2794 -0.1778)
							(mid 0.249642 -0.249642)
							(end 0.1778 -0.2794)
						)
					)
					(width 0)
					(fill yes)
				)
			)
		)
	)
	(footprint ""
		(layer "F.Cu")
		(at 169.507662 -58.072528)
		(property "Reference" "R267"
			(at 0 0 0)
			(layer "F.SilkS")
			(hide yes)
			(effects
				(font
					(size 1.27 1.27)
				)
			)
		)
		(property "Value" "4K7R2F-GP"
			(at 0.064008 -3.993896 0)
			(unlocked yes)
			(layer "F.Fab")
			(hide yes)
			(effects
				(font
					(size 1.016 1.016)
					(thickness 0.1524)
				)
			)
		)
		(property "Device Type" "R402H16"
			(at 0.064008 -5.517896 0)
			(unlocked yes)
			(layer "F.Fab")
			(hide yes)
			(effects
				(font
					(size 1.016 1.016)
					(thickness 0.1524)
				)
			)
		)
		(duplicate_pad_numbers_are_jumpers no)
		(fp_line
			(start -0.508 -0.9398)
			(end -0.508 0.9398)
			(stroke
				(width 0.1524)
				(type default)
			)
			(layer "F.SilkS")
		)
		(fp_line
			(start 0.508 -0.9398)
			(end -0.508 -0.9398)
			(stroke
				(width 0.1524)
				(type default)
			)
			(layer "F.SilkS")
		)
		(fp_rect
			(start -0.508 0.9398)
			(end 0.508 -0.9398)
			(stroke
				(width 0)
				(type default)
			)
			(fill no)
			(layer "F.CrtYd")
		)
		(fp_rect
			(start -0.508 0.9398)
			(end 0.508 -0.9398)
			(stroke
				(width 0)
				(type default)
			)
			(fill no)
			(layer "F.Fab")
		)
		(pad "1" smd custom
			(at 0 -0.4445)
			(size 0.1397 0.1397)
			(layers "F.Cu" "F.Mask" "F.Paste")
			(net "P1V8_C")
			(options
				(clearance outline)
				(anchor circle)
			)
			(primitives
				(gr_poly
					(pts
						(arc
							(start -0.1778 -0.2794)
							(mid -0.249642 -0.249642)
							(end -0.2794 -0.1778)
						)
						(arc
							(start -0.2794 0.1778)
							(mid -0.249642 0.249642)
							(end -0.1778 0.2794)
						)
						(arc
							(start 0.1778 0.2794)
							(mid 0.249642 0.249642)
							(end 0.2794 0.1778)
						)
						(arc
							(start 0.2794 -0.1778)
							(mid 0.249642 -0.249642)
							(end 0.1778 -0.2794)
						)
					)
					(width 0)
					(fill yes)
				)
			)
		)
		(pad "2" smd custom
			(at 0 0.4445)
			(size 0.1397 0.1397)
			(layers "F.Cu" "F.Mask" "F.Paste")
			(net "ICE0_TCK")
			(options
				(clearance outline)
				(anchor circle)
			)
			(primitives
				(gr_poly
					(pts
						(arc
							(start -0.1778 -0.2794)
							(mid -0.249642 -0.249642)
							(end -0.2794 -0.1778)
						)
						(arc
							(start -0.2794 0.1778)
							(mid -0.249642 0.249642)
							(end -0.1778 0.2794)
						)
						(arc
							(start 0.1778 0.2794)
							(mid 0.249642 0.249642)
							(end 0.2794 0.1778)
						)
						(arc
							(start 0.2794 -0.1778)
							(mid 0.249642 -0.249642)
							(end 0.1778 -0.2794)
						)
					)
					(width 0)
					(fill yes)
				)
			)
		)
	)
	(footprint ""
		(layer "F.Cu")
		(at 41.0972 -29.8958 -90)
		(property "Reference" "R91"
			(at 0 0 270)
			(layer "F.SilkS")
			(hide yes)
			(effects
				(font
					(size 1.27 1.27)
				)
			)
		)
		(property "Value" "200KR2F-L-GP"
			(at 0.064008 -3.993896 270)
			(unlocked yes)
			(layer "F.Fab")
			(hide yes)
			(effects
				(font
					(size 1.016 1.016)
					(thickness 0.1524)
				)
			)
		)
		(property "Device Type" "R402H16"
			(at 0.064008 -5.517896 270)
			(unlocked yes)
			(layer "F.Fab")
			(hide yes)
			(effects
				(font
					(size 1.016 1.016)
					(thickness 0.1524)
				)
			)
		)
		(duplicate_pad_numbers_are_jumpers no)
		(fp_line
			(start -0.508 -0.9398)
			(end -0.508 0.9398)
			(stroke
				(width 0.1524)
				(type default)
			)
			(layer "F.SilkS")
		)
		(fp_line
			(start 0.508 -0.9398)
			(end -0.508 -0.9398)
			(stroke
				(width 0.1524)
				(type default)
			)
			(layer "F.SilkS")
		)
		(fp_rect
			(start -0.508 0.9398)
			(end 0.508 -0.9398)
			(stroke
				(width 0)
				(type default)
			)
			(fill no)
			(layer "F.CrtYd")
		)
		(fp_rect
			(start -0.508 0.9398)
			(end 0.508 -0.9398)
			(stroke
				(width 0)
				(type default)
			)
			(fill no)
			(layer "F.Fab")
		)
		(pad "1" smd custom
			(at 0 -0.4445 270)
			(size 0.1397 0.1397)
			(layers "F.Cu" "F.Mask" "F.Paste")
			(net "P0V9_U8_PG")
			(options
				(clearance outline)
				(anchor circle)
			)
			(primitives
				(gr_poly
					(pts
						(arc
							(start -0.1778 -0.2794)
							(mid -0.249642 -0.249642)
							(end -0.2794 -0.1778)
						)
						(arc
							(start -0.2794 0.1778)
							(mid -0.249642 0.249642)
							(end -0.1778 0.2794)
						)
						(arc
							(start 0.1778 0.2794)
							(mid 0.249642 0.249642)
							(end 0.2794 0.1778)
						)
						(arc
							(start 0.2794 -0.1778)
							(mid 0.249642 -0.249642)
							(end 0.1778 -0.2794)
						)
					)
					(width 0)
					(fill yes)
				)
			)
		)
		(pad "2" smd custom
			(at 0 0.4445 270)
			(size 0.1397 0.1397)
			(layers "F.Cu" "F.Mask" "F.Paste")
			(net "P0V9_MODE")
			(options
				(clearance outline)
				(anchor circle)
			)
			(primitives
				(gr_poly
					(pts
						(arc
							(start -0.1778 -0.2794)
							(mid -0.249642 -0.249642)
							(end -0.2794 -0.1778)
						)
						(arc
							(start -0.2794 0.1778)
							(mid -0.249642 0.249642)
							(end -0.1778 0.2794)
						)
						(arc
							(start 0.1778 0.2794)
							(mid 0.249642 0.249642)
							(end 0.2794 0.1778)
						)
						(arc
							(start 0.2794 -0.1778)
							(mid 0.249642 -0.249642)
							(end 0.1778 -0.2794)
						)
					)
					(width 0)
					(fill yes)
				)
			)
		)
	)
	(footprint ""
		(layer "F.Cu")
		(at 13.3096 -59.1312)
		(property "Reference" "R693"
			(at 0 0 0)
			(layer "F.SilkS")
			(hide yes)
			(effects
				(font
					(size 1.27 1.27)
				)
			)
		)
		(property "Value" "10KR2F-2-GP"
			(at 0.064008 -3.993896 0)
			(unlocked yes)
			(layer "F.Fab")
			(hide yes)
			(effects
				(font
					(size 1.016 1.016)
					(thickness 0.1524)
				)
			)
		)
		(property "Device Type" "R402H16"
			(at 0.064008 -5.517896 0)
			(unlocked yes)
			(layer "F.Fab")
			(hide yes)
			(effects
				(font
					(size 1.016 1.016)
					(thickness 0.1524)
				)
			)
		)
		(duplicate_pad_numbers_are_jumpers no)
		(fp_line
			(start -0.508 -0.9398)
			(end -0.508 0.9398)
			(stroke
				(width 0.1524)
				(type default)
			)
			(layer "F.SilkS")
		)
		(fp_line
			(start 0.508 -0.9398)
			(end -0.508 -0.9398)
			(stroke
				(width 0.1524)
				(type default)
			)
			(layer "F.SilkS")
		)
		(fp_rect
			(start -0.508 0.9398)
			(end 0.508 -0.9398)
			(stroke
				(width 0)
				(type default)
			)
			(fill no)
			(layer "F.CrtYd")
		)
		(fp_rect
			(start -0.508 0.9398)
			(end 0.508 -0.9398)
			(stroke
				(width 0)
				(type default)
			)
			(fill no)
			(layer "F.Fab")
		)
		(pad "1" smd custom
			(at 0 -0.4445)
			(size 0.1397 0.1397)
			(layers "F.Cu" "F.Mask" "F.Paste")
			(net "GND")
			(options
				(clearance outline)
				(anchor circle)
			)
			(primitives
				(gr_poly
					(pts
						(arc
							(start -0.1778 -0.2794)
							(mid -0.249642 -0.249642)
							(end -0.2794 -0.1778)
						)
						(arc
							(start -0.2794 0.1778)
							(mid -0.249642 0.249642)
							(end -0.1778 0.2794)
						)
						(arc
							(start 0.1778 0.2794)
							(mid 0.249642 0.249642)
							(end 0.2794 0.1778)
						)
						(arc
							(start 0.2794 -0.1778)
							(mid 0.249642 -0.249642)
							(end 0.1778 -0.2794)
						)
					)
					(width 0)
					(fill yes)
				)
			)
		)
		(pad "2" smd custom
			(at 0 0.4445)
			(size 0.1397 0.1397)
			(layers "F.Cu" "F.Mask" "F.Paste")
			(net "MB0_HS_ENABLE")
			(options
				(clearance outline)
				(anchor circle)
			)
			(primitives
				(gr_poly
					(pts
						(arc
							(start -0.1778 -0.2794)
							(mid -0.249642 -0.249642)
							(end -0.2794 -0.1778)
						)
						(arc
							(start -0.2794 0.1778)
							(mid -0.249642 0.249642)
							(end -0.1778 0.2794)
						)
						(arc
							(start 0.1778 0.2794)
							(mid 0.249642 0.249642)
							(end 0.2794 0.1778)
						)
						(arc
							(start 0.2794 -0.1778)
							(mid 0.249642 -0.249642)
							(end 0.1778 -0.2794)
						)
					)
					(width 0)
					(fill yes)
				)
			)
		)
	)
	(footprint ""
		(layer "F.Cu")
		(at 75.438 -41.148 180)
		(property "Reference" "C288"
			(at 0 0 180)
			(layer "F.SilkS")
			(hide yes)
			(effects
				(font
					(size 1.27 1.27)
				)
			)
		)
		(property "Value" "SC22U6D3V3MX-9-GP-U"
			(at 0 -2.8194 180)
			(unlocked yes)
			(layer "F.Fab")
			(hide yes)
			(effects
				(font
					(size 1.016 1.016)
					(thickness 0.1524)
				)
			)
		)
		(property "Device Type" "C603H40"
			(at 0 -4.3434 180)
			(unlocked yes)
			(layer "F.Fab")
			(hide yes)
			(effects
				(font
					(size 1.016 1.016)
					(thickness 0.1524)
				)
			)
		)
		(duplicate_pad_numbers_are_jumpers no)
		(fp_line
			(start 0.508 0)
			(end -0.508 0)
			(stroke
				(width 0.2032)
				(type default)
			)
			(layer "F.SilkS")
		)
		(fp_rect
			(start -0.5842 1.3335)
			(end 0.5842 -1.3335)
			(stroke
				(width 0)
				(type default)
			)
			(fill no)
			(layer "F.CrtYd")
		)
		(fp_rect
			(start -0.5842 1.3335)
			(end 0.5842 -1.3335)
			(stroke
				(width 0)
				(type default)
			)
			(fill no)
			(layer "F.Fab")
		)
		(pad "1" smd custom
			(at 0 -0.762 180)
			(size 0.2159 0.2159)
			(layers "F.Cu" "F.Mask" "F.Paste")
			(net "GB_VDDA")
			(options
				(clearance outline)
				(anchor circle)
			)
			(primitives
				(gr_poly
					(pts
						(arc
							(start -0.3302 -0.4318)
							(mid -0.402042 -0.402042)
							(end -0.4318 -0.3302)
						)
						(arc
							(start -0.4318 0.3302)
							(mid -0.402042 0.402042)
							(end -0.3302 0.4318)
						)
						(arc
							(start 0.3302 0.4318)
							(mid 0.402042 0.402042)
							(end 0.4318 0.3302)
						)
						(arc
							(start 0.4318 -0.3302)
							(mid 0.402042 -0.402042)
							(end 0.3302 -0.4318)
						)
					)
					(width 0)
					(fill yes)
				)
			)
		)
		(pad "2" smd custom
			(at 0 0.762 180)
			(size 0.2159 0.2159)
			(layers "F.Cu" "F.Mask" "F.Paste")
			(net "GND")
			(options
				(clearance outline)
				(anchor circle)
			)
			(primitives
				(gr_poly
					(pts
						(arc
							(start -0.3302 -0.4318)
							(mid -0.402042 -0.402042)
							(end -0.4318 -0.3302)
						)
						(arc
							(start -0.4318 0.3302)
							(mid -0.402042 0.402042)
							(end -0.3302 0.4318)
						)
						(arc
							(start 0.3302 0.4318)
							(mid 0.402042 0.402042)
							(end 0.4318 0.3302)
						)
						(arc
							(start 0.4318 -0.3302)
							(mid 0.402042 -0.402042)
							(end 0.3302 -0.4318)
						)
					)
					(width 0)
					(fill yes)
				)
			)
		)
	)
	(footprint ""
		(layer "F.Cu")
		(at 60.67552 -17.414748 180)
		(property "Reference" "R575"
			(at 0 0 180)
			(layer "F.SilkS")
			(hide yes)
			(effects
				(font
					(size 1.27 1.27)
				)
			)
		)
		(property "Value" "10KR2F-2-GP"
			(at 0.064008 -3.993896 180)
			(unlocked yes)
			(layer "F.Fab")
			(hide yes)
			(effects
				(font
					(size 1.016 1.016)
					(thickness 0.1524)
				)
			)
		)
		(property "Device Type" "R402H16"
			(at 0.064008 -5.517896 180)
			(unlocked yes)
			(layer "F.Fab")
			(hide yes)
			(effects
				(font
					(size 1.016 1.016)
					(thickness 0.1524)
				)
			)
		)
		(duplicate_pad_numbers_are_jumpers no)
		(fp_line
			(start 0.508 -0.9398)
			(end -0.508 -0.9398)
			(stroke
				(width 0.1524)
				(type default)
			)
			(layer "F.SilkS")
		)
		(fp_line
			(start -0.508 -0.9398)
			(end -0.508 0.9398)
			(stroke
				(width 0.1524)
				(type default)
			)
			(layer "F.SilkS")
		)
		(fp_rect
			(start -0.508 0.9398)
			(end 0.508 -0.9398)
			(stroke
				(width 0)
				(type default)
			)
			(fill no)
			(layer "F.CrtYd")
		)
		(fp_rect
			(start -0.508 0.9398)
			(end 0.508 -0.9398)
			(stroke
				(width 0)
				(type default)
			)
			(fill no)
			(layer "F.Fab")
		)
		(pad "1" smd custom
			(at 0 -0.4445 180)
			(size 0.1397 0.1397)
			(layers "F.Cu" "F.Mask" "F.Paste")
			(net "P3V3")
			(options
				(clearance outline)
				(anchor circle)
			)
			(primitives
				(gr_poly
					(pts
						(arc
							(start -0.1778 -0.2794)
							(mid -0.249642 -0.249642)
							(end -0.2794 -0.1778)
						)
						(arc
							(start -0.2794 0.1778)
							(mid -0.249642 0.249642)
							(end -0.1778 0.2794)
						)
						(arc
							(start 0.1778 0.2794)
							(mid 0.249642 0.249642)
							(end 0.2794 0.1778)
						)
						(arc
							(start 0.2794 -0.1778)
							(mid 0.249642 -0.249642)
							(end 0.1778 -0.2794)
						)
					)
					(width 0)
					(fill yes)
				)
			)
		)
		(pad "2" smd custom
			(at 0 0.4445 180)
			(size 0.1397 0.1397)
			(layers "F.Cu" "F.Mask" "F.Paste")
			(net "U49_OE")
			(options
				(clearance outline)
				(anchor circle)
			)
			(primitives
				(gr_poly
					(pts
						(arc
							(start -0.1778 -0.2794)
							(mid -0.249642 -0.249642)
							(end -0.2794 -0.1778)
						)
						(arc
							(start -0.2794 0.1778)
							(mid -0.249642 0.249642)
							(end -0.1778 0.2794)
						)
						(arc
							(start 0.1778 0.2794)
							(mid 0.249642 0.249642)
							(end 0.2794 0.1778)
						)
						(arc
							(start 0.2794 -0.1778)
							(mid 0.249642 -0.249642)
							(end 0.1778 -0.2794)
						)
					)
					(width 0)
					(fill yes)
				)
			)
		)
	)
	(footprint ""
		(layer "F.Cu")
		(at 22.1742 -57.2516 180)
		(property "Reference" "R521"
			(at 0 0 180)
			(layer "F.SilkS")
			(hide yes)
			(effects
				(font
					(size 1.27 1.27)
				)
			)
		)
		(property "Value" "38K3R2F-GP"
			(at 0.064008 -3.993896 180)
			(unlocked yes)
			(layer "F.Fab")
			(hide yes)
			(effects
				(font
					(size 1.016 1.016)
					(thickness 0.1524)
				)
			)
		)
		(property "Device Type" "R402H16"
			(at 0.064008 -5.517896 180)
			(unlocked yes)
			(layer "F.Fab")
			(hide yes)
			(effects
				(font
					(size 1.016 1.016)
					(thickness 0.1524)
				)
			)
		)
		(duplicate_pad_numbers_are_jumpers no)
		(fp_line
			(start 0.508 -0.9398)
			(end -0.508 -0.9398)
			(stroke
				(width 0.1524)
				(type default)
			)
			(layer "F.SilkS")
		)
		(fp_line
			(start -0.508 -0.9398)
			(end -0.508 0.9398)
			(stroke
				(width 0.1524)
				(type default)
			)
			(layer "F.SilkS")
		)
		(fp_rect
			(start -0.508 0.9398)
			(end 0.508 -0.9398)
			(stroke
				(width 0)
				(type default)
			)
			(fill no)
			(layer "F.CrtYd")
		)
		(fp_rect
			(start -0.508 0.9398)
			(end 0.508 -0.9398)
			(stroke
				(width 0)
				(type default)
			)
			(fill no)
			(layer "F.Fab")
		)
		(pad "1" smd custom
			(at 0 -0.4445 180)
			(size 0.1397 0.1397)
			(layers "F.Cu" "F.Mask" "F.Paste")
			(net "MB0_ISTART_R")
			(options
				(clearance outline)
				(anchor circle)
			)
			(primitives
				(gr_poly
					(pts
						(arc
							(start -0.1778 -0.2794)
							(mid -0.249642 -0.249642)
							(end -0.2794 -0.1778)
						)
						(arc
							(start -0.2794 0.1778)
							(mid -0.249642 0.249642)
							(end -0.1778 0.2794)
						)
						(arc
							(start 0.1778 0.2794)
							(mid 0.249642 0.249642)
							(end 0.2794 0.1778)
						)
						(arc
							(start 0.2794 -0.1778)
							(mid 0.249642 -0.249642)
							(end 0.1778 -0.2794)
						)
					)
					(width 0)
					(fill yes)
				)
			)
		)
		(pad "2" smd custom
			(at 0 0.4445 180)
			(size 0.1397 0.1397)
			(layers "F.Cu" "F.Mask" "F.Paste")
			(net "AGND_CURRENT_MON")
			(options
				(clearance outline)
				(anchor circle)
			)
			(primitives
				(gr_poly
					(pts
						(arc
							(start -0.1778 -0.2794)
							(mid -0.249642 -0.249642)
							(end -0.2794 -0.1778)
						)
						(arc
							(start -0.2794 0.1778)
							(mid -0.249642 0.249642)
							(end -0.1778 0.2794)
						)
						(arc
							(start 0.1778 0.2794)
							(mid 0.249642 0.249642)
							(end 0.2794 0.1778)
						)
						(arc
							(start 0.2794 -0.1778)
							(mid 0.249642 -0.249642)
							(end 0.1778 -0.2794)
						)
					)
					(width 0)
					(fill yes)
				)
			)
		)
	)
	(footprint ""
		(layer "F.Cu")
		(at 197.72376 -71.22414)
		(property "Reference" "C510"
			(at 0 0 0)
			(layer "F.SilkS")
			(hide yes)
			(effects
				(font
					(size 1.27 1.27)
				)
			)
		)
		(property "Value" "SCD1U16V2KX-3GP"
			(at 1.1811 -2.7051 0)
			(unlocked yes)
			(layer "F.Fab")
			(hide yes)
			(effects
				(font
					(size 1.016 1.016)
					(thickness 0.1524)
				)
			)
		)
		(property "Device Type" "C402H22"
			(at 1.1811 -4.2291 0)
			(unlocked yes)
			(layer "F.Fab")
			(hide yes)
			(effects
				(font
					(size 1.016 1.016)
					(thickness 0.1524)
				)
			)
		)
		(duplicate_pad_numbers_are_jumpers no)
		(fp_rect
			(start -0.4318 0.9525)
			(end 0.4318 -0.9525)
			(stroke
				(width 0)
				(type default)
			)
			(fill no)
			(layer "F.CrtYd")
		)
		(fp_rect
			(start -0.4318 0.9525)
			(end 0.4318 -0.9525)
			(stroke
				(width 0)
				(type default)
			)
			(fill no)
			(layer "F.Fab")
		)
		(pad "1" smd custom
			(at 0 -0.4445)
			(size 0.1524 0.1524)
			(layers "F.Cu" "F.Mask" "F.Paste")
			(net "P1V8_C")
			(options
				(clearance outline)
				(anchor circle)
			)
			(primitives
				(gr_poly
					(pts
						(arc
							(start 0.3048 -0.2032)
							(mid 0.275042 -0.275042)
							(end 0.2032 -0.3048)
						)
						(arc
							(start -0.2032 -0.3048)
							(mid -0.275042 -0.275042)
							(end -0.3048 -0.2032)
						)
						(arc
							(start -0.3048 0.2032)
							(mid -0.275042 0.275042)
							(end -0.2032 0.3048)
						)
						(arc
							(start 0.2032 0.3048)
							(mid 0.275042 0.275042)
							(end 0.3048 0.2032)
						)
					)
					(width 0)
					(fill yes)
				)
			)
		)
		(pad "2" smd custom
			(at 0 0.4445)
			(size 0.1524 0.1524)
			(layers "F.Cu" "F.Mask" "F.Paste")
			(net "GND")
			(options
				(clearance outline)
				(anchor circle)
			)
			(primitives
				(gr_poly
					(pts
						(arc
							(start 0.3048 -0.2032)
							(mid 0.275042 -0.275042)
							(end 0.2032 -0.3048)
						)
						(arc
							(start -0.2032 -0.3048)
							(mid -0.275042 -0.275042)
							(end -0.3048 -0.2032)
						)
						(arc
							(start -0.3048 0.2032)
							(mid -0.275042 0.275042)
							(end -0.2032 0.3048)
						)
						(arc
							(start 0.2032 0.3048)
							(mid 0.275042 0.275042)
							(end 0.3048 0.2032)
						)
					)
					(width 0)
					(fill yes)
				)
			)
		)
	)
	(footprint ""
		(layer "F.Cu")
		(at 21.7932 -54.3052 -90)
		(property "Reference" "R17"
			(at 0 0 270)
			(layer "F.SilkS")
			(hide yes)
			(effects
				(font
					(size 1.27 1.27)
				)
			)
		)
		(property "Value" "100KR2J-4-GP"
			(at 0.064008 -3.993896 270)
			(unlocked yes)
			(layer "F.Fab")
			(hide yes)
			(effects
				(font
					(size 1.016 1.016)
					(thickness 0.1524)
				)
			)
		)
		(property "Device Type" "R402H15"
			(at 0.064008 -5.517896 270)
			(unlocked yes)
			(layer "F.Fab")
			(hide yes)
			(effects
				(font
					(size 1.016 1.016)
					(thickness 0.1524)
				)
			)
		)
		(duplicate_pad_numbers_are_jumpers no)
		(fp_line
			(start -0.508 -0.9398)
			(end -0.508 0.9398)
			(stroke
				(width 0.1524)
				(type default)
			)
			(layer "F.SilkS")
		)
		(fp_line
			(start 0.508 -0.9398)
			(end -0.508 -0.9398)
			(stroke
				(width 0.1524)
				(type default)
			)
			(layer "F.SilkS")
		)
		(fp_rect
			(start -0.508 0.9398)
			(end 0.508 -0.9398)
			(stroke
				(width 0)
				(type default)
			)
			(fill no)
			(layer "F.CrtYd")
		)
		(fp_rect
			(start -0.508 0.9398)
			(end 0.508 -0.9398)
			(stroke
				(width 0)
				(type default)
			)
			(fill no)
			(layer "F.Fab")
		)
		(pad "1" smd custom
			(at 0 -0.4445 270)
			(size 0.1397 0.1397)
			(layers "F.Cu" "F.Mask" "F.Paste")
			(net "MB0_VCAP_R")
			(options
				(clearance outline)
				(anchor circle)
			)
			(primitives
				(gr_poly
					(pts
						(arc
							(start -0.1778 -0.2794)
							(mid -0.249642 -0.249642)
							(end -0.2794 -0.1778)
						)
						(arc
							(start -0.2794 0.1778)
							(mid -0.249642 0.249642)
							(end -0.1778 0.2794)
						)
						(arc
							(start 0.1778 0.2794)
							(mid 0.249642 0.249642)
							(end 0.2794 0.1778)
						)
						(arc
							(start 0.2794 -0.1778)
							(mid 0.249642 -0.249642)
							(end 0.1778 -0.2794)
						)
					)
					(width 0)
					(fill yes)
				)
			)
		)
		(pad "2" smd custom
			(at 0 0.4445 270)
			(size 0.1397 0.1397)
			(layers "F.Cu" "F.Mask" "F.Paste")
			(net "MB0_ISET_R")
			(options
				(clearance outline)
				(anchor circle)
			)
			(primitives
				(gr_poly
					(pts
						(arc
							(start -0.1778 -0.2794)
							(mid -0.249642 -0.249642)
							(end -0.2794 -0.1778)
						)
						(arc
							(start -0.2794 0.1778)
							(mid -0.249642 0.249642)
							(end -0.1778 0.2794)
						)
						(arc
							(start 0.1778 0.2794)
							(mid 0.249642 0.249642)
							(end 0.2794 0.1778)
						)
						(arc
							(start 0.2794 -0.1778)
							(mid 0.249642 -0.249642)
							(end 0.1778 -0.2794)
						)
					)
					(width 0)
					(fill yes)
				)
			)
		)
	)
	(footprint ""
		(layer "F.Cu")
		(at 191.035432 -39.1414 -90)
		(property "Reference" "R179"
			(at 0 0 270)
			(layer "F.SilkS")
			(hide yes)
			(effects
				(font
					(size 1.27 1.27)
				)
			)
		)
		(property "Value" "2K2R2F-GP"
			(at 0.064008 -3.993896 270)
			(unlocked yes)
			(layer "F.Fab")
			(hide yes)
			(effects
				(font
					(size 1.016 1.016)
					(thickness 0.1524)
				)
			)
		)
		(property "Device Type" "R402H16"
			(at 0.064008 -5.517896 270)
			(unlocked yes)
			(layer "F.Fab")
			(hide yes)
			(effects
				(font
					(size 1.016 1.016)
					(thickness 0.1524)
				)
			)
		)
		(duplicate_pad_numbers_are_jumpers no)
		(fp_line
			(start -0.508 -0.9398)
			(end -0.508 0.9398)
			(stroke
				(width 0.1524)
				(type default)
			)
			(layer "F.SilkS")
		)
		(fp_line
			(start 0.508 -0.9398)
			(end -0.508 -0.9398)
			(stroke
				(width 0.1524)
				(type default)
			)
			(layer "F.SilkS")
		)
		(fp_rect
			(start -0.508 0.9398)
			(end 0.508 -0.9398)
			(stroke
				(width 0)
				(type default)
			)
			(fill no)
			(layer "F.CrtYd")
		)
		(fp_rect
			(start -0.508 0.9398)
			(end 0.508 -0.9398)
			(stroke
				(width 0)
				(type default)
			)
			(fill no)
			(layer "F.Fab")
		)
		(pad "1" smd custom
			(at 0 -0.4445 270)
			(size 0.1397 0.1397)
			(layers "F.Cu" "F.Mask" "F.Paste")
			(net "P1V8_C")
			(options
				(clearance outline)
				(anchor circle)
			)
			(primitives
				(gr_poly
					(pts
						(arc
							(start -0.1778 -0.2794)
							(mid -0.249642 -0.249642)
							(end -0.2794 -0.1778)
						)
						(arc
							(start -0.2794 0.1778)
							(mid -0.249642 0.249642)
							(end -0.1778 0.2794)
						)
						(arc
							(start 0.1778 0.2794)
							(mid 0.249642 0.249642)
							(end 0.2794 0.1778)
						)
						(arc
							(start 0.2794 -0.1778)
							(mid 0.249642 -0.249642)
							(end 0.1778 -0.2794)
						)
					)
					(width 0)
					(fill yes)
				)
			)
		)
		(pad "2" smd custom
			(at 0 0.4445 270)
			(size 0.1397 0.1397)
			(layers "F.Cu" "F.Mask" "F.Paste")
			(net "SBL_SCL")
			(options
				(clearance outline)
				(anchor circle)
			)
			(primitives
				(gr_poly
					(pts
						(arc
							(start -0.1778 -0.2794)
							(mid -0.249642 -0.249642)
							(end -0.2794 -0.1778)
						)
						(arc
							(start -0.2794 0.1778)
							(mid -0.249642 0.249642)
							(end -0.1778 0.2794)
						)
						(arc
							(start 0.1778 0.2794)
							(mid 0.249642 0.249642)
							(end 0.2794 0.1778)
						)
						(arc
							(start 0.2794 -0.1778)
							(mid 0.249642 -0.249642)
							(end 0.1778 -0.2794)
						)
					)
					(width 0)
					(fill yes)
				)
			)
		)
	)
	(footprint ""
		(layer "F.Cu")
		(at 68.838572 -100.463096 -90)
		(property "Reference" "G3"
			(at 0 0 270)
			(layer "F.SilkS")
			(hide yes)
			(effects
				(font
					(size 1.27 1.27)
				)
			)
		)
		(property "Value" "COPPER-CLOSE-GP-U"
			(at 0.0762 -2.8702 270)
			(unlocked yes)
			(layer "F.Fab")
			(hide yes)
			(effects
				(font
					(size 1.016 1.016)
					(thickness 0.1524)
				)
			)
		)
		(property "Device Type" "CON2C-U"
			(at 0.0762 -4.3942 270)
			(unlocked yes)
			(layer "F.Fab")
			(hide yes)
			(effects
				(font
					(size 1.016 1.016)
					(thickness 0.1524)
				)
			)
		)
		(duplicate_pad_numbers_are_jumpers no)
		(fp_rect
			(start -0.9398 0.9652)
			(end 0.9398 -0.9652)
			(stroke
				(width 0)
				(type default)
			)
			(fill no)
			(layer "F.CrtYd")
		)
		(fp_rect
			(start -0.9398 0.9652)
			(end 0.9398 -0.9652)
			(stroke
				(width 0)
				(type default)
			)
			(fill no)
			(layer "F.Fab")
		)
		(pad "1" smd custom
			(at 0 -0.5334 270)
			(size 0.17145 0.17145)
			(layers "F.Cu" "F.Mask" "F.Paste")
			(net "AGND_P3V3")
			(options
				(clearance outline)
				(anchor circle)
			)
			(primitives
				(gr_poly
					(pts
						(xy -0.127 0.3429) (xy -0.127 0.1651) (xy -0.635 -0.3429) (xy 0.635 -0.3429) (xy 0.127 0.1651)
						(xy 0.127 0.3429)
					)
					(width 0)
					(fill yes)
				)
			)
		)
		(pad "2" smd custom
			(at 0 0.5334 270)
			(size 0.17145 0.17145)
			(layers "F.Cu" "F.Mask" "F.Paste")
			(net "GND")
			(options
				(clearance outline)
				(anchor circle)
			)
			(primitives
				(gr_poly
					(pts
						(xy -0.635 0.3429) (xy -0.127 -0.1651) (xy -0.127 -0.3429) (xy 0.127 -0.3429) (xy 0.127 -0.1651)
						(xy 0.635 0.3429)
					)
					(width 0)
					(fill yes)
				)
			)
		)
	)
	(footprint ""
		(layer "F.Cu")
		(at 58.9788 -94.0054 -90)
		(property "Reference" "C702"
			(at 0 0 270)
			(layer "F.SilkS")
			(hide yes)
			(effects
				(font
					(size 1.27 1.27)
				)
			)
		)
		(property "Value" "SC10U16V5KX-7-GP-U"
			(at -0.0762 -6.1214 270)
			(unlocked yes)
			(layer "F.Fab")
			(hide yes)
			(effects
				(font
					(size 1.016 1.016)
					(thickness 0.1524)
				)
			)
		)
		(property "Device Type" "C805H58"
			(at -0.0762 -8.1534 270)
			(unlocked yes)
			(layer "F.Fab")
			(hide yes)
			(effects
				(font
					(size 1.016 1.016)
					(thickness 0.1524)
				)
			)
		)
		(duplicate_pad_numbers_are_jumpers no)
		(fp_line
			(start 0.635 0)
			(end -0.635 0)
			(stroke
				(width 0.508)
				(type default)
			)
			(layer "F.SilkS")
		)
		(fp_rect
			(start -0.9652 1.778)
			(end 0.9652 -1.778)
			(stroke
				(width 0)
				(type default)
			)
			(fill no)
			(layer "F.CrtYd")
		)
		(fp_poly
			(pts
				(xy -0.9652 -1.778) (xy 0.9652 -1.778) (xy 0.9652 1.778) (xy -0.9652 1.778)
			)
			(stroke
				(width 0)
				(type default)
			)
			(fill no)
			(layer "F.Fab")
		)
		(pad "1" smd rect
			(at 0 -0.9652 270)
			(size 1.397 1.143)
			(layers "F.Cu" "F.Mask" "F.Paste")
			(net "P12V_STBY_VIN_U10")
		)
		(pad "2" smd rect
			(at 0 0.9652 270)
			(size 1.397 1.143)
			(layers "F.Cu" "F.Mask" "F.Paste")
			(net "GND")
		)
	)
	(footprint ""
		(layer "F.Cu")
		(at 101.6762 -87.2236 180)
		(property "Reference" "R73"
			(at 0 0 180)
			(layer "F.SilkS")
			(hide yes)
			(effects
				(font
					(size 1.27 1.27)
				)
			)
		)
		(property "Value" "4K7R2F-GP"
			(at 0.064008 -3.993896 180)
			(unlocked yes)
			(layer "F.Fab")
			(hide yes)
			(effects
				(font
					(size 1.016 1.016)
					(thickness 0.1524)
				)
			)
		)
		(property "Device Type" "R402H16"
			(at 0.064008 -5.517896 180)
			(unlocked yes)
			(layer "F.Fab")
			(hide yes)
			(effects
				(font
					(size 1.016 1.016)
					(thickness 0.1524)
				)
			)
		)
		(duplicate_pad_numbers_are_jumpers no)
		(fp_line
			(start 0.508 -0.9398)
			(end -0.508 -0.9398)
			(stroke
				(width 0.1524)
				(type default)
			)
			(layer "F.SilkS")
		)
		(fp_line
			(start -0.508 -0.9398)
			(end -0.508 0.9398)
			(stroke
				(width 0.1524)
				(type default)
			)
			(layer "F.SilkS")
		)
		(fp_rect
			(start -0.508 0.9398)
			(end 0.508 -0.9398)
			(stroke
				(width 0)
				(type default)
			)
			(fill no)
			(layer "F.CrtYd")
		)
		(fp_rect
			(start -0.508 0.9398)
			(end 0.508 -0.9398)
			(stroke
				(width 0)
				(type default)
			)
			(fill no)
			(layer "F.Fab")
		)
		(pad "1" smd custom
			(at 0 -0.4445 180)
			(size 0.1397 0.1397)
			(layers "F.Cu" "F.Mask" "F.Paste")
			(net "P1V8_E")
			(options
				(clearance outline)
				(anchor circle)
			)
			(primitives
				(gr_poly
					(pts
						(arc
							(start -0.1778 -0.2794)
							(mid -0.249642 -0.249642)
							(end -0.2794 -0.1778)
						)
						(arc
							(start -0.2794 0.1778)
							(mid -0.249642 0.249642)
							(end -0.1778 0.2794)
						)
						(arc
							(start 0.1778 0.2794)
							(mid 0.249642 0.249642)
							(end 0.2794 0.1778)
						)
						(arc
							(start 0.2794 -0.1778)
							(mid 0.249642 -0.249642)
							(end 0.1778 -0.2794)
						)
					)
					(width 0)
					(fill yes)
				)
			)
		)
		(pad "2" smd custom
			(at 0 0.4445 180)
			(size 0.1397 0.1397)
			(layers "F.Cu" "F.Mask" "F.Paste")
			(net "SCC_TYPE_1_LS")
			(options
				(clearance outline)
				(anchor circle)
			)
			(primitives
				(gr_poly
					(pts
						(arc
							(start -0.1778 -0.2794)
							(mid -0.249642 -0.249642)
							(end -0.2794 -0.1778)
						)
						(arc
							(start -0.2794 0.1778)
							(mid -0.249642 0.249642)
							(end -0.1778 0.2794)
						)
						(arc
							(start 0.1778 0.2794)
							(mid 0.249642 0.249642)
							(end 0.2794 0.1778)
						)
						(arc
							(start 0.2794 -0.1778)
							(mid 0.249642 -0.249642)
							(end 0.1778 -0.2794)
						)
					)
					(width 0)
					(fill yes)
				)
			)
		)
	)
	(footprint ""
		(layer "F.Cu")
		(at 92.583 -75.9968 90)
		(property "Reference" "R123"
			(at 0 0 90)
			(layer "F.SilkS")
			(hide yes)
			(effects
				(font
					(size 1.27 1.27)
				)
			)
		)
		(property "Value" "4K75R2F-1-GP"
			(at 0.064008 -3.993896 90)
			(unlocked yes)
			(layer "F.Fab")
			(hide yes)
			(effects
				(font
					(size 1.016 1.016)
					(thickness 0.1524)
				)
			)
		)
		(property "Device Type" "R402H16"
			(at 0.064008 -5.517896 90)
			(unlocked yes)
			(layer "F.Fab")
			(hide yes)
			(effects
				(font
					(size 1.016 1.016)
					(thickness 0.1524)
				)
			)
		)
		(duplicate_pad_numbers_are_jumpers no)
		(fp_line
			(start 0.508 -0.9398)
			(end -0.508 -0.9398)
			(stroke
				(width 0.1524)
				(type default)
			)
			(layer "F.SilkS")
		)
		(fp_line
			(start -0.508 -0.9398)
			(end -0.508 0.9398)
			(stroke
				(width 0.1524)
				(type default)
			)
			(layer "F.SilkS")
		)
		(fp_rect
			(start -0.508 0.9398)
			(end 0.508 -0.9398)
			(stroke
				(width 0)
				(type default)
			)
			(fill no)
			(layer "F.CrtYd")
		)
		(fp_rect
			(start -0.508 0.9398)
			(end 0.508 -0.9398)
			(stroke
				(width 0)
				(type default)
			)
			(fill no)
			(layer "F.Fab")
		)
		(pad "1" smd custom
			(at 0 -0.4445 90)
			(size 0.1397 0.1397)
			(layers "F.Cu" "F.Mask" "F.Paste")
			(net "P1V8_E")
			(options
				(clearance outline)
				(anchor circle)
			)
			(primitives
				(gr_poly
					(pts
						(arc
							(start -0.1778 -0.2794)
							(mid -0.249642 -0.249642)
							(end -0.2794 -0.1778)
						)
						(arc
							(start -0.2794 0.1778)
							(mid -0.249642 0.249642)
							(end -0.1778 0.2794)
						)
						(arc
							(start 0.1778 0.2794)
							(mid 0.249642 0.249642)
							(end 0.2794 0.1778)
						)
						(arc
							(start 0.2794 -0.1778)
							(mid 0.249642 -0.249642)
							(end 0.1778 -0.2794)
						)
					)
					(width 0)
					(fill yes)
				)
			)
		)
		(pad "2" smd custom
			(at 0 0.4445 90)
			(size 0.1397 0.1397)
			(layers "F.Cu" "F.Mask" "F.Paste")
			(net "EXP_CLK_SEL0")
			(options
				(clearance outline)
				(anchor circle)
			)
			(primitives
				(gr_poly
					(pts
						(arc
							(start -0.1778 -0.2794)
							(mid -0.249642 -0.249642)
							(end -0.2794 -0.1778)
						)
						(arc
							(start -0.2794 0.1778)
							(mid -0.249642 0.249642)
							(end -0.1778 0.2794)
						)
						(arc
							(start 0.1778 0.2794)
							(mid 0.249642 0.249642)
							(end 0.2794 0.1778)
						)
						(arc
							(start 0.2794 -0.1778)
							(mid 0.249642 -0.249642)
							(end 0.1778 -0.2794)
						)
					)
					(width 0)
					(fill yes)
				)
			)
		)
	)
	(footprint ""
		(layer "F.Cu")
		(at 75.311 -46.5582)
		(property "Reference" "C296"
			(at 0 0 0)
			(layer "F.SilkS")
			(hide yes)
			(effects
				(font
					(size 1.27 1.27)
				)
			)
		)
		(property "Value" "SC22U6D3V3MX-9-GP-U"
			(at 0 -2.8194 0)
			(unlocked yes)
			(layer "F.Fab")
			(hide yes)
			(effects
				(font
					(size 1.016 1.016)
					(thickness 0.1524)
				)
			)
		)
		(property "Device Type" "C603H40"
			(at 0 -4.3434 0)
			(unlocked yes)
			(layer "F.Fab")
			(hide yes)
			(effects
				(font
					(size 1.016 1.016)
					(thickness 0.1524)
				)
			)
		)
		(duplicate_pad_numbers_are_jumpers no)
		(fp_line
			(start 0.508 0)
			(end -0.508 0)
			(stroke
				(width 0.2032)
				(type default)
			)
			(layer "F.SilkS")
		)
		(fp_rect
			(start -0.5842 1.3335)
			(end 0.5842 -1.3335)
			(stroke
				(width 0)
				(type default)
			)
			(fill no)
			(layer "F.CrtYd")
		)
		(fp_rect
			(start -0.5842 1.3335)
			(end 0.5842 -1.3335)
			(stroke
				(width 0)
				(type default)
			)
			(fill no)
			(layer "F.Fab")
		)
		(pad "1" smd custom
			(at 0 -0.762)
			(size 0.2159 0.2159)
			(layers "F.Cu" "F.Mask" "F.Paste")
			(net "GB_VDDA")
			(options
				(clearance outline)
				(anchor circle)
			)
			(primitives
				(gr_poly
					(pts
						(arc
							(start -0.3302 -0.4318)
							(mid -0.402042 -0.402042)
							(end -0.4318 -0.3302)
						)
						(arc
							(start -0.4318 0.3302)
							(mid -0.402042 0.402042)
							(end -0.3302 0.4318)
						)
						(arc
							(start 0.3302 0.4318)
							(mid 0.402042 0.402042)
							(end 0.4318 0.3302)
						)
						(arc
							(start 0.4318 -0.3302)
							(mid 0.402042 -0.402042)
							(end 0.3302 -0.4318)
						)
					)
					(width 0)
					(fill yes)
				)
			)
		)
		(pad "2" smd custom
			(at 0 0.762)
			(size 0.2159 0.2159)
			(layers "F.Cu" "F.Mask" "F.Paste")
			(net "GND")
			(options
				(clearance outline)
				(anchor circle)
			)
			(primitives
				(gr_poly
					(pts
						(arc
							(start -0.3302 -0.4318)
							(mid -0.402042 -0.402042)
							(end -0.4318 -0.3302)
						)
						(arc
							(start -0.4318 0.3302)
							(mid -0.402042 0.402042)
							(end -0.3302 0.4318)
						)
						(arc
							(start 0.3302 0.4318)
							(mid 0.402042 0.402042)
							(end 0.4318 0.3302)
						)
						(arc
							(start 0.4318 -0.3302)
							(mid 0.402042 -0.402042)
							(end 0.3302 -0.4318)
						)
					)
					(width 0)
					(fill yes)
				)
			)
		)
	)
	(footprint ""
		(layer "F.Cu")
		(at 15.3416 -93.5736)
		(property "Reference" "R431"
			(at 0 0 0)
			(layer "F.SilkS")
			(hide yes)
			(effects
				(font
					(size 1.27 1.27)
				)
			)
		)
		(property "Value" "1KR2F-3-GP"
			(at 0.064008 -3.993896 0)
			(unlocked yes)
			(layer "F.Fab")
			(hide yes)
			(effects
				(font
					(size 1.016 1.016)
					(thickness 0.1524)
				)
			)
		)
		(property "Device Type" "R402H16"
			(at 0.064008 -5.517896 0)
			(unlocked yes)
			(layer "F.Fab")
			(hide yes)
			(effects
				(font
					(size 1.016 1.016)
					(thickness 0.1524)
				)
			)
		)
		(duplicate_pad_numbers_are_jumpers no)
		(fp_line
			(start -0.508 -0.9398)
			(end -0.508 0.9398)
			(stroke
				(width 0.1524)
				(type default)
			)
			(layer "F.SilkS")
		)
		(fp_line
			(start 0.508 -0.9398)
			(end -0.508 -0.9398)
			(stroke
				(width 0.1524)
				(type default)
			)
			(layer "F.SilkS")
		)
		(fp_rect
			(start -0.508 0.9398)
			(end 0.508 -0.9398)
			(stroke
				(width 0)
				(type default)
			)
			(fill no)
			(layer "F.CrtYd")
		)
		(fp_rect
			(start -0.508 0.9398)
			(end 0.508 -0.9398)
			(stroke
				(width 0)
				(type default)
			)
			(fill no)
			(layer "F.Fab")
		)
		(pad "1" smd custom
			(at 0 -0.4445)
			(size 0.1397 0.1397)
			(layers "F.Cu" "F.Mask" "F.Paste")
			(net "P3V3")
			(options
				(clearance outline)
				(anchor circle)
			)
			(primitives
				(gr_poly
					(pts
						(arc
							(start -0.1778 -0.2794)
							(mid -0.249642 -0.249642)
							(end -0.2794 -0.1778)
						)
						(arc
							(start -0.2794 0.1778)
							(mid -0.249642 0.249642)
							(end -0.1778 0.2794)
						)
						(arc
							(start 0.1778 0.2794)
							(mid 0.249642 0.249642)
							(end 0.2794 0.1778)
						)
						(arc
							(start 0.2794 -0.1778)
							(mid 0.249642 -0.249642)
							(end 0.1778 -0.2794)
						)
					)
					(width 0)
					(fill yes)
				)
			)
		)
		(pad "2" smd custom
			(at 0 0.4445)
			(size 0.1397 0.1397)
			(layers "F.Cu" "F.Mask" "F.Paste")
			(net "I2C_DPB_SDA3")
			(options
				(clearance outline)
				(anchor circle)
			)
			(primitives
				(gr_poly
					(pts
						(arc
							(start -0.1778 -0.2794)
							(mid -0.249642 -0.249642)
							(end -0.2794 -0.1778)
						)
						(arc
							(start -0.2794 0.1778)
							(mid -0.249642 0.249642)
							(end -0.1778 0.2794)
						)
						(arc
							(start 0.1778 0.2794)
							(mid 0.249642 0.249642)
							(end 0.2794 0.1778)
						)
						(arc
							(start 0.2794 -0.1778)
							(mid 0.249642 -0.249642)
							(end 0.1778 -0.2794)
						)
					)
					(width 0)
					(fill yes)
				)
			)
		)
	)
	(footprint ""
		(layer "F.Cu")
		(at 61.0108 -77.4954 180)
		(property "Reference" "R437"
			(at 0 0 180)
			(layer "F.SilkS")
			(hide yes)
			(effects
				(font
					(size 1.27 1.27)
				)
			)
		)
		(property "Value" "200KR2F-L-GP"
			(at 0.064008 -3.993896 180)
			(unlocked yes)
			(layer "F.Fab")
			(hide yes)
			(effects
				(font
					(size 1.016 1.016)
					(thickness 0.1524)
				)
			)
		)
		(property "Device Type" "R402H16"
			(at 0.064008 -5.517896 180)
			(unlocked yes)
			(layer "F.Fab")
			(hide yes)
			(effects
				(font
					(size 1.016 1.016)
					(thickness 0.1524)
				)
			)
		)
		(duplicate_pad_numbers_are_jumpers no)
		(fp_line
			(start 0.508 -0.9398)
			(end -0.508 -0.9398)
			(stroke
				(width 0.1524)
				(type default)
			)
			(layer "F.SilkS")
		)
		(fp_line
			(start -0.508 -0.9398)
			(end -0.508 0.9398)
			(stroke
				(width 0.1524)
				(type default)
			)
			(layer "F.SilkS")
		)
		(fp_rect
			(start -0.508 0.9398)
			(end 0.508 -0.9398)
			(stroke
				(width 0)
				(type default)
			)
			(fill no)
			(layer "F.CrtYd")
		)
		(fp_rect
			(start -0.508 0.9398)
			(end 0.508 -0.9398)
			(stroke
				(width 0)
				(type default)
			)
			(fill no)
			(layer "F.Fab")
		)
		(pad "1" smd custom
			(at 0 -0.4445 180)
			(size 0.1397 0.1397)
			(layers "F.Cu" "F.Mask" "F.Paste")
			(net "LS_EN_U37")
			(options
				(clearance outline)
				(anchor circle)
			)
			(primitives
				(gr_poly
					(pts
						(arc
							(start -0.1778 -0.2794)
							(mid -0.249642 -0.249642)
							(end -0.2794 -0.1778)
						)
						(arc
							(start -0.2794 0.1778)
							(mid -0.249642 0.249642)
							(end -0.1778 0.2794)
						)
						(arc
							(start 0.1778 0.2794)
							(mid 0.249642 0.249642)
							(end 0.2794 0.1778)
						)
						(arc
							(start 0.2794 -0.1778)
							(mid 0.249642 -0.249642)
							(end 0.1778 -0.2794)
						)
					)
					(width 0)
					(fill yes)
				)
			)
		)
		(pad "2" smd custom
			(at 0 0.4445 180)
			(size 0.1397 0.1397)
			(layers "F.Cu" "F.Mask" "F.Paste")
			(net "P0V9_PG")
			(options
				(clearance outline)
				(anchor circle)
			)
			(primitives
				(gr_poly
					(pts
						(arc
							(start -0.1778 -0.2794)
							(mid -0.249642 -0.249642)
							(end -0.2794 -0.1778)
						)
						(arc
							(start -0.2794 0.1778)
							(mid -0.249642 0.249642)
							(end -0.1778 0.2794)
						)
						(arc
							(start 0.1778 0.2794)
							(mid 0.249642 0.249642)
							(end 0.2794 0.1778)
						)
						(arc
							(start 0.2794 -0.1778)
							(mid 0.249642 -0.249642)
							(end 0.1778 -0.2794)
						)
					)
					(width 0)
					(fill yes)
				)
			)
		)
	)
	(footprint ""
		(layer "F.Cu")
		(at 191.85382 -53.3908 90)
		(property "Reference" "R225"
			(at 0 0 90)
			(layer "F.SilkS")
			(hide yes)
			(effects
				(font
					(size 1.27 1.27)
				)
			)
		)
		(property "Value" "10KR2F-2-GP"
			(at 0.064008 -3.993896 90)
			(unlocked yes)
			(layer "F.Fab")
			(hide yes)
			(effects
				(font
					(size 1.016 1.016)
					(thickness 0.1524)
				)
			)
		)
		(property "Device Type" "R402H16"
			(at 0.064008 -5.517896 90)
			(unlocked yes)
			(layer "F.Fab")
			(hide yes)
			(effects
				(font
					(size 1.016 1.016)
					(thickness 0.1524)
				)
			)
		)
		(duplicate_pad_numbers_are_jumpers no)
		(fp_line
			(start 0.508 -0.9398)
			(end -0.508 -0.9398)
			(stroke
				(width 0.1524)
				(type default)
			)
			(layer "F.SilkS")
		)
		(fp_line
			(start -0.508 -0.9398)
			(end -0.508 0.9398)
			(stroke
				(width 0.1524)
				(type default)
			)
			(layer "F.SilkS")
		)
		(fp_rect
			(start -0.508 0.9398)
			(end 0.508 -0.9398)
			(stroke
				(width 0)
				(type default)
			)
			(fill no)
			(layer "F.CrtYd")
		)
		(fp_rect
			(start -0.508 0.9398)
			(end 0.508 -0.9398)
			(stroke
				(width 0)
				(type default)
			)
			(fill no)
			(layer "F.Fab")
		)
		(pad "1" smd custom
			(at 0 -0.4445 90)
			(size 0.1397 0.1397)
			(layers "F.Cu" "F.Mask" "F.Paste")
			(net "XM_ADDR_5")
			(options
				(clearance outline)
				(anchor circle)
			)
			(primitives
				(gr_poly
					(pts
						(arc
							(start -0.1778 -0.2794)
							(mid -0.249642 -0.249642)
							(end -0.2794 -0.1778)
						)
						(arc
							(start -0.2794 0.1778)
							(mid -0.249642 0.249642)
							(end -0.1778 0.2794)
						)
						(arc
							(start 0.1778 0.2794)
							(mid 0.249642 0.249642)
							(end 0.2794 0.1778)
						)
						(arc
							(start 0.2794 -0.1778)
							(mid 0.249642 -0.249642)
							(end 0.1778 -0.2794)
						)
					)
					(width 0)
					(fill yes)
				)
			)
		)
		(pad "2" smd custom
			(at 0 0.4445 90)
			(size 0.1397 0.1397)
			(layers "F.Cu" "F.Mask" "F.Paste")
			(net "GND")
			(options
				(clearance outline)
				(anchor circle)
			)
			(primitives
				(gr_poly
					(pts
						(arc
							(start -0.1778 -0.2794)
							(mid -0.249642 -0.249642)
							(end -0.2794 -0.1778)
						)
						(arc
							(start -0.2794 0.1778)
							(mid -0.249642 0.249642)
							(end -0.1778 0.2794)
						)
						(arc
							(start 0.1778 0.2794)
							(mid 0.249642 0.249642)
							(end 0.2794 0.1778)
						)
						(arc
							(start 0.2794 -0.1778)
							(mid 0.249642 -0.249642)
							(end 0.1778 -0.2794)
						)
					)
					(width 0)
					(fill yes)
				)
			)
		)
	)
	(footprint ""
		(layer "F.Cu")
		(at 109.782356 -90.518742 90)
		(property "Reference" "R580"
			(at 0 0 90)
			(layer "F.SilkS")
			(hide yes)
			(effects
				(font
					(size 1.27 1.27)
				)
			)
		)
		(property "Value" "10KR2F-2-GP"
			(at 0.064008 -3.993896 90)
			(unlocked yes)
			(layer "F.Fab")
			(hide yes)
			(effects
				(font
					(size 1.016 1.016)
					(thickness 0.1524)
				)
			)
		)
		(property "Device Type" "R402H16"
			(at 0.064008 -5.517896 90)
			(unlocked yes)
			(layer "F.Fab")
			(hide yes)
			(effects
				(font
					(size 1.016 1.016)
					(thickness 0.1524)
				)
			)
		)
		(duplicate_pad_numbers_are_jumpers no)
		(fp_line
			(start 0.508 -0.9398)
			(end -0.508 -0.9398)
			(stroke
				(width 0.1524)
				(type default)
			)
			(layer "F.SilkS")
		)
		(fp_line
			(start -0.508 -0.9398)
			(end -0.508 0.9398)
			(stroke
				(width 0.1524)
				(type default)
			)
			(layer "F.SilkS")
		)
		(fp_rect
			(start -0.508 0.9398)
			(end 0.508 -0.9398)
			(stroke
				(width 0)
				(type default)
			)
			(fill no)
			(layer "F.CrtYd")
		)
		(fp_rect
			(start -0.508 0.9398)
			(end 0.508 -0.9398)
			(stroke
				(width 0)
				(type default)
			)
			(fill no)
			(layer "F.Fab")
		)
		(pad "1" smd custom
			(at 0 -0.4445 90)
			(size 0.1397 0.1397)
			(layers "F.Cu" "F.Mask" "F.Paste")
			(net "SCC_LOC_HEARTBEAT_LS")
			(options
				(clearance outline)
				(anchor circle)
			)
			(primitives
				(gr_poly
					(pts
						(arc
							(start -0.1778 -0.2794)
							(mid -0.249642 -0.249642)
							(end -0.2794 -0.1778)
						)
						(arc
							(start -0.2794 0.1778)
							(mid -0.249642 0.249642)
							(end -0.1778 0.2794)
						)
						(arc
							(start 0.1778 0.2794)
							(mid 0.249642 0.249642)
							(end 0.2794 0.1778)
						)
						(arc
							(start 0.2794 -0.1778)
							(mid 0.249642 -0.249642)
							(end 0.1778 -0.2794)
						)
					)
					(width 0)
					(fill yes)
				)
			)
		)
		(pad "2" smd custom
			(at 0 0.4445 90)
			(size 0.1397 0.1397)
			(layers "F.Cu" "F.Mask" "F.Paste")
			(net "P1V8_E")
			(options
				(clearance outline)
				(anchor circle)
			)
			(primitives
				(gr_poly
					(pts
						(arc
							(start -0.1778 -0.2794)
							(mid -0.249642 -0.249642)
							(end -0.2794 -0.1778)
						)
						(arc
							(start -0.2794 0.1778)
							(mid -0.249642 0.249642)
							(end -0.1778 0.2794)
						)
						(arc
							(start 0.1778 0.2794)
							(mid 0.249642 0.249642)
							(end 0.2794 0.1778)
						)
						(arc
							(start 0.2794 -0.1778)
							(mid 0.249642 -0.249642)
							(end 0.1778 -0.2794)
						)
					)
					(width 0)
					(fill yes)
				)
			)
		)
	)
	(footprint ""
		(layer "F.Cu")
		(at 119.912638 -91.094052 -90)
		(property "Reference" "R44"
			(at 0 0 270)
			(layer "F.SilkS")
			(hide yes)
			(effects
				(font
					(size 1.27 1.27)
				)
			)
		)
		(property "Value" "4K7R2F-GP"
			(at 0.064008 -3.993896 270)
			(unlocked yes)
			(layer "F.Fab")
			(hide yes)
			(effects
				(font
					(size 1.016 1.016)
					(thickness 0.1524)
				)
			)
		)
		(property "Device Type" "R402H16"
			(at 0.064008 -5.517896 270)
			(unlocked yes)
			(layer "F.Fab")
			(hide yes)
			(effects
				(font
					(size 1.016 1.016)
					(thickness 0.1524)
				)
			)
		)
		(duplicate_pad_numbers_are_jumpers no)
		(fp_line
			(start -0.508 -0.9398)
			(end -0.508 0.9398)
			(stroke
				(width 0.1524)
				(type default)
			)
			(layer "F.SilkS")
		)
		(fp_line
			(start 0.508 -0.9398)
			(end -0.508 -0.9398)
			(stroke
				(width 0.1524)
				(type default)
			)
			(layer "F.SilkS")
		)
		(fp_rect
			(start -0.508 0.9398)
			(end 0.508 -0.9398)
			(stroke
				(width 0)
				(type default)
			)
			(fill no)
			(layer "F.CrtYd")
		)
		(fp_rect
			(start -0.508 0.9398)
			(end 0.508 -0.9398)
			(stroke
				(width 0)
				(type default)
			)
			(fill no)
			(layer "F.Fab")
		)
		(pad "1" smd custom
			(at 0 -0.4445 270)
			(size 0.1397 0.1397)
			(layers "F.Cu" "F.Mask" "F.Paste")
			(net "EXP_GPIO13")
			(options
				(clearance outline)
				(anchor circle)
			)
			(primitives
				(gr_poly
					(pts
						(arc
							(start -0.1778 -0.2794)
							(mid -0.249642 -0.249642)
							(end -0.2794 -0.1778)
						)
						(arc
							(start -0.2794 0.1778)
							(mid -0.249642 0.249642)
							(end -0.1778 0.2794)
						)
						(arc
							(start 0.1778 0.2794)
							(mid 0.249642 0.249642)
							(end 0.2794 0.1778)
						)
						(arc
							(start 0.2794 -0.1778)
							(mid 0.249642 -0.249642)
							(end 0.1778 -0.2794)
						)
					)
					(width 0)
					(fill yes)
				)
			)
		)
		(pad "2" smd custom
			(at 0 0.4445 270)
			(size 0.1397 0.1397)
			(layers "F.Cu" "F.Mask" "F.Paste")
			(net "GND")
			(options
				(clearance outline)
				(anchor circle)
			)
			(primitives
				(gr_poly
					(pts
						(arc
							(start -0.1778 -0.2794)
							(mid -0.249642 -0.249642)
							(end -0.2794 -0.1778)
						)
						(arc
							(start -0.2794 0.1778)
							(mid -0.249642 0.249642)
							(end -0.1778 0.2794)
						)
						(arc
							(start 0.1778 0.2794)
							(mid 0.249642 0.249642)
							(end 0.2794 0.1778)
						)
						(arc
							(start 0.2794 -0.1778)
							(mid 0.249642 -0.249642)
							(end 0.1778 -0.2794)
						)
					)
					(width 0)
					(fill yes)
				)
			)
		)
	)
	(footprint ""
		(layer "F.Cu")
		(at 64.897 -106.045 180)
		(property "Reference" "R517"
			(at 0 0 180)
			(layer "F.SilkS")
			(hide yes)
			(effects
				(font
					(size 1.27 1.27)
				)
			)
		)
		(property "Value" "0R2J-2-GP"
			(at 0.064008 -3.993896 180)
			(unlocked yes)
			(layer "F.Fab")
			(hide yes)
			(effects
				(font
					(size 1.016 1.016)
					(thickness 0.1524)
				)
			)
		)
		(property "Device Type" "R402H16"
			(at 0.064008 -5.517896 180)
			(unlocked yes)
			(layer "F.Fab")
			(hide yes)
			(effects
				(font
					(size 1.016 1.016)
					(thickness 0.1524)
				)
			)
		)
		(duplicate_pad_numbers_are_jumpers no)
		(fp_line
			(start 0.508 -0.9398)
			(end -0.508 -0.9398)
			(stroke
				(width 0.1524)
				(type default)
			)
			(layer "F.SilkS")
		)
		(fp_line
			(start -0.508 -0.9398)
			(end -0.508 0.9398)
			(stroke
				(width 0.1524)
				(type default)
			)
			(layer "F.SilkS")
		)
		(fp_rect
			(start -0.508 0.9398)
			(end 0.508 -0.9398)
			(stroke
				(width 0)
				(type default)
			)
			(fill no)
			(layer "F.CrtYd")
		)
		(fp_rect
			(start -0.508 0.9398)
			(end 0.508 -0.9398)
			(stroke
				(width 0)
				(type default)
			)
			(fill no)
			(layer "F.Fab")
		)
		(pad "1" smd custom
			(at 0 -0.4445 180)
			(size 0.1397 0.1397)
			(layers "F.Cu" "F.Mask" "F.Paste")
			(net "P3V3_ROVP")
			(options
				(clearance outline)
				(anchor circle)
			)
			(primitives
				(gr_poly
					(pts
						(arc
							(start -0.1778 -0.2794)
							(mid -0.249642 -0.249642)
							(end -0.2794 -0.1778)
						)
						(arc
							(start -0.2794 0.1778)
							(mid -0.249642 0.249642)
							(end -0.1778 0.2794)
						)
						(arc
							(start 0.1778 0.2794)
							(mid 0.249642 0.249642)
							(end 0.2794 0.1778)
						)
						(arc
							(start 0.2794 -0.1778)
							(mid 0.249642 -0.249642)
							(end 0.1778 -0.2794)
						)
					)
					(width 0)
					(fill yes)
				)
			)
		)
		(pad "2" smd custom
			(at 0 0.4445 180)
			(size 0.1397 0.1397)
			(layers "F.Cu" "F.Mask" "F.Paste")
			(net "AGND_P3V3")
			(options
				(clearance outline)
				(anchor circle)
			)
			(primitives
				(gr_poly
					(pts
						(arc
							(start -0.1778 -0.2794)
							(mid -0.249642 -0.249642)
							(end -0.2794 -0.1778)
						)
						(arc
							(start -0.2794 0.1778)
							(mid -0.249642 0.249642)
							(end -0.1778 0.2794)
						)
						(arc
							(start 0.1778 0.2794)
							(mid 0.249642 0.249642)
							(end 0.2794 0.1778)
						)
						(arc
							(start 0.2794 -0.1778)
							(mid 0.249642 -0.249642)
							(end 0.1778 -0.2794)
						)
					)
					(width 0)
					(fill yes)
				)
			)
		)
	)
	(footprint ""
		(layer "F.Cu")
		(at 105.877614 -86.889336)
		(property "Reference" "R87"
			(at 0 0 0)
			(layer "F.SilkS")
			(hide yes)
			(effects
				(font
					(size 1.27 1.27)
				)
			)
		)
		(property "Value" "4K75R2F-1-GP"
			(at 0.064008 -3.993896 0)
			(unlocked yes)
			(layer "F.Fab")
			(hide yes)
			(effects
				(font
					(size 1.016 1.016)
					(thickness 0.1524)
				)
			)
		)
		(property "Device Type" "R402H16"
			(at 0.064008 -5.517896 0)
			(unlocked yes)
			(layer "F.Fab")
			(hide yes)
			(effects
				(font
					(size 1.016 1.016)
					(thickness 0.1524)
				)
			)
		)
		(duplicate_pad_numbers_are_jumpers no)
		(fp_line
			(start -0.508 -0.9398)
			(end -0.508 0.9398)
			(stroke
				(width 0.1524)
				(type default)
			)
			(layer "F.SilkS")
		)
		(fp_line
			(start 0.508 -0.9398)
			(end -0.508 -0.9398)
			(stroke
				(width 0.1524)
				(type default)
			)
			(layer "F.SilkS")
		)
		(fp_rect
			(start -0.508 0.9398)
			(end 0.508 -0.9398)
			(stroke
				(width 0)
				(type default)
			)
			(fill no)
			(layer "F.CrtYd")
		)
		(fp_rect
			(start -0.508 0.9398)
			(end 0.508 -0.9398)
			(stroke
				(width 0)
				(type default)
			)
			(fill no)
			(layer "F.Fab")
		)
		(pad "1" smd custom
			(at 0 -0.4445)
			(size 0.1397 0.1397)
			(layers "F.Cu" "F.Mask" "F.Paste")
			(net "P1V8_E")
			(options
				(clearance outline)
				(anchor circle)
			)
			(primitives
				(gr_poly
					(pts
						(arc
							(start -0.1778 -0.2794)
							(mid -0.249642 -0.249642)
							(end -0.2794 -0.1778)
						)
						(arc
							(start -0.2794 0.1778)
							(mid -0.249642 0.249642)
							(end -0.1778 0.2794)
						)
						(arc
							(start 0.1778 0.2794)
							(mid 0.249642 0.249642)
							(end 0.2794 0.1778)
						)
						(arc
							(start 0.2794 -0.1778)
							(mid 0.249642 -0.249642)
							(end 0.1778 -0.2794)
						)
					)
					(width 0)
					(fill yes)
				)
			)
		)
		(pad "2" smd custom
			(at 0 0.4445)
			(size 0.1397 0.1397)
			(layers "F.Cu" "F.Mask" "F.Paste")
			(net "SXP_ACTIVE_2")
			(options
				(clearance outline)
				(anchor circle)
			)
			(primitives
				(gr_poly
					(pts
						(arc
							(start -0.1778 -0.2794)
							(mid -0.249642 -0.249642)
							(end -0.2794 -0.1778)
						)
						(arc
							(start -0.2794 0.1778)
							(mid -0.249642 0.249642)
							(end -0.1778 0.2794)
						)
						(arc
							(start 0.1778 0.2794)
							(mid 0.249642 0.249642)
							(end 0.2794 0.1778)
						)
						(arc
							(start 0.2794 -0.1778)
							(mid 0.249642 -0.249642)
							(end 0.1778 -0.2794)
						)
					)
					(width 0)
					(fill yes)
				)
			)
		)
	)
	(footprint ""
		(layer "F.Cu")
		(at 117.939058 -86.995254 180)
		(property "Reference" "R142"
			(at 0 0 180)
			(layer "F.SilkS")
			(hide yes)
			(effects
				(font
					(size 1.27 1.27)
				)
			)
		)
		(property "Value" "4K7R2F-GP"
			(at 0.064008 -3.993896 180)
			(unlocked yes)
			(layer "F.Fab")
			(hide yes)
			(effects
				(font
					(size 1.016 1.016)
					(thickness 0.1524)
				)
			)
		)
		(property "Device Type" "R402H16"
			(at 0.064008 -5.517896 180)
			(unlocked yes)
			(layer "F.Fab")
			(hide yes)
			(effects
				(font
					(size 1.016 1.016)
					(thickness 0.1524)
				)
			)
		)
		(duplicate_pad_numbers_are_jumpers no)
		(fp_line
			(start 0.508 -0.9398)
			(end -0.508 -0.9398)
			(stroke
				(width 0.1524)
				(type default)
			)
			(layer "F.SilkS")
		)
		(fp_line
			(start -0.508 -0.9398)
			(end -0.508 0.9398)
			(stroke
				(width 0.1524)
				(type default)
			)
			(layer "F.SilkS")
		)
		(fp_rect
			(start -0.508 0.9398)
			(end 0.508 -0.9398)
			(stroke
				(width 0)
				(type default)
			)
			(fill no)
			(layer "F.CrtYd")
		)
		(fp_rect
			(start -0.508 0.9398)
			(end 0.508 -0.9398)
			(stroke
				(width 0)
				(type default)
			)
			(fill no)
			(layer "F.Fab")
		)
		(pad "1" smd custom
			(at 0 -0.4445 180)
			(size 0.1397 0.1397)
			(layers "F.Cu" "F.Mask" "F.Paste")
			(net "EXP_XM_ADDR_16")
			(options
				(clearance outline)
				(anchor circle)
			)
			(primitives
				(gr_poly
					(pts
						(arc
							(start -0.1778 -0.2794)
							(mid -0.249642 -0.249642)
							(end -0.2794 -0.1778)
						)
						(arc
							(start -0.2794 0.1778)
							(mid -0.249642 0.249642)
							(end -0.1778 0.2794)
						)
						(arc
							(start 0.1778 0.2794)
							(mid 0.249642 0.249642)
							(end 0.2794 0.1778)
						)
						(arc
							(start 0.2794 -0.1778)
							(mid 0.249642 -0.249642)
							(end 0.1778 -0.2794)
						)
					)
					(width 0)
					(fill yes)
				)
			)
		)
		(pad "2" smd custom
			(at 0 0.4445 180)
			(size 0.1397 0.1397)
			(layers "F.Cu" "F.Mask" "F.Paste")
			(net "GND")
			(options
				(clearance outline)
				(anchor circle)
			)
			(primitives
				(gr_poly
					(pts
						(arc
							(start -0.1778 -0.2794)
							(mid -0.249642 -0.249642)
							(end -0.2794 -0.1778)
						)
						(arc
							(start -0.2794 0.1778)
							(mid -0.249642 0.249642)
							(end -0.1778 0.2794)
						)
						(arc
							(start 0.1778 0.2794)
							(mid 0.249642 0.249642)
							(end 0.2794 0.1778)
						)
						(arc
							(start 0.2794 -0.1778)
							(mid 0.249642 -0.249642)
							(end 0.1778 -0.2794)
						)
					)
					(width 0)
					(fill yes)
				)
			)
		)
	)
	(footprint ""
		(layer "F.Cu")
		(at 10.922 -94.801182 180)
		(property "Reference" "R426"
			(at 0 0 180)
			(layer "F.SilkS")
			(hide yes)
			(effects
				(font
					(size 1.27 1.27)
				)
			)
		)
		(property "Value" "200KR2F-L-GP"
			(at 0.064008 -3.993896 180)
			(unlocked yes)
			(layer "F.Fab")
			(hide yes)
			(effects
				(font
					(size 1.016 1.016)
					(thickness 0.1524)
				)
			)
		)
		(property "Device Type" "R402H16"
			(at 0.064008 -5.517896 180)
			(unlocked yes)
			(layer "F.Fab")
			(hide yes)
			(effects
				(font
					(size 1.016 1.016)
					(thickness 0.1524)
				)
			)
		)
		(duplicate_pad_numbers_are_jumpers no)
		(fp_line
			(start 0.508 -0.9398)
			(end -0.508 -0.9398)
			(stroke
				(width 0.1524)
				(type default)
			)
			(layer "F.SilkS")
		)
		(fp_line
			(start -0.508 -0.9398)
			(end -0.508 0.9398)
			(stroke
				(width 0.1524)
				(type default)
			)
			(layer "F.SilkS")
		)
		(fp_rect
			(start -0.508 0.9398)
			(end 0.508 -0.9398)
			(stroke
				(width 0)
				(type default)
			)
			(fill no)
			(layer "F.CrtYd")
		)
		(fp_rect
			(start -0.508 0.9398)
			(end 0.508 -0.9398)
			(stroke
				(width 0)
				(type default)
			)
			(fill no)
			(layer "F.Fab")
		)
		(pad "1" smd custom
			(at 0 -0.4445 180)
			(size 0.1397 0.1397)
			(layers "F.Cu" "F.Mask" "F.Paste")
			(net "LS_EN_U40")
			(options
				(clearance outline)
				(anchor circle)
			)
			(primitives
				(gr_poly
					(pts
						(arc
							(start -0.1778 -0.2794)
							(mid -0.249642 -0.249642)
							(end -0.2794 -0.1778)
						)
						(arc
							(start -0.2794 0.1778)
							(mid -0.249642 0.249642)
							(end -0.1778 0.2794)
						)
						(arc
							(start 0.1778 0.2794)
							(mid 0.249642 0.249642)
							(end 0.2794 0.1778)
						)
						(arc
							(start 0.2794 -0.1778)
							(mid 0.249642 -0.249642)
							(end 0.1778 -0.2794)
						)
					)
					(width 0)
					(fill yes)
				)
			)
		)
		(pad "2" smd custom
			(at 0 0.4445 180)
			(size 0.1397 0.1397)
			(layers "F.Cu" "F.Mask" "F.Paste")
			(net "P0V9_PG")
			(options
				(clearance outline)
				(anchor circle)
			)
			(primitives
				(gr_poly
					(pts
						(arc
							(start -0.1778 -0.2794)
							(mid -0.249642 -0.249642)
							(end -0.2794 -0.1778)
						)
						(arc
							(start -0.2794 0.1778)
							(mid -0.249642 0.249642)
							(end -0.1778 0.2794)
						)
						(arc
							(start 0.1778 0.2794)
							(mid 0.249642 0.249642)
							(end 0.2794 0.1778)
						)
						(arc
							(start 0.2794 -0.1778)
							(mid 0.249642 -0.249642)
							(end 0.1778 -0.2794)
						)
					)
					(width 0)
					(fill yes)
				)
			)
		)
	)
	(footprint ""
		(layer "F.Cu")
		(at 168.008808 -55.179214)
		(property "Reference" "TP123"
			(at 0 0 0)
			(layer "F.SilkS")
			(hide yes)
			(effects
				(font
					(size 1.27 1.27)
				)
			)
		)
		(property "Value" "TPAD28-2-GP"
			(at -0.0127 -1.6637 0)
			(unlocked yes)
			(layer "F.Fab")
			(hide yes)
			(effects
				(font
					(size 1.016 1.016)
					(thickness 0.1524)
				)
			)
		)
		(property "Device Type" "TPAD28"
			(at -0.0127 -3.1877 0)
			(unlocked yes)
			(layer "F.Fab")
			(hide yes)
			(effects
				(font
					(size 1.016 1.016)
					(thickness 0.1524)
				)
			)
		)
		(duplicate_pad_numbers_are_jumpers no)
		(fp_poly
			(pts
				(arc
					(start 0.3556 0)
					(mid -0.3556 0)
					(end 0.3556 0)
				)
			)
			(stroke
				(width 0)
				(type default)
			)
			(fill no)
			(layer "F.CrtYd")
		)
		(fp_poly
			(pts
				(arc
					(start 0.6096 0)
					(mid -0.6096 0)
					(end 0.6096 0)
				)
			)
			(stroke
				(width 0)
				(type default)
			)
			(fill no)
			(layer "F.Fab")
		)
		(pad "1" smd circle
			(at 0 0)
			(size 0.7112 0.7112)
			(layers "F.Cu" "F.Mask" "F.Paste")
			(net "ICE0_TRST#")
		)
	)
	(footprint ""
		(layer "F.Cu")
		(at 60.15228 -108.797852 180)
		(property "Reference" "L34"
			(at 0 0 180)
			(layer "F.SilkS")
			(hide yes)
			(effects
				(font
					(size 1.27 1.27)
				)
			)
		)
		(property "Value" "COIL-3D3UH-26-GP"
			(at -4.699 -4.0132 180)
			(unlocked yes)
			(layer "F.Fab")
			(hide yes)
			(effects
				(font
					(size 1.016 1.016)
					(thickness 0.1524)
				)
			)
		)
		(property "Device Type" "L7066-1830-UH119"
			(at -4.699 -5.5372 180)
			(unlocked yes)
			(layer "F.Fab")
			(hide yes)
			(effects
				(font
					(size 1.016 1.016)
					(thickness 0.1524)
				)
			)
		)
		(duplicate_pad_numbers_are_jumpers no)
		(fp_line
			(start 3.556 4.4958)
			(end -3.556 4.4958)
			(stroke
				(width 0.1524)
				(type default)
			)
			(layer "F.SilkS")
		)
		(fp_line
			(start 3.556 -4.4958)
			(end 3.556 4.4958)
			(stroke
				(width 0.1524)
				(type default)
			)
			(layer "F.SilkS")
		)
		(fp_line
			(start -3.556 4.4958)
			(end -3.556 -4.4958)
			(stroke
				(width 0.1524)
				(type default)
			)
			(layer "F.SilkS")
		)
		(fp_line
			(start -3.556 -4.4958)
			(end 3.556 -4.4958)
			(stroke
				(width 0.1524)
				(type default)
			)
			(layer "F.SilkS")
		)
		(fp_rect
			(start -3.302 3.4798)
			(end 3.302 -3.4798)
			(stroke
				(width 0)
				(type default)
			)
			(fill no)
			(layer "F.CrtYd")
		)
		(fp_poly
			(pts
				(xy -3.81 4.572) (xy -3.81 -4.572) (xy 3.81 -4.572) (xy 3.81 -0.5588) (xy 3.302 -0.5588) (xy 3.302 -3.4798)
				(xy -3.302 -3.4798) (xy -3.302 3.4798) (xy 3.302 3.4798) (xy 3.302 -0.5461) (xy 3.81 -0.5461) (xy 3.81 4.572)
			)
			(stroke
				(width 0)
				(type default)
			)
			(fill no)
			(layer "F.CrtYd")
		)
		(fp_rect
			(start -3.81 4.572)
			(end 3.81 -4.572)
			(stroke
				(width 0)
				(type default)
			)
			(fill no)
			(layer "F.Fab")
		)
		(pad "1" smd rect
			(at 0 -2.779522 180)
			(size 3.5052 2.921)
			(layers "F.Cu" "F.Mask" "F.Paste")
			(net "P3V3_LL")
		)
		(pad "2" smd rect
			(at 0 2.779522 180)
			(size 3.5052 2.921)
			(layers "F.Cu" "F.Mask" "F.Paste")
			(net "P3V3_OUT")
		)
	)
	(footprint ""
		(layer "F.Cu")
		(at 62.4332 -72.7202 180)
		(property "Reference" "R419"
			(at 0 0 180)
			(layer "F.SilkS")
			(hide yes)
			(effects
				(font
					(size 1.27 1.27)
				)
			)
		)
		(property "Value" "1KR2F-3-GP"
			(at 0.064008 -3.993896 180)
			(unlocked yes)
			(layer "F.Fab")
			(hide yes)
			(effects
				(font
					(size 1.016 1.016)
					(thickness 0.1524)
				)
			)
		)
		(property "Device Type" "R402H16"
			(at 0.064008 -5.517896 180)
			(unlocked yes)
			(layer "F.Fab")
			(hide yes)
			(effects
				(font
					(size 1.016 1.016)
					(thickness 0.1524)
				)
			)
		)
		(duplicate_pad_numbers_are_jumpers no)
		(fp_line
			(start 0.508 -0.9398)
			(end -0.508 -0.9398)
			(stroke
				(width 0.1524)
				(type default)
			)
			(layer "F.SilkS")
		)
		(fp_line
			(start -0.508 -0.9398)
			(end -0.508 0.9398)
			(stroke
				(width 0.1524)
				(type default)
			)
			(layer "F.SilkS")
		)
		(fp_rect
			(start -0.508 0.9398)
			(end 0.508 -0.9398)
			(stroke
				(width 0)
				(type default)
			)
			(fill no)
			(layer "F.CrtYd")
		)
		(fp_rect
			(start -0.508 0.9398)
			(end 0.508 -0.9398)
			(stroke
				(width 0)
				(type default)
			)
			(fill no)
			(layer "F.Fab")
		)
		(pad "1" smd custom
			(at 0 -0.4445 180)
			(size 0.1397 0.1397)
			(layers "F.Cu" "F.Mask" "F.Paste")
			(net "P3V3")
			(options
				(clearance outline)
				(anchor circle)
			)
			(primitives
				(gr_poly
					(pts
						(arc
							(start -0.1778 -0.2794)
							(mid -0.249642 -0.249642)
							(end -0.2794 -0.1778)
						)
						(arc
							(start -0.2794 0.1778)
							(mid -0.249642 0.249642)
							(end -0.1778 0.2794)
						)
						(arc
							(start 0.1778 0.2794)
							(mid 0.249642 0.249642)
							(end 0.2794 0.1778)
						)
						(arc
							(start 0.2794 -0.1778)
							(mid 0.249642 -0.249642)
							(end 0.1778 -0.2794)
						)
					)
					(width 0)
					(fill yes)
				)
			)
		)
		(pad "2" smd custom
			(at 0 0.4445 180)
			(size 0.1397 0.1397)
			(layers "F.Cu" "F.Mask" "F.Paste")
			(net "I2C_DRIVE_INS_SCL5")
			(options
				(clearance outline)
				(anchor circle)
			)
			(primitives
				(gr_poly
					(pts
						(arc
							(start -0.1778 -0.2794)
							(mid -0.249642 -0.249642)
							(end -0.2794 -0.1778)
						)
						(arc
							(start -0.2794 0.1778)
							(mid -0.249642 0.249642)
							(end -0.1778 0.2794)
						)
						(arc
							(start 0.1778 0.2794)
							(mid 0.249642 0.249642)
							(end 0.2794 0.1778)
						)
						(arc
							(start 0.2794 -0.1778)
							(mid 0.249642 -0.249642)
							(end 0.1778 -0.2794)
						)
					)
					(width 0)
					(fill yes)
				)
			)
		)
	)
	(footprint ""
		(layer "F.Cu")
		(at 172.339 -59.817)
		(property "Reference" "R252"
			(at 0 0 0)
			(layer "F.SilkS")
			(hide yes)
			(effects
				(font
					(size 1.27 1.27)
				)
			)
		)
		(property "Value" "10KR2F-2-GP"
			(at 0.064008 -3.993896 0)
			(unlocked yes)
			(layer "F.Fab")
			(hide yes)
			(effects
				(font
					(size 1.016 1.016)
					(thickness 0.1524)
				)
			)
		)
		(property "Device Type" "R402H16"
			(at 0.064008 -5.517896 0)
			(unlocked yes)
			(layer "F.Fab")
			(hide yes)
			(effects
				(font
					(size 1.016 1.016)
					(thickness 0.1524)
				)
			)
		)
		(duplicate_pad_numbers_are_jumpers no)
		(fp_line
			(start -0.508 -0.9398)
			(end -0.508 0.9398)
			(stroke
				(width 0.1524)
				(type default)
			)
			(layer "F.SilkS")
		)
		(fp_line
			(start 0.508 -0.9398)
			(end -0.508 -0.9398)
			(stroke
				(width 0.1524)
				(type default)
			)
			(layer "F.SilkS")
		)
		(fp_rect
			(start -0.508 0.9398)
			(end 0.508 -0.9398)
			(stroke
				(width 0)
				(type default)
			)
			(fill no)
			(layer "F.CrtYd")
		)
		(fp_rect
			(start -0.508 0.9398)
			(end 0.508 -0.9398)
			(stroke
				(width 0)
				(type default)
			)
			(fill no)
			(layer "F.Fab")
		)
		(pad "1" smd custom
			(at 0 -0.4445)
			(size 0.1397 0.1397)
			(layers "F.Cu" "F.Mask" "F.Paste")
			(net "P1V8_C")
			(options
				(clearance outline)
				(anchor circle)
			)
			(primitives
				(gr_poly
					(pts
						(arc
							(start -0.1778 -0.2794)
							(mid -0.249642 -0.249642)
							(end -0.2794 -0.1778)
						)
						(arc
							(start -0.2794 0.1778)
							(mid -0.249642 0.249642)
							(end -0.1778 0.2794)
						)
						(arc
							(start 0.1778 0.2794)
							(mid 0.249642 0.249642)
							(end 0.2794 0.1778)
						)
						(arc
							(start 0.2794 -0.1778)
							(mid 0.249642 -0.249642)
							(end 0.1778 -0.2794)
						)
					)
					(width 0)
					(fill yes)
				)
			)
		)
		(pad "2" smd custom
			(at 0 0.4445)
			(size 0.1397 0.1397)
			(layers "F.Cu" "F.Mask" "F.Paste")
			(net "LSI_TN")
			(options
				(clearance outline)
				(anchor circle)
			)
			(primitives
				(gr_poly
					(pts
						(arc
							(start -0.1778 -0.2794)
							(mid -0.249642 -0.249642)
							(end -0.2794 -0.1778)
						)
						(arc
							(start -0.2794 0.1778)
							(mid -0.249642 0.249642)
							(end -0.1778 0.2794)
						)
						(arc
							(start 0.1778 0.2794)
							(mid 0.249642 0.249642)
							(end 0.2794 0.1778)
						)
						(arc
							(start 0.2794 -0.1778)
							(mid 0.249642 -0.249642)
							(end 0.1778 -0.2794)
						)
					)
					(width 0)
					(fill yes)
				)
			)
		)
	)
	(footprint ""
		(layer "F.Cu")
		(at 148.631148 -44.257214 102)
		(property "Reference" "C338"
			(at 0 0 102)
			(layer "F.SilkS")
			(hide yes)
			(effects
				(font
					(size 1.27 1.27)
				)
			)
		)
		(property "Value" "SCD01U16V1KX-GP"
			(at -2.832048 -1.739777 102)
			(unlocked yes)
			(layer "F.Fab")
			(hide yes)
			(effects
				(font
					(size 1.016 1.016)
					(thickness 0.1524)
				)
			)
		)
		(property "Device Type" "C0201H13"
			(at -2.832174 -3.263834 102)
			(unlocked yes)
			(layer "F.Fab")
			(hide yes)
			(effects
				(font
					(size 1.016 1.016)
					(thickness 0.1524)
				)
			)
		)
		(duplicate_pad_numbers_are_jumpers no)
		(fp_poly
			(pts
				(xy -0.279454 -0.647706) (xy 0.279346 -0.647706) (xy 0.279346 0.647694) (xy -0.279454 0.647694)
			)
			(stroke
				(width 0)
				(type default)
			)
			(fill no)
			(layer "F.CrtYd")
		)
		(fp_poly
			(pts
				(xy -0.279454 -0.647706) (xy 0.279346 -0.647706) (xy 0.279346 0.647694) (xy -0.279454 0.647694)
			)
			(stroke
				(width 0)
				(type default)
			)
			(fill no)
			(layer "F.Fab")
		)
		(pad "1" smd custom
			(at -0.000001 -0.2794 102)
			(size 0.0762 0.0762)
			(layers "F.Cu" "F.Mask" "F.Paste")
			(net "PHY_SCC_TO_IOC_44_DN")
			(options
				(clearance outline)
				(anchor circle)
			)
			(primitives
				(gr_poly
					(pts
						(arc
							(start 0.1524 -0.127)
							(mid 0.137521 -0.162921)
							(end 0.1016 -0.1778)
						)
						(arc
							(start -0.1016 -0.1778)
							(mid -0.137521 -0.162921)
							(end -0.1524 -0.127)
						)
						(arc
							(start -0.1524 0.127)
							(mid -0.137521 0.162921)
							(end -0.1016 0.1778)
						)
						(arc
							(start 0.1016 0.1778)
							(mid 0.137521 0.162921)
							(end 0.1524 0.127)
						)
					)
					(width 0)
					(fill yes)
				)
			)
		)
		(pad "2" smd custom
			(at 0.000001 0.2794 102)
			(size 0.0762 0.0762)
			(layers "F.Cu" "F.Mask" "F.Paste")
			(net "PHY_SCC_TO_IOC_C_44_DN")
			(options
				(clearance outline)
				(anchor circle)
			)
			(primitives
				(gr_poly
					(pts
						(arc
							(start 0.1524 -0.127)
							(mid 0.137521 -0.162921)
							(end 0.1016 -0.1778)
						)
						(arc
							(start -0.1016 -0.1778)
							(mid -0.137521 -0.162921)
							(end -0.1524 -0.127)
						)
						(arc
							(start -0.1524 0.127)
							(mid -0.137521 0.162921)
							(end -0.1016 0.1778)
						)
						(arc
							(start 0.1016 0.1778)
							(mid 0.137521 0.162921)
							(end 0.1524 0.127)
						)
					)
					(width 0)
					(fill yes)
				)
			)
		)
	)
	(footprint ""
		(layer "F.Cu")
		(at 123.317 -112.62868)
		(property "Reference" "TP22"
			(at 0 0 0)
			(layer "F.SilkS")
			(hide yes)
			(effects
				(font
					(size 1.27 1.27)
				)
			)
		)
		(property "Value" "TPAD28-2-GP"
			(at -0.0127 -1.6637 0)
			(unlocked yes)
			(layer "F.Fab")
			(hide yes)
			(effects
				(font
					(size 1.016 1.016)
					(thickness 0.1524)
				)
			)
		)
		(property "Device Type" "TPAD28"
			(at -0.0127 -3.1877 0)
			(unlocked yes)
			(layer "F.Fab")
			(hide yes)
			(effects
				(font
					(size 1.016 1.016)
					(thickness 0.1524)
				)
			)
		)
		(duplicate_pad_numbers_are_jumpers no)
		(fp_poly
			(pts
				(arc
					(start 0.3556 0)
					(mid -0.3556 0)
					(end 0.3556 0)
				)
			)
			(stroke
				(width 0)
				(type default)
			)
			(fill no)
			(layer "F.CrtYd")
		)
		(fp_poly
			(pts
				(arc
					(start 0.6096 0)
					(mid -0.6096 0)
					(end 0.6096 0)
				)
			)
			(stroke
				(width 0)
				(type default)
			)
			(fill no)
			(layer "F.Fab")
		)
		(pad "1" smd circle
			(at 0 0)
			(size 0.7112 0.7112)
			(layers "F.Cu" "F.Mask" "F.Paste")
			(net "INT_A2_CONN1")
		)
	)
	(footprint ""
		(layer "F.Cu")
		(at 37.8206 -49.7332 180)
		(property "Reference" "C564"
			(at 0 0 180)
			(layer "F.SilkS")
			(hide yes)
			(effects
				(font
					(size 1.27 1.27)
				)
			)
		)
		(property "Value" "SC10U16V5KX-7-GP-U"
			(at -0.0762 -6.1214 180)
			(unlocked yes)
			(layer "F.Fab")
			(hide yes)
			(effects
				(font
					(size 1.016 1.016)
					(thickness 0.1524)
				)
			)
		)
		(property "Device Type" "C805H58"
			(at -0.0762 -8.1534 180)
			(unlocked yes)
			(layer "F.Fab")
			(hide yes)
			(effects
				(font
					(size 1.016 1.016)
					(thickness 0.1524)
				)
			)
		)
		(duplicate_pad_numbers_are_jumpers no)
		(fp_line
			(start 0.635 0)
			(end -0.635 0)
			(stroke
				(width 0.508)
				(type default)
			)
			(layer "F.SilkS")
		)
		(fp_rect
			(start -0.9652 1.778)
			(end 0.9652 -1.778)
			(stroke
				(width 0)
				(type default)
			)
			(fill no)
			(layer "F.CrtYd")
		)
		(fp_poly
			(pts
				(xy -0.9652 -1.778) (xy 0.9652 -1.778) (xy 0.9652 1.778) (xy -0.9652 1.778)
			)
			(stroke
				(width 0)
				(type default)
			)
			(fill no)
			(layer "F.Fab")
		)
		(pad "1" smd rect
			(at 0 -0.9652 180)
			(size 1.397 1.143)
			(layers "F.Cu" "F.Mask" "F.Paste")
			(net "P12V_STBY_VIN_Q7")
		)
		(pad "2" smd rect
			(at 0 0.9652 180)
			(size 1.397 1.143)
			(layers "F.Cu" "F.Mask" "F.Paste")
			(net "GND")
		)
	)
	(footprint ""
		(layer "F.Cu")
		(at 151.765 -110.363 90)
		(property "Reference" "C710"
			(at 0 0 90)
			(layer "F.SilkS")
			(hide yes)
			(effects
				(font
					(size 1.27 1.27)
				)
			)
		)
		(property "Value" "SC2200P50V2KX-2GP"
			(at 1.1811 -2.7051 90)
			(unlocked yes)
			(layer "F.Fab")
			(hide yes)
			(effects
				(font
					(size 1.016 1.016)
					(thickness 0.1524)
				)
			)
		)
		(property "Device Type" "C402H22"
			(at 1.1811 -4.2291 90)
			(unlocked yes)
			(layer "F.Fab")
			(hide yes)
			(effects
				(font
					(size 1.016 1.016)
					(thickness 0.1524)
				)
			)
		)
		(duplicate_pad_numbers_are_jumpers no)
		(fp_rect
			(start -0.4318 0.9525)
			(end 0.4318 -0.9525)
			(stroke
				(width 0)
				(type default)
			)
			(fill no)
			(layer "F.CrtYd")
		)
		(fp_rect
			(start -0.4318 0.9525)
			(end 0.4318 -0.9525)
			(stroke
				(width 0)
				(type default)
			)
			(fill no)
			(layer "F.Fab")
		)
		(pad "1" smd custom
			(at 0 -0.4445 90)
			(size 0.1524 0.1524)
			(layers "F.Cu" "F.Mask" "F.Paste")
			(net "P1V5_E_LL")
			(options
				(clearance outline)
				(anchor circle)
			)
			(primitives
				(gr_poly
					(pts
						(arc
							(start 0.3048 -0.2032)
							(mid 0.275042 -0.275042)
							(end 0.2032 -0.3048)
						)
						(arc
							(start -0.2032 -0.3048)
							(mid -0.275042 -0.275042)
							(end -0.3048 -0.2032)
						)
						(arc
							(start -0.3048 0.2032)
							(mid -0.275042 0.275042)
							(end -0.2032 0.3048)
						)
						(arc
							(start 0.2032 0.3048)
							(mid 0.275042 0.275042)
							(end 0.3048 0.2032)
						)
					)
					(width 0)
					(fill yes)
				)
			)
		)
		(pad "2" smd custom
			(at 0 0.4445 90)
			(size 0.1524 0.1524)
			(layers "F.Cu" "F.Mask" "F.Paste")
			(net "P1V5_E_SNB")
			(options
				(clearance outline)
				(anchor circle)
			)
			(primitives
				(gr_poly
					(pts
						(arc
							(start 0.3048 -0.2032)
							(mid 0.275042 -0.275042)
							(end 0.2032 -0.3048)
						)
						(arc
							(start -0.2032 -0.3048)
							(mid -0.275042 -0.275042)
							(end -0.3048 -0.2032)
						)
						(arc
							(start -0.3048 0.2032)
							(mid -0.275042 0.275042)
							(end -0.2032 0.3048)
						)
						(arc
							(start 0.2032 0.3048)
							(mid 0.275042 0.275042)
							(end 0.3048 0.2032)
						)
					)
					(width 0)
					(fill yes)
				)
			)
		)
	)
	(footprint ""
		(layer "F.Cu")
		(at 44.831 -43.8404 180)
		(property "Reference" "R481"
			(at 0 0 180)
			(layer "F.SilkS")
			(hide yes)
			(effects
				(font
					(size 1.27 1.27)
				)
			)
		)
		(property "Value" "0R3J-0-U-GP"
			(at -0.0254 -2.5146 180)
			(unlocked yes)
			(layer "F.Fab")
			(hide yes)
			(effects
				(font
					(size 1.016 1.016)
					(thickness 0.1524)
				)
			)
		)
		(property "Device Type" "R603H22"
			(at -0.0254 -4.0386 180)
			(unlocked yes)
			(layer "F.Fab")
			(hide yes)
			(effects
				(font
					(size 1.016 1.016)
					(thickness 0.1524)
				)
			)
		)
		(duplicate_pad_numbers_are_jumpers no)
		(fp_line
			(start 0.2032 0)
			(end 0.4826 0)
			(stroke
				(width 0.2032)
				(type default)
			)
			(layer "F.SilkS")
		)
		(fp_line
			(start -0.4826 0)
			(end -0.2032 0)
			(stroke
				(width 0.2032)
				(type default)
			)
			(layer "F.SilkS")
		)
		(fp_rect
			(start -0.5842 1.3335)
			(end 0.5842 -1.3335)
			(stroke
				(width 0)
				(type default)
			)
			(fill no)
			(layer "F.CrtYd")
		)
		(fp_rect
			(start -0.5842 1.3335)
			(end 0.5842 -1.3335)
			(stroke
				(width 0)
				(type default)
			)
			(fill no)
			(layer "F.Fab")
		)
		(pad "1" smd custom
			(at 0 -0.762 180)
			(size 0.2159 0.2159)
			(layers "F.Cu" "F.Mask" "F.Paste")
			(net "P0V9_DH")
			(options
				(clearance outline)
				(anchor circle)
			)
			(primitives
				(gr_poly
					(pts
						(arc
							(start -0.3302 -0.4318)
							(mid -0.402042 -0.402042)
							(end -0.4318 -0.3302)
						)
						(arc
							(start -0.4318 0.3302)
							(mid -0.402042 0.402042)
							(end -0.3302 0.4318)
						)
						(arc
							(start 0.3302 0.4318)
							(mid 0.402042 0.402042)
							(end 0.4318 0.3302)
						)
						(arc
							(start 0.4318 -0.3302)
							(mid 0.402042 -0.402042)
							(end 0.3302 -0.4318)
						)
					)
					(width 0)
					(fill yes)
				)
			)
		)
		(pad "2" smd custom
			(at 0 0.762 180)
			(size 0.2159 0.2159)
			(layers "F.Cu" "F.Mask" "F.Paste")
			(net "P0V9_TG")
			(options
				(clearance outline)
				(anchor circle)
			)
			(primitives
				(gr_poly
					(pts
						(arc
							(start -0.3302 -0.4318)
							(mid -0.402042 -0.402042)
							(end -0.4318 -0.3302)
						)
						(arc
							(start -0.4318 0.3302)
							(mid -0.402042 0.402042)
							(end -0.3302 0.4318)
						)
						(arc
							(start 0.3302 0.4318)
							(mid 0.402042 0.402042)
							(end 0.4318 0.3302)
						)
						(arc
							(start 0.4318 -0.3302)
							(mid 0.402042 -0.402042)
							(end 0.3302 -0.4318)
						)
					)
					(width 0)
					(fill yes)
				)
			)
		)
	)
	(footprint ""
		(layer "F.Cu")
		(at 186.508644 -56.571642 180)
		(property "Reference" "R223"
			(at 0 0 180)
			(layer "F.SilkS")
			(hide yes)
			(effects
				(font
					(size 1.27 1.27)
				)
			)
		)
		(property "Value" "10KR2F-2-GP"
			(at 0.064008 -3.993896 180)
			(unlocked yes)
			(layer "F.Fab")
			(hide yes)
			(effects
				(font
					(size 1.016 1.016)
					(thickness 0.1524)
				)
			)
		)
		(property "Device Type" "R402H16"
			(at 0.064008 -5.517896 180)
			(unlocked yes)
			(layer "F.Fab")
			(hide yes)
			(effects
				(font
					(size 1.016 1.016)
					(thickness 0.1524)
				)
			)
		)
		(duplicate_pad_numbers_are_jumpers no)
		(fp_line
			(start 0.508 -0.9398)
			(end -0.508 -0.9398)
			(stroke
				(width 0.1524)
				(type default)
			)
			(layer "F.SilkS")
		)
		(fp_line
			(start -0.508 -0.9398)
			(end -0.508 0.9398)
			(stroke
				(width 0.1524)
				(type default)
			)
			(layer "F.SilkS")
		)
		(fp_rect
			(start -0.508 0.9398)
			(end 0.508 -0.9398)
			(stroke
				(width 0)
				(type default)
			)
			(fill no)
			(layer "F.CrtYd")
		)
		(fp_rect
			(start -0.508 0.9398)
			(end 0.508 -0.9398)
			(stroke
				(width 0)
				(type default)
			)
			(fill no)
			(layer "F.Fab")
		)
		(pad "1" smd custom
			(at 0 -0.4445 180)
			(size 0.1397 0.1397)
			(layers "F.Cu" "F.Mask" "F.Paste")
			(net "XM_ADDR_2")
			(options
				(clearance outline)
				(anchor circle)
			)
			(primitives
				(gr_poly
					(pts
						(arc
							(start -0.1778 -0.2794)
							(mid -0.249642 -0.249642)
							(end -0.2794 -0.1778)
						)
						(arc
							(start -0.2794 0.1778)
							(mid -0.249642 0.249642)
							(end -0.1778 0.2794)
						)
						(arc
							(start 0.1778 0.2794)
							(mid 0.249642 0.249642)
							(end 0.2794 0.1778)
						)
						(arc
							(start 0.2794 -0.1778)
							(mid 0.249642 -0.249642)
							(end 0.1778 -0.2794)
						)
					)
					(width 0)
					(fill yes)
				)
			)
		)
		(pad "2" smd custom
			(at 0 0.4445 180)
			(size 0.1397 0.1397)
			(layers "F.Cu" "F.Mask" "F.Paste")
			(net "GND")
			(options
				(clearance outline)
				(anchor circle)
			)
			(primitives
				(gr_poly
					(pts
						(arc
							(start -0.1778 -0.2794)
							(mid -0.249642 -0.249642)
							(end -0.2794 -0.1778)
						)
						(arc
							(start -0.2794 0.1778)
							(mid -0.249642 0.249642)
							(end -0.1778 0.2794)
						)
						(arc
							(start 0.1778 0.2794)
							(mid 0.249642 0.249642)
							(end 0.2794 0.1778)
						)
						(arc
							(start 0.2794 -0.1778)
							(mid 0.249642 -0.249642)
							(end 0.1778 -0.2794)
						)
					)
					(width 0)
					(fill yes)
				)
			)
		)
	)
	(footprint ""
		(layer "F.Cu")
		(at 64.008 -72.6948)
		(property "Reference" "R417"
			(at 0 0 0)
			(layer "F.SilkS")
			(hide yes)
			(effects
				(font
					(size 1.27 1.27)
				)
			)
		)
		(property "Value" "200KR2F-L-GP"
			(at 0.064008 -3.993896 0)
			(unlocked yes)
			(layer "F.Fab")
			(hide yes)
			(effects
				(font
					(size 1.016 1.016)
					(thickness 0.1524)
				)
			)
		)
		(property "Device Type" "R402H16"
			(at 0.064008 -5.517896 0)
			(unlocked yes)
			(layer "F.Fab")
			(hide yes)
			(effects
				(font
					(size 1.016 1.016)
					(thickness 0.1524)
				)
			)
		)
		(duplicate_pad_numbers_are_jumpers no)
		(fp_line
			(start -0.508 -0.9398)
			(end -0.508 0.9398)
			(stroke
				(width 0.1524)
				(type default)
			)
			(layer "F.SilkS")
		)
		(fp_line
			(start 0.508 -0.9398)
			(end -0.508 -0.9398)
			(stroke
				(width 0.1524)
				(type default)
			)
			(layer "F.SilkS")
		)
		(fp_rect
			(start -0.508 0.9398)
			(end 0.508 -0.9398)
			(stroke
				(width 0)
				(type default)
			)
			(fill no)
			(layer "F.CrtYd")
		)
		(fp_rect
			(start -0.508 0.9398)
			(end 0.508 -0.9398)
			(stroke
				(width 0)
				(type default)
			)
			(fill no)
			(layer "F.Fab")
		)
		(pad "1" smd custom
			(at 0 -0.4445)
			(size 0.1397 0.1397)
			(layers "F.Cu" "F.Mask" "F.Paste")
			(net "VREF5")
			(options
				(clearance outline)
				(anchor circle)
			)
			(primitives
				(gr_poly
					(pts
						(arc
							(start -0.1778 -0.2794)
							(mid -0.249642 -0.249642)
							(end -0.2794 -0.1778)
						)
						(arc
							(start -0.2794 0.1778)
							(mid -0.249642 0.249642)
							(end -0.1778 0.2794)
						)
						(arc
							(start 0.1778 0.2794)
							(mid 0.249642 0.249642)
							(end 0.2794 0.1778)
						)
						(arc
							(start 0.2794 -0.1778)
							(mid 0.249642 -0.249642)
							(end 0.1778 -0.2794)
						)
					)
					(width 0)
					(fill yes)
				)
			)
		)
		(pad "2" smd custom
			(at 0 0.4445)
			(size 0.1397 0.1397)
			(layers "F.Cu" "F.Mask" "F.Paste")
			(net "P3V3")
			(options
				(clearance outline)
				(anchor circle)
			)
			(primitives
				(gr_poly
					(pts
						(arc
							(start -0.1778 -0.2794)
							(mid -0.249642 -0.249642)
							(end -0.2794 -0.1778)
						)
						(arc
							(start -0.2794 0.1778)
							(mid -0.249642 0.249642)
							(end -0.1778 0.2794)
						)
						(arc
							(start 0.1778 0.2794)
							(mid 0.249642 0.249642)
							(end 0.2794 0.1778)
						)
						(arc
							(start 0.2794 -0.1778)
							(mid 0.249642 -0.249642)
							(end 0.1778 -0.2794)
						)
					)
					(width 0)
					(fill yes)
				)
			)
		)
	)
	(footprint ""
		(layer "F.Cu")
		(at 58.682128 -77.49667 180)
		(property "Reference" "U37"
			(at 0 0 180)
			(layer "F.SilkS")
			(hide yes)
			(effects
				(font
					(size 1.27 1.27)
				)
			)
		)
		(property "Value" "PCA9306DCTR-GP"
			(at 0 -11.6332 180)
			(unlocked yes)
			(layer "F.Fab")
			(hide yes)
			(effects
				(font
					(size 1.016 1.016)
					(thickness 0.1524)
				)
			)
		)
		(property "Device Type" "SSOIC8H52"
			(at 0 -13.1572 180)
			(unlocked yes)
			(layer "F.Fab")
			(hide yes)
			(effects
				(font
					(size 1.016 1.016)
					(thickness 0.1524)
				)
			)
		)
		(duplicate_pad_numbers_are_jumpers no)
		(fp_line
			(start 1.0668 0.5842)
			(end -1.524 0.5842)
			(stroke
				(width 0.1524)
				(type default)
			)
			(layer "F.SilkS")
		)
		(fp_line
			(start 1.0668 -0.5842)
			(end 1.0668 0.5842)
			(stroke
				(width 0.1524)
				(type default)
			)
			(layer "F.SilkS")
		)
		(fp_line
			(start -1.397 0)
			(end -1.7018 0.3048)
			(stroke
				(width 0.1524)
				(type default)
			)
			(layer "F.SilkS")
		)
		(fp_line
			(start -1.397 0)
			(end -1.7018 -0.3048)
			(stroke
				(width 0.1524)
				(type default)
			)
			(layer "F.SilkS")
		)
		(fp_line
			(start -1.524 0.5842)
			(end -1.524 2.286)
			(stroke
				(width 0.508)
				(type default)
			)
			(layer "F.SilkS")
		)
		(fp_line
			(start -1.7018 -0.5842)
			(end 1.0668 -0.5842)
			(stroke
				(width 0.1524)
				(type default)
			)
			(layer "F.SilkS")
		)
		(fp_line
			(start -1.7018 -0.5842)
			(end -1.7018 2.286)
			(stroke
				(width 0.1524)
				(type default)
			)
			(layer "F.SilkS")
		)
		(fp_poly
			(pts
				(xy -1.1684 -0.5842) (xy 1.0668 -0.5842) (xy 1.0668 0.5842) (xy -1.1684 0.5842)
			)
			(stroke
				(width 0)
				(type default)
			)
			(fill yes)
			(layer "F.SilkS")
		)
		(fp_poly
			(pts
				(xy -1.778 2.54) (xy 1.778 2.54) (xy 1.778 -2.54) (xy -1.778 -2.54)
			)
			(stroke
				(width 0)
				(type default)
			)
			(fill no)
			(layer "F.CrtYd")
		)
		(fp_poly
			(pts
				(xy -1.778 -2.54) (xy 1.778 -2.54) (xy 1.778 2.54) (xy -1.778 2.54)
			)
			(stroke
				(width 0)
				(type default)
			)
			(fill no)
			(layer "F.Fab")
		)
		(pad "1" smd rect
			(at -0.97536 1.6256 180)
			(size 0.3556 1.524)
			(layers "F.Cu" "F.Mask" "F.Paste")
			(net "GND")
		)
		(pad "2" smd rect
			(at -0.32512 1.6256 180)
			(size 0.3556 1.524)
			(layers "F.Cu" "F.Mask" "F.Paste")
			(net "P1V8_E")
		)
		(pad "3" smd rect
			(at 0.32512 1.6256 180)
			(size 0.3556 1.524)
			(layers "F.Cu" "F.Mask" "F.Paste")
			(net "I2C_DRIVE_PWR_SCL4_LS")
		)
		(pad "4" smd rect
			(at 0.97536 1.6256 180)
			(size 0.3556 1.524)
			(layers "F.Cu" "F.Mask" "F.Paste")
			(net "I2C_DRIVE_PWR_SDA4_LS")
		)
		(pad "5" smd rect
			(at 0.97536 -1.6256 180)
			(size 0.3556 1.524)
			(layers "F.Cu" "F.Mask" "F.Paste")
			(net "I2C_DRIVE_PWR_SDA4")
		)
		(pad "6" smd rect
			(at 0.32512 -1.6256 180)
			(size 0.3556 1.524)
			(layers "F.Cu" "F.Mask" "F.Paste")
			(net "I2C_DRIVE_PWR_SCL4")
		)
		(pad "7" smd rect
			(at -0.32512 -1.6256 180)
			(size 0.3556 1.524)
			(layers "F.Cu" "F.Mask" "F.Paste")
			(net "VREF4")
		)
		(pad "8" smd rect
			(at -0.97536 -1.6256 180)
			(size 0.3556 1.524)
			(layers "F.Cu" "F.Mask" "F.Paste")
			(net "LS_EN_U37")
		)
	)
	(footprint ""
		(layer "F.Cu")
		(at 12.319 -48.4378 -90)
		(property "Reference" "C574"
			(at 0 0 270)
			(layer "F.SilkS")
			(hide yes)
			(effects
				(font
					(size 1.27 1.27)
				)
			)
		)
		(property "Value" "SCD015U25V2KX-GP"
			(at 1.1811 -2.7051 270)
			(unlocked yes)
			(layer "F.Fab")
			(hide yes)
			(effects
				(font
					(size 1.016 1.016)
					(thickness 0.1524)
				)
			)
		)
		(property "Device Type" "C402H22"
			(at 1.1811 -4.2291 270)
			(unlocked yes)
			(layer "F.Fab")
			(hide yes)
			(effects
				(font
					(size 1.016 1.016)
					(thickness 0.1524)
				)
			)
		)
		(duplicate_pad_numbers_are_jumpers no)
		(fp_rect
			(start -0.4318 0.9525)
			(end 0.4318 -0.9525)
			(stroke
				(width 0)
				(type default)
			)
			(fill no)
			(layer "F.CrtYd")
		)
		(fp_rect
			(start -0.4318 0.9525)
			(end 0.4318 -0.9525)
			(stroke
				(width 0)
				(type default)
			)
			(fill no)
			(layer "F.Fab")
		)
		(pad "1" smd custom
			(at 0 -0.4445 270)
			(size 0.1524 0.1524)
			(layers "F.Cu" "F.Mask" "F.Paste")
			(net "MB0_HS_SENSE_P")
			(options
				(clearance outline)
				(anchor circle)
			)
			(primitives
				(gr_poly
					(pts
						(arc
							(start 0.3048 -0.2032)
							(mid 0.275042 -0.275042)
							(end 0.2032 -0.3048)
						)
						(arc
							(start -0.2032 -0.3048)
							(mid -0.275042 -0.275042)
							(end -0.3048 -0.2032)
						)
						(arc
							(start -0.3048 0.2032)
							(mid -0.275042 0.275042)
							(end -0.2032 0.3048)
						)
						(arc
							(start 0.2032 0.3048)
							(mid 0.275042 0.275042)
							(end 0.3048 0.2032)
						)
					)
					(width 0)
					(fill yes)
				)
			)
		)
		(pad "2" smd custom
			(at 0 0.4445 270)
			(size 0.1524 0.1524)
			(layers "F.Cu" "F.Mask" "F.Paste")
			(net "MB0_HS_SENSE_N")
			(options
				(clearance outline)
				(anchor circle)
			)
			(primitives
				(gr_poly
					(pts
						(arc
							(start 0.3048 -0.2032)
							(mid 0.275042 -0.275042)
							(end 0.2032 -0.3048)
						)
						(arc
							(start -0.2032 -0.3048)
							(mid -0.275042 -0.275042)
							(end -0.3048 -0.2032)
						)
						(arc
							(start -0.3048 0.2032)
							(mid -0.275042 0.275042)
							(end -0.2032 0.3048)
						)
						(arc
							(start 0.2032 0.3048)
							(mid 0.275042 0.275042)
							(end 0.3048 0.2032)
						)
					)
					(width 0)
					(fill yes)
				)
			)
		)
	)
	(footprint ""
		(layer "F.Cu")
		(at 142.57782 -60.525152 -90)
		(property "Reference" "C38"
			(at 0 0 270)
			(layer "F.SilkS")
			(hide yes)
			(effects
				(font
					(size 1.27 1.27)
				)
			)
		)
		(property "Value" "SCD01U16V1KX-GP"
			(at -2.8321 -1.7399 270)
			(unlocked yes)
			(layer "F.Fab")
			(hide yes)
			(effects
				(font
					(size 1.016 1.016)
					(thickness 0.1524)
				)
			)
		)
		(property "Device Type" "C0201H13"
			(at -2.8321 -3.2639 270)
			(unlocked yes)
			(layer "F.Fab")
			(hide yes)
			(effects
				(font
					(size 1.016 1.016)
					(thickness 0.1524)
				)
			)
		)
		(duplicate_pad_numbers_are_jumpers no)
		(fp_rect
			(start -0.2794 0.6477)
			(end 0.2794 -0.6477)
			(stroke
				(width 0)
				(type default)
			)
			(fill no)
			(layer "F.CrtYd")
		)
		(fp_rect
			(start -0.2794 0.6477)
			(end 0.2794 -0.6477)
			(stroke
				(width 0)
				(type default)
			)
			(fill no)
			(layer "F.Fab")
		)
		(pad "1" smd custom
			(at 0 -0.2794 270)
			(size 0.0762 0.0762)
			(layers "F.Cu" "F.Mask" "F.Paste")
			(net "PHY_IOC_TO_SCC_45_DN")
			(options
				(clearance outline)
				(anchor circle)
			)
			(primitives
				(gr_poly
					(pts
						(arc
							(start 0.1524 -0.127)
							(mid 0.137521 -0.162921)
							(end 0.1016 -0.1778)
						)
						(arc
							(start -0.1016 -0.1778)
							(mid -0.137521 -0.162921)
							(end -0.1524 -0.127)
						)
						(arc
							(start -0.1524 0.127)
							(mid -0.137521 0.162921)
							(end -0.1016 0.1778)
						)
						(arc
							(start 0.1016 0.1778)
							(mid 0.137521 0.162921)
							(end 0.1524 0.127)
						)
					)
					(width 0)
					(fill yes)
				)
			)
		)
		(pad "2" smd custom
			(at 0 0.2794 270)
			(size 0.0762 0.0762)
			(layers "F.Cu" "F.Mask" "F.Paste")
			(net "PHY_IOC_TO_SCC_C_45_DN")
			(options
				(clearance outline)
				(anchor circle)
			)
			(primitives
				(gr_poly
					(pts
						(arc
							(start 0.1524 -0.127)
							(mid 0.137521 -0.162921)
							(end 0.1016 -0.1778)
						)
						(arc
							(start -0.1016 -0.1778)
							(mid -0.137521 -0.162921)
							(end -0.1524 -0.127)
						)
						(arc
							(start -0.1524 0.127)
							(mid -0.137521 0.162921)
							(end -0.1016 0.1778)
						)
						(arc
							(start 0.1016 0.1778)
							(mid 0.137521 0.162921)
							(end 0.1524 0.127)
						)
					)
					(width 0)
					(fill yes)
				)
			)
		)
	)
	(footprint ""
		(layer "F.Cu")
		(at 22.715982 -30.934152)
		(property "Reference" "C565"
			(at 0 0 0)
			(layer "F.SilkS")
			(hide yes)
			(effects
				(font
					(size 1.27 1.27)
				)
			)
		)
		(property "Value" "SC10U16V5KX-7-GP-U"
			(at -0.0762 -6.1214 0)
			(unlocked yes)
			(layer "F.Fab")
			(hide yes)
			(effects
				(font
					(size 1.016 1.016)
					(thickness 0.1524)
				)
			)
		)
		(property "Device Type" "C805H58"
			(at -0.0762 -8.1534 0)
			(unlocked yes)
			(layer "F.Fab")
			(hide yes)
			(effects
				(font
					(size 1.016 1.016)
					(thickness 0.1524)
				)
			)
		)
		(duplicate_pad_numbers_are_jumpers no)
		(fp_line
			(start 0.635 0)
			(end -0.635 0)
			(stroke
				(width 0.508)
				(type default)
			)
			(layer "F.SilkS")
		)
		(fp_rect
			(start -0.9652 1.778)
			(end 0.9652 -1.778)
			(stroke
				(width 0)
				(type default)
			)
			(fill no)
			(layer "F.CrtYd")
		)
		(fp_poly
			(pts
				(xy -0.9652 -1.778) (xy 0.9652 -1.778) (xy 0.9652 1.778) (xy -0.9652 1.778)
			)
			(stroke
				(width 0)
				(type default)
			)
			(fill no)
			(layer "F.Fab")
		)
		(pad "1" smd rect
			(at 0 -0.9652)
			(size 1.397 1.143)
			(layers "F.Cu" "F.Mask" "F.Paste")
			(net "P12V_MAIN")
		)
		(pad "2" smd rect
			(at 0 0.9652)
			(size 1.397 1.143)
			(layers "F.Cu" "F.Mask" "F.Paste")
			(net "GND")
		)
	)
	(footprint ""
		(layer "F.Cu")
		(at 13.310616 -79.355188 -90)
		(property "Reference" "U27"
			(at 0 0 270)
			(layer "F.SilkS")
			(hide yes)
			(effects
				(font
					(size 1.27 1.27)
				)
			)
		)
		(property "Value" "CAT24C64WI-GT3-GP"
			(at -3.707384 -1.5367 270)
			(unlocked yes)
			(layer "F.Fab")
			(hide yes)
			(effects
				(font
					(size 1.016 1.016)
					(thickness 0.1524)
				)
			)
		)
		(property "Device Type" "SOIC8H69"
			(at -3.707384 -3.0607 270)
			(unlocked yes)
			(layer "F.Fab")
			(hide yes)
			(effects
				(font
					(size 1.016 1.016)
					(thickness 0.1524)
				)
			)
		)
		(duplicate_pad_numbers_are_jumpers no)
		(fp_line
			(start -2.6289 3.4417)
			(end -2.6289 1.4732)
			(stroke
				(width 0.381)
				(type default)
			)
			(layer "F.SilkS")
		)
		(fp_line
			(start -2.7432 1.4224)
			(end -2.6416 1.4224)
			(stroke
				(width 0.1524)
				(type default)
			)
			(layer "F.SilkS")
		)
		(fp_line
			(start -2.7432 1.4224)
			(end 2.1336 1.4224)
			(stroke
				(width 0.1524)
				(type default)
			)
			(layer "F.SilkS")
		)
		(fp_line
			(start 2.1336 1.4224)
			(end 2.1336 -1.4224)
			(stroke
				(width 0.1524)
				(type default)
			)
			(layer "F.SilkS")
		)
		(fp_line
			(start -2.1844 -0.0508)
			(end -2.7178 0.508)
			(stroke
				(width 0.1524)
				(type default)
			)
			(layer "F.SilkS")
		)
		(fp_line
			(start -2.7178 -0.508)
			(end -2.1844 -0.0508)
			(stroke
				(width 0.1524)
				(type default)
			)
			(layer "F.SilkS")
		)
		(fp_line
			(start -2.7432 -1.4224)
			(end -2.7432 1.4224)
			(stroke
				(width 0.1524)
				(type default)
			)
			(layer "F.SilkS")
		)
		(fp_line
			(start 2.1336 -1.4224)
			(end -2.7432 -1.4224)
			(stroke
				(width 0.1524)
				(type default)
			)
			(layer "F.SilkS")
		)
		(fp_poly
			(pts
				(xy -2.2098 -1.4224) (xy -2.2098 1.4224) (xy 2.2098 1.4224) (xy 2.2098 -1.4224)
			)
			(stroke
				(width 0)
				(type default)
			)
			(fill yes)
			(layer "F.SilkS")
		)
		(fp_rect
			(start -2.450084 2.999994)
			(end 2.450084 -2.999994)
			(stroke
				(width 0)
				(type default)
			)
			(fill no)
			(layer "F.CrtYd")
		)
		(fp_poly
			(pts
				(xy -2.8194 3.6322) (xy -2.8194 -3.6322) (xy 2.8194 -3.6322) (xy 2.8194 1.18364) (xy 2.450084 1.18364)
				(xy 2.450084 -2.999994) (xy -2.450084 -2.999994) (xy -2.450084 2.999994) (xy 2.450084 2.999994)
				(xy 2.450084 1.18618) (xy 2.8194 1.18618) (xy 2.8194 3.6322)
			)
			(stroke
				(width 0)
				(type default)
			)
			(fill no)
			(layer "F.CrtYd")
		)
		(fp_rect
			(start -2.8194 3.6322)
			(end 2.8194 -3.6322)
			(stroke
				(width 0)
				(type default)
			)
			(fill no)
			(layer "F.Fab")
		)
		(pad "1" smd rect
			(at -1.905 2.54 270)
			(size 0.635 1.651)
			(layers "F.Cu" "F.Mask" "F.Paste")
			(net "EXP_EEPROM_A0")
		)
		(pad "2" smd rect
			(at -0.635 2.54 270)
			(size 0.635 1.651)
			(layers "F.Cu" "F.Mask" "F.Paste")
			(net "EXP_EEPROM_A1")
		)
		(pad "3" smd rect
			(at 0.635 2.54 270)
			(size 0.635 1.651)
			(layers "F.Cu" "F.Mask" "F.Paste")
			(net "EXP_EEPROM_A2")
		)
		(pad "4" smd rect
			(at 1.905 2.54 270)
			(size 0.635 1.651)
			(layers "F.Cu" "F.Mask" "F.Paste")
			(net "GND")
		)
		(pad "5" smd rect
			(at 1.905 -2.54 270)
			(size 0.635 1.651)
			(layers "F.Cu" "F.Mask" "F.Paste")
			(net "EXP_EEPROM_SDA")
		)
		(pad "6" smd rect
			(at 0.635 -2.54 270)
			(size 0.635 1.651)
			(layers "F.Cu" "F.Mask" "F.Paste")
			(net "EXP_EEPROM_SCL")
		)
		(pad "7" smd rect
			(at -0.635 -2.54 270)
			(size 0.635 1.651)
			(layers "F.Cu" "F.Mask" "F.Paste")
			(net "EXP_EEPROM_WP")
		)
		(pad "8" smd rect
			(at -1.905 -2.54 270)
			(size 0.635 1.651)
			(layers "F.Cu" "F.Mask" "F.Paste")
			(net "P3V3")
		)
	)
	(footprint ""
		(layer "F.Cu")
		(at 124.6632 -108.59008)
		(property "Reference" "TP167"
			(at 0 0 0)
			(layer "F.SilkS")
			(hide yes)
			(effects
				(font
					(size 1.27 1.27)
				)
			)
		)
		(property "Value" "TPAD28-2-GP"
			(at -0.0127 -1.6637 0)
			(unlocked yes)
			(layer "F.Fab")
			(hide yes)
			(effects
				(font
					(size 1.016 1.016)
					(thickness 0.1524)
				)
			)
		)
		(property "Device Type" "TPAD28"
			(at -0.0127 -3.1877 0)
			(unlocked yes)
			(layer "F.Fab")
			(hide yes)
			(effects
				(font
					(size 1.016 1.016)
					(thickness 0.1524)
				)
			)
		)
		(duplicate_pad_numbers_are_jumpers no)
		(fp_poly
			(pts
				(arc
					(start 0.3556 0)
					(mid -0.3556 0)
					(end 0.3556 0)
				)
			)
			(stroke
				(width 0)
				(type default)
			)
			(fill no)
			(layer "F.CrtYd")
		)
		(fp_poly
			(pts
				(arc
					(start 0.6096 0)
					(mid -0.6096 0)
					(end 0.6096 0)
				)
			)
			(stroke
				(width 0)
				(type default)
			)
			(fill no)
			(layer "F.Fab")
		)
		(pad "1" smd circle
			(at 0 0)
			(size 0.7112 0.7112)
			(layers "F.Cu" "F.Mask" "F.Paste")
			(net "INT_D2_CONN1")
		)
	)
	(footprint ""
		(layer "F.Cu")
		(at 86.9315 -78.695042 -90)
		(property "Reference" "R150"
			(at 0 0 270)
			(layer "F.SilkS")
			(hide yes)
			(effects
				(font
					(size 1.27 1.27)
				)
			)
		)
		(property "Value" "4K75R2F-1-GP"
			(at 0.064008 -3.993896 270)
			(unlocked yes)
			(layer "F.Fab")
			(hide yes)
			(effects
				(font
					(size 1.016 1.016)
					(thickness 0.1524)
				)
			)
		)
		(property "Device Type" "R402H16"
			(at 0.064008 -5.517896 270)
			(unlocked yes)
			(layer "F.Fab")
			(hide yes)
			(effects
				(font
					(size 1.016 1.016)
					(thickness 0.1524)
				)
			)
		)
		(duplicate_pad_numbers_are_jumpers no)
		(fp_line
			(start -0.508 -0.9398)
			(end -0.508 0.9398)
			(stroke
				(width 0.1524)
				(type default)
			)
			(layer "F.SilkS")
		)
		(fp_line
			(start 0.508 -0.9398)
			(end -0.508 -0.9398)
			(stroke
				(width 0.1524)
				(type default)
			)
			(layer "F.SilkS")
		)
		(fp_rect
			(start -0.508 0.9398)
			(end 0.508 -0.9398)
			(stroke
				(width 0)
				(type default)
			)
			(fill no)
			(layer "F.CrtYd")
		)
		(fp_rect
			(start -0.508 0.9398)
			(end 0.508 -0.9398)
			(stroke
				(width 0)
				(type default)
			)
			(fill no)
			(layer "F.Fab")
		)
		(pad "1" smd custom
			(at 0 -0.4445 270)
			(size 0.1397 0.1397)
			(layers "F.Cu" "F.Mask" "F.Paste")
			(net "P1V8_E")
			(options
				(clearance outline)
				(anchor circle)
			)
			(primitives
				(gr_poly
					(pts
						(arc
							(start -0.1778 -0.2794)
							(mid -0.249642 -0.249642)
							(end -0.2794 -0.1778)
						)
						(arc
							(start -0.2794 0.1778)
							(mid -0.249642 0.249642)
							(end -0.1778 0.2794)
						)
						(arc
							(start 0.1778 0.2794)
							(mid 0.249642 0.249642)
							(end 0.2794 0.1778)
						)
						(arc
							(start 0.2794 -0.1778)
							(mid 0.249642 -0.249642)
							(end 0.1778 -0.2794)
						)
					)
					(width 0)
					(fill yes)
				)
			)
		)
		(pad "2" smd custom
			(at 0 0.4445 270)
			(size 0.1397 0.1397)
			(layers "F.Cu" "F.Mask" "F.Paste")
			(net "EXP_XM_NOR_CS_N")
			(options
				(clearance outline)
				(anchor circle)
			)
			(primitives
				(gr_poly
					(pts
						(arc
							(start -0.1778 -0.2794)
							(mid -0.249642 -0.249642)
							(end -0.2794 -0.1778)
						)
						(arc
							(start -0.2794 0.1778)
							(mid -0.249642 0.249642)
							(end -0.1778 0.2794)
						)
						(arc
							(start 0.1778 0.2794)
							(mid 0.249642 0.249642)
							(end 0.2794 0.1778)
						)
						(arc
							(start 0.2794 -0.1778)
							(mid 0.249642 -0.249642)
							(end 0.1778 -0.2794)
						)
					)
					(width 0)
					(fill yes)
				)
			)
		)
	)
	(footprint ""
		(layer "F.Cu")
		(at 159.722312 -97.867216 90)
		(property "Reference" "R291"
			(at 0 0 90)
			(layer "F.SilkS")
			(hide yes)
			(effects
				(font
					(size 1.27 1.27)
				)
			)
		)
		(property "Value" "10KR2F-2-GP"
			(at 0.064008 -3.993896 90)
			(unlocked yes)
			(layer "F.Fab")
			(hide yes)
			(effects
				(font
					(size 1.016 1.016)
					(thickness 0.1524)
				)
			)
		)
		(property "Device Type" "R402H16"
			(at 0.064008 -5.517896 90)
			(unlocked yes)
			(layer "F.Fab")
			(hide yes)
			(effects
				(font
					(size 1.016 1.016)
					(thickness 0.1524)
				)
			)
		)
		(duplicate_pad_numbers_are_jumpers no)
		(fp_line
			(start 0.508 -0.9398)
			(end -0.508 -0.9398)
			(stroke
				(width 0.1524)
				(type default)
			)
			(layer "F.SilkS")
		)
		(fp_line
			(start -0.508 -0.9398)
			(end -0.508 0.9398)
			(stroke
				(width 0.1524)
				(type default)
			)
			(layer "F.SilkS")
		)
		(fp_rect
			(start -0.508 0.9398)
			(end 0.508 -0.9398)
			(stroke
				(width 0)
				(type default)
			)
			(fill no)
			(layer "F.CrtYd")
		)
		(fp_rect
			(start -0.508 0.9398)
			(end 0.508 -0.9398)
			(stroke
				(width 0)
				(type default)
			)
			(fill no)
			(layer "F.Fab")
		)
		(pad "1" smd custom
			(at 0 -0.4445 90)
			(size 0.1397 0.1397)
			(layers "F.Cu" "F.Mask" "F.Paste")
			(net "SDB_UART_EN")
			(options
				(clearance outline)
				(anchor circle)
			)
			(primitives
				(gr_poly
					(pts
						(arc
							(start -0.1778 -0.2794)
							(mid -0.249642 -0.249642)
							(end -0.2794 -0.1778)
						)
						(arc
							(start -0.2794 0.1778)
							(mid -0.249642 0.249642)
							(end -0.1778 0.2794)
						)
						(arc
							(start 0.1778 0.2794)
							(mid 0.249642 0.249642)
							(end 0.2794 0.1778)
						)
						(arc
							(start 0.2794 -0.1778)
							(mid 0.249642 -0.249642)
							(end 0.1778 -0.2794)
						)
					)
					(width 0)
					(fill yes)
				)
			)
		)
		(pad "2" smd custom
			(at 0 0.4445 90)
			(size 0.1397 0.1397)
			(layers "F.Cu" "F.Mask" "F.Paste")
			(net "P1V8_E")
			(options
				(clearance outline)
				(anchor circle)
			)
			(primitives
				(gr_poly
					(pts
						(arc
							(start -0.1778 -0.2794)
							(mid -0.249642 -0.249642)
							(end -0.2794 -0.1778)
						)
						(arc
							(start -0.2794 0.1778)
							(mid -0.249642 0.249642)
							(end -0.1778 0.2794)
						)
						(arc
							(start 0.1778 0.2794)
							(mid 0.249642 0.249642)
							(end 0.2794 0.1778)
						)
						(arc
							(start 0.2794 -0.1778)
							(mid 0.249642 -0.249642)
							(end 0.1778 -0.2794)
						)
					)
					(width 0)
					(fill yes)
				)
			)
		)
	)
	(footprint ""
		(layer "F.Cu")
		(at 170.217084 -23.55977 90)
		(property "Reference" "VIA3"
			(at 0 0 90)
			(layer "F.SilkS")
			(hide yes)
			(effects
				(font
					(size 1.27 1.27)
				)
			)
		)
		(property "Value" "85OHM-8L-1D6MM-L16L18-GP"
			(at 4.064 0.6096 90)
			(unlocked yes)
			(layer "F.Fab")
			(hide yes)
			(effects
				(font
					(size 1.016 1.016)
					(thickness 0.1524)
				)
			)
		)
		(property "Device Type" "VIA-PCIE-4P-368076"
			(at 4.064 -0.9144 90)
			(unlocked yes)
			(layer "F.Fab")
			(hide yes)
			(effects
				(font
					(size 1.016 1.016)
					(thickness 0.1524)
				)
			)
		)
		(duplicate_pad_numbers_are_jumpers no)
		(fp_rect
			(start -1.8415 0.381)
			(end 1.8415 -0.381)
			(stroke
				(width 0)
				(type default)
			)
			(fill no)
			(layer "F.CrtYd")
		)
		(fp_rect
			(start -1.8415 0.381)
			(end 1.8415 -0.381)
			(stroke
				(width 0)
				(type default)
			)
			(fill no)
			(layer "F.Fab")
		)
		(pad "1" thru_hole circle
			(at -1.4605 0 90)
			(size 0.508 0.508)
			(drill 0.254)
			(layers "*.Cu" "*.Mask")
			(remove_unused_layers no)
			(net "GND")
			(clearance 0.127)
			(thermal_gap 0.127)
		)
		(pad "2" thru_hole circle
			(at -0.4445 0 90)
			(size 0.508 0.508)
			(drill 0.254)
			(layers "*.Cu" "*.Mask")
			(remove_unused_layers no)
			(net "PCIE_COMP_TO_SCC_2_DP")
			(clearance 0.127)
			(thermal_gap 0.127)
		)
		(pad "3" thru_hole circle
			(at 0.4445 0 90)
			(size 0.508 0.508)
			(drill 0.254)
			(layers "*.Cu" "*.Mask")
			(remove_unused_layers no)
			(net "PCIE_COMP_TO_SCC_2_DN")
			(clearance 0.127)
			(thermal_gap 0.127)
		)
		(pad "4" thru_hole circle
			(at 1.4605 0 90)
			(size 0.508 0.508)
			(drill 0.254)
			(layers "*.Cu" "*.Mask")
			(remove_unused_layers no)
			(net "GND")
			(clearance 0.127)
			(thermal_gap 0.127)
		)
	)
	(footprint ""
		(layer "F.Cu")
		(at 123.603258 -90.595196 180)
		(property "Reference" "R126"
			(at 0 0 180)
			(layer "F.SilkS")
			(hide yes)
			(effects
				(font
					(size 1.27 1.27)
				)
			)
		)
		(property "Value" "4K7R2F-GP"
			(at 0.064008 -3.993896 180)
			(unlocked yes)
			(layer "F.Fab")
			(hide yes)
			(effects
				(font
					(size 1.016 1.016)
					(thickness 0.1524)
				)
			)
		)
		(property "Device Type" "R402H16"
			(at 0.064008 -5.517896 180)
			(unlocked yes)
			(layer "F.Fab")
			(hide yes)
			(effects
				(font
					(size 1.016 1.016)
					(thickness 0.1524)
				)
			)
		)
		(duplicate_pad_numbers_are_jumpers no)
		(fp_line
			(start 0.508 -0.9398)
			(end -0.508 -0.9398)
			(stroke
				(width 0.1524)
				(type default)
			)
			(layer "F.SilkS")
		)
		(fp_line
			(start -0.508 -0.9398)
			(end -0.508 0.9398)
			(stroke
				(width 0.1524)
				(type default)
			)
			(layer "F.SilkS")
		)
		(fp_rect
			(start -0.508 0.9398)
			(end 0.508 -0.9398)
			(stroke
				(width 0)
				(type default)
			)
			(fill no)
			(layer "F.CrtYd")
		)
		(fp_rect
			(start -0.508 0.9398)
			(end 0.508 -0.9398)
			(stroke
				(width 0)
				(type default)
			)
			(fill no)
			(layer "F.Fab")
		)
		(pad "1" smd custom
			(at 0 -0.4445 180)
			(size 0.1397 0.1397)
			(layers "F.Cu" "F.Mask" "F.Paste")
			(net "USB_CLK")
			(options
				(clearance outline)
				(anchor circle)
			)
			(primitives
				(gr_poly
					(pts
						(arc
							(start -0.1778 -0.2794)
							(mid -0.249642 -0.249642)
							(end -0.2794 -0.1778)
						)
						(arc
							(start -0.2794 0.1778)
							(mid -0.249642 0.249642)
							(end -0.1778 0.2794)
						)
						(arc
							(start 0.1778 0.2794)
							(mid 0.249642 0.249642)
							(end 0.2794 0.1778)
						)
						(arc
							(start 0.2794 -0.1778)
							(mid 0.249642 -0.249642)
							(end 0.1778 -0.2794)
						)
					)
					(width 0)
					(fill yes)
				)
			)
		)
		(pad "2" smd custom
			(at 0 0.4445 180)
			(size 0.1397 0.1397)
			(layers "F.Cu" "F.Mask" "F.Paste")
			(net "GND")
			(options
				(clearance outline)
				(anchor circle)
			)
			(primitives
				(gr_poly
					(pts
						(arc
							(start -0.1778 -0.2794)
							(mid -0.249642 -0.249642)
							(end -0.2794 -0.1778)
						)
						(arc
							(start -0.2794 0.1778)
							(mid -0.249642 0.249642)
							(end -0.1778 0.2794)
						)
						(arc
							(start 0.1778 0.2794)
							(mid 0.249642 0.249642)
							(end 0.2794 0.1778)
						)
						(arc
							(start 0.2794 -0.1778)
							(mid 0.249642 -0.249642)
							(end 0.1778 -0.2794)
						)
					)
					(width 0)
					(fill yes)
				)
			)
		)
	)
	(footprint ""
		(layer "F.Cu")
		(at 135.975344 -84.714588)
		(property "Reference" "R61"
			(at 0 0 0)
			(layer "F.SilkS")
			(hide yes)
			(effects
				(font
					(size 1.27 1.27)
				)
			)
		)
		(property "Value" "4K7R2F-GP"
			(at 0.064008 -3.993896 0)
			(unlocked yes)
			(layer "F.Fab")
			(hide yes)
			(effects
				(font
					(size 1.016 1.016)
					(thickness 0.1524)
				)
			)
		)
		(property "Device Type" "R402H16"
			(at 0.064008 -5.517896 0)
			(unlocked yes)
			(layer "F.Fab")
			(hide yes)
			(effects
				(font
					(size 1.016 1.016)
					(thickness 0.1524)
				)
			)
		)
		(duplicate_pad_numbers_are_jumpers no)
		(fp_line
			(start -0.508 -0.9398)
			(end -0.508 0.9398)
			(stroke
				(width 0.1524)
				(type default)
			)
			(layer "F.SilkS")
		)
		(fp_line
			(start 0.508 -0.9398)
			(end -0.508 -0.9398)
			(stroke
				(width 0.1524)
				(type default)
			)
			(layer "F.SilkS")
		)
		(fp_rect
			(start -0.508 0.9398)
			(end 0.508 -0.9398)
			(stroke
				(width 0)
				(type default)
			)
			(fill no)
			(layer "F.CrtYd")
		)
		(fp_rect
			(start -0.508 0.9398)
			(end 0.508 -0.9398)
			(stroke
				(width 0)
				(type default)
			)
			(fill no)
			(layer "F.Fab")
		)
		(pad "1" smd custom
			(at 0 -0.4445)
			(size 0.1397 0.1397)
			(layers "F.Cu" "F.Mask" "F.Paste")
			(net "P1V8_E")
			(options
				(clearance outline)
				(anchor circle)
			)
			(primitives
				(gr_poly
					(pts
						(arc
							(start -0.1778 -0.2794)
							(mid -0.249642 -0.249642)
							(end -0.2794 -0.1778)
						)
						(arc
							(start -0.2794 0.1778)
							(mid -0.249642 0.249642)
							(end -0.1778 0.2794)
						)
						(arc
							(start 0.1778 0.2794)
							(mid 0.249642 0.249642)
							(end 0.2794 0.1778)
						)
						(arc
							(start 0.2794 -0.1778)
							(mid 0.249642 -0.249642)
							(end 0.1778 -0.2794)
						)
					)
					(width 0)
					(fill yes)
				)
			)
		)
		(pad "2" smd custom
			(at 0 0.4445)
			(size 0.1397 0.1397)
			(layers "F.Cu" "F.Mask" "F.Paste")
			(net "I2C_DRIVE_FLT_LED_SDA6_LS")
			(options
				(clearance outline)
				(anchor circle)
			)
			(primitives
				(gr_poly
					(pts
						(arc
							(start -0.1778 -0.2794)
							(mid -0.249642 -0.249642)
							(end -0.2794 -0.1778)
						)
						(arc
							(start -0.2794 0.1778)
							(mid -0.249642 0.249642)
							(end -0.1778 0.2794)
						)
						(arc
							(start 0.1778 0.2794)
							(mid 0.249642 0.249642)
							(end 0.2794 0.1778)
						)
						(arc
							(start 0.2794 -0.1778)
							(mid 0.249642 -0.249642)
							(end 0.1778 -0.2794)
						)
					)
					(width 0)
					(fill yes)
				)
			)
		)
	)
	(footprint ""
		(layer "F.Cu")
		(at 175.317404 -88.333834 90)
		(property "Reference" "L33"
			(at 0 0 90)
			(layer "F.SilkS")
			(hide yes)
			(effects
				(font
					(size 1.27 1.27)
				)
			)
		)
		(property "Value" "COIL-D24UH-GP"
			(at -5.5118 1.5748 90)
			(unlocked yes)
			(layer "F.Fab")
			(hide yes)
			(effects
				(font
					(size 1.016 1.016)
					(thickness 0.1524)
				)
			)
		)
		(property "Device Type" "L7267-1630H158"
			(at -5.5118 0.0508 90)
			(unlocked yes)
			(layer "F.Fab")
			(hide yes)
			(effects
				(font
					(size 1.016 1.016)
					(thickness 0.1524)
				)
			)
		)
		(duplicate_pad_numbers_are_jumpers no)
		(fp_line
			(start 3.6068 -4.6101)
			(end 3.6068 4.6101)
			(stroke
				(width 0.1524)
				(type default)
			)
			(layer "F.SilkS")
		)
		(fp_line
			(start -3.6068 -4.6101)
			(end 3.6068 -4.6101)
			(stroke
				(width 0.1524)
				(type default)
			)
			(layer "F.SilkS")
		)
		(fp_line
			(start 3.6068 4.6101)
			(end -3.6068 4.6101)
			(stroke
				(width 0.1524)
				(type default)
			)
			(layer "F.SilkS")
		)
		(fp_line
			(start -3.6068 4.6101)
			(end -3.6068 -4.6101)
			(stroke
				(width 0.1524)
				(type default)
			)
			(layer "F.SilkS")
		)
		(fp_rect
			(start -3.3528 3.5941)
			(end 3.3528 -3.5941)
			(stroke
				(width 0)
				(type default)
			)
			(fill no)
			(layer "F.CrtYd")
		)
		(fp_poly
			(pts
				(xy -3.8608 4.6863) (xy -3.8608 3.5941) (xy 3.3528 3.5941) (xy 3.3528 -3.5941) (xy -3.3528 -3.5941)
				(xy -3.3528 3.5814) (xy -3.8608 3.5814) (xy -3.8608 -4.6863) (xy 3.8608 -4.6863) (xy 3.8608 4.6863)
			)
			(stroke
				(width 0)
				(type default)
			)
			(fill no)
			(layer "F.CrtYd")
		)
		(fp_rect
			(start -3.8608 4.6863)
			(end 3.8608 -4.6863)
			(stroke
				(width 0)
				(type default)
			)
			(fill no)
			(layer "F.Fab")
		)
		(pad "1" smd rect
			(at 0 -2.990596 90)
			(size 3.5052 2.7432)
			(layers "F.Cu" "F.Mask" "F.Paste")
			(net "VT235_VX")
		)
		(pad "2" smd rect
			(at 0 2.990596 90)
			(size 3.5052 2.7432)
			(layers "F.Cu" "F.Mask" "F.Paste")
			(net "P0V975")
		)
	)
	(footprint ""
		(layer "F.Cu")
		(at 149.95906 -37.995352 102)
		(property "Reference" "C332"
			(at 0 0 102)
			(layer "F.SilkS")
			(hide yes)
			(effects
				(font
					(size 1.27 1.27)
				)
			)
		)
		(property "Value" "SCD01U16V1KX-GP"
			(at -2.832296 -1.73983 102)
			(unlocked yes)
			(layer "F.Fab")
			(hide yes)
			(effects
				(font
					(size 1.016 1.016)
					(thickness 0.1524)
				)
			)
		)
		(property "Device Type" "C0201H13"
			(at -2.832174 -3.263834 102)
			(unlocked yes)
			(layer "F.Fab")
			(hide yes)
			(effects
				(font
					(size 1.016 1.016)
					(thickness 0.1524)
				)
			)
		)
		(duplicate_pad_numbers_are_jumpers no)
		(fp_poly
			(pts
				(xy -0.279454 -0.647706) (xy 0.279346 -0.647706) (xy 0.279346 0.647694) (xy -0.279454 0.647694)
			)
			(stroke
				(width 0)
				(type default)
			)
			(fill no)
			(layer "F.CrtYd")
		)
		(fp_poly
			(pts
				(xy -0.279454 -0.647706) (xy 0.279346 -0.647706) (xy 0.279346 0.647694) (xy -0.279454 0.647694)
			)
			(stroke
				(width 0)
				(type default)
			)
			(fill no)
			(layer "F.Fab")
		)
		(pad "1" smd custom
			(at -0.000001 -0.2794 102)
			(size 0.0762 0.0762)
			(layers "F.Cu" "F.Mask" "F.Paste")
			(net "PHY_SCC_TO_IOC_42_DN")
			(options
				(clearance outline)
				(anchor circle)
			)
			(primitives
				(gr_poly
					(pts
						(arc
							(start 0.1524 -0.127)
							(mid 0.137521 -0.162921)
							(end 0.1016 -0.1778)
						)
						(arc
							(start -0.1016 -0.1778)
							(mid -0.137521 -0.162921)
							(end -0.1524 -0.127)
						)
						(arc
							(start -0.1524 0.127)
							(mid -0.137521 0.162921)
							(end -0.1016 0.1778)
						)
						(arc
							(start 0.1016 0.1778)
							(mid 0.137521 0.162921)
							(end 0.1524 0.127)
						)
					)
					(width 0)
					(fill yes)
				)
			)
		)
		(pad "2" smd custom
			(at 0.000001 0.2794 102)
			(size 0.0762 0.0762)
			(layers "F.Cu" "F.Mask" "F.Paste")
			(net "PHY_SCC_TO_IOC_C_42_DN")
			(options
				(clearance outline)
				(anchor circle)
			)
			(primitives
				(gr_poly
					(pts
						(arc
							(start 0.1524 -0.127)
							(mid 0.137521 -0.162921)
							(end 0.1016 -0.1778)
						)
						(arc
							(start -0.1016 -0.1778)
							(mid -0.137521 -0.162921)
							(end -0.1524 -0.127)
						)
						(arc
							(start -0.1524 0.127)
							(mid -0.137521 0.162921)
							(end -0.1016 0.1778)
						)
						(arc
							(start 0.1016 0.1778)
							(mid 0.137521 0.162921)
							(end 0.1524 0.127)
						)
					)
					(width 0)
					(fill yes)
				)
			)
		)
	)
	(footprint ""
		(layer "F.Cu")
		(at 147.470114 -40.80891 102)
		(property "Reference" "C333"
			(at 0 0 102)
			(layer "F.SilkS")
			(hide yes)
			(effects
				(font
					(size 1.27 1.27)
				)
			)
		)
		(property "Value" "SCD01U16V1KX-GP"
			(at -2.832048 -1.739777 102)
			(unlocked yes)
			(layer "F.Fab")
			(hide yes)
			(effects
				(font
					(size 1.016 1.016)
					(thickness 0.1524)
				)
			)
		)
		(property "Device Type" "C0201H13"
			(at -2.831925 -3.263781 102)
			(unlocked yes)
			(layer "F.Fab")
			(hide yes)
			(effects
				(font
					(size 1.016 1.016)
					(thickness 0.1524)
				)
			)
		)
		(duplicate_pad_numbers_are_jumpers no)
		(fp_poly
			(pts
				(xy -0.279454 -0.647706) (xy 0.279346 -0.647706) (xy 0.279346 0.647694) (xy -0.279454 0.647694)
			)
			(stroke
				(width 0)
				(type default)
			)
			(fill no)
			(layer "F.CrtYd")
		)
		(fp_poly
			(pts
				(xy -0.279454 -0.647706) (xy 0.279346 -0.647706) (xy 0.279346 0.647694) (xy -0.279454 0.647694)
			)
			(stroke
				(width 0)
				(type default)
			)
			(fill no)
			(layer "F.Fab")
		)
		(pad "1" smd custom
			(at -0.000001 -0.2794 102)
			(size 0.0762 0.0762)
			(layers "F.Cu" "F.Mask" "F.Paste")
			(net "PHY_SCC_TO_IOC_43_DP")
			(options
				(clearance outline)
				(anchor circle)
			)
			(primitives
				(gr_poly
					(pts
						(arc
							(start 0.1524 -0.127)
							(mid 0.137521 -0.162921)
							(end 0.1016 -0.1778)
						)
						(arc
							(start -0.1016 -0.1778)
							(mid -0.137521 -0.162921)
							(end -0.1524 -0.127)
						)
						(arc
							(start -0.1524 0.127)
							(mid -0.137521 0.162921)
							(end -0.1016 0.1778)
						)
						(arc
							(start 0.1016 0.1778)
							(mid 0.137521 0.162921)
							(end 0.1524 0.127)
						)
					)
					(width 0)
					(fill yes)
				)
			)
		)
		(pad "2" smd custom
			(at 0.000001 0.2794 102)
			(size 0.0762 0.0762)
			(layers "F.Cu" "F.Mask" "F.Paste")
			(net "PHY_SCC_TO_IOC_C_43_DP")
			(options
				(clearance outline)
				(anchor circle)
			)
			(primitives
				(gr_poly
					(pts
						(arc
							(start 0.1524 -0.127)
							(mid 0.137521 -0.162921)
							(end 0.1016 -0.1778)
						)
						(arc
							(start -0.1016 -0.1778)
							(mid -0.137521 -0.162921)
							(end -0.1524 -0.127)
						)
						(arc
							(start -0.1524 0.127)
							(mid -0.137521 0.162921)
							(end -0.1016 0.1778)
						)
						(arc
							(start 0.1016 0.1778)
							(mid 0.137521 0.162921)
							(end 0.1524 0.127)
						)
					)
					(width 0)
					(fill yes)
				)
			)
		)
	)
	(footprint ""
		(layer "F.Cu")
		(at 66.421 -104.6734 90)
		(property "Reference" "R501"
			(at 0 0 90)
			(layer "F.SilkS")
			(hide yes)
			(effects
				(font
					(size 1.27 1.27)
				)
			)
		)
		(property "Value" "19K6R2F-GP"
			(at 0.064008 -3.993896 90)
			(unlocked yes)
			(layer "F.Fab")
			(hide yes)
			(effects
				(font
					(size 1.016 1.016)
					(thickness 0.1524)
				)
			)
		)
		(property "Device Type" "R402H16"
			(at 0.064008 -5.517896 90)
			(unlocked yes)
			(layer "F.Fab")
			(hide yes)
			(effects
				(font
					(size 1.016 1.016)
					(thickness 0.1524)
				)
			)
		)
		(duplicate_pad_numbers_are_jumpers no)
		(fp_line
			(start 0.508 -0.9398)
			(end -0.508 -0.9398)
			(stroke
				(width 0.1524)
				(type default)
			)
			(layer "F.SilkS")
		)
		(fp_line
			(start -0.508 -0.9398)
			(end -0.508 0.9398)
			(stroke
				(width 0.1524)
				(type default)
			)
			(layer "F.SilkS")
		)
		(fp_rect
			(start -0.508 0.9398)
			(end 0.508 -0.9398)
			(stroke
				(width 0)
				(type default)
			)
			(fill no)
			(layer "F.CrtYd")
		)
		(fp_rect
			(start -0.508 0.9398)
			(end 0.508 -0.9398)
			(stroke
				(width 0)
				(type default)
			)
			(fill no)
			(layer "F.Fab")
		)
		(pad "1" smd custom
			(at 0 -0.4445 90)
			(size 0.1397 0.1397)
			(layers "F.Cu" "F.Mask" "F.Paste")
			(net "SCC_STBY_PGOOD_BUF")
			(options
				(clearance outline)
				(anchor circle)
			)
			(primitives
				(gr_poly
					(pts
						(arc
							(start -0.1778 -0.2794)
							(mid -0.249642 -0.249642)
							(end -0.2794 -0.1778)
						)
						(arc
							(start -0.2794 0.1778)
							(mid -0.249642 0.249642)
							(end -0.1778 0.2794)
						)
						(arc
							(start 0.1778 0.2794)
							(mid 0.249642 0.249642)
							(end 0.2794 0.1778)
						)
						(arc
							(start 0.2794 -0.1778)
							(mid 0.249642 -0.249642)
							(end 0.1778 -0.2794)
						)
					)
					(width 0)
					(fill yes)
				)
			)
		)
		(pad "2" smd custom
			(at 0 0.4445 90)
			(size 0.1397 0.1397)
			(layers "F.Cu" "F.Mask" "F.Paste")
			(net "GND")
			(options
				(clearance outline)
				(anchor circle)
			)
			(primitives
				(gr_poly
					(pts
						(arc
							(start -0.1778 -0.2794)
							(mid -0.249642 -0.249642)
							(end -0.2794 -0.1778)
						)
						(arc
							(start -0.2794 0.1778)
							(mid -0.249642 0.249642)
							(end -0.1778 0.2794)
						)
						(arc
							(start 0.1778 0.2794)
							(mid 0.249642 0.249642)
							(end 0.2794 0.1778)
						)
						(arc
							(start 0.2794 -0.1778)
							(mid 0.249642 -0.249642)
							(end 0.1778 -0.2794)
						)
					)
					(width 0)
					(fill yes)
				)
			)
		)
	)
	(footprint ""
		(layer "F.Cu")
		(at 8.750046 -48.653192 -90)
		(property "Reference" "C655"
			(at 0 0 270)
			(layer "F.SilkS")
			(hide yes)
			(effects
				(font
					(size 1.27 1.27)
				)
			)
		)
		(property "Value" "SC1KP50V2KX-1GP"
			(at 1.1811 -2.7051 270)
			(unlocked yes)
			(layer "F.Fab")
			(hide yes)
			(effects
				(font
					(size 1.016 1.016)
					(thickness 0.1524)
				)
			)
		)
		(property "Device Type" "C402H22"
			(at 1.1811 -4.2291 270)
			(unlocked yes)
			(layer "F.Fab")
			(hide yes)
			(effects
				(font
					(size 1.016 1.016)
					(thickness 0.1524)
				)
			)
		)
		(duplicate_pad_numbers_are_jumpers no)
		(fp_rect
			(start -0.4318 0.9525)
			(end 0.4318 -0.9525)
			(stroke
				(width 0)
				(type default)
			)
			(fill no)
			(layer "F.CrtYd")
		)
		(fp_rect
			(start -0.4318 0.9525)
			(end 0.4318 -0.9525)
			(stroke
				(width 0)
				(type default)
			)
			(fill no)
			(layer "F.Fab")
		)
		(pad "1" smd custom
			(at 0 -0.4445 270)
			(size 0.1524 0.1524)
			(layers "F.Cu" "F.Mask" "F.Paste")
			(net "MB0_TEMP")
			(options
				(clearance outline)
				(anchor circle)
			)
			(primitives
				(gr_poly
					(pts
						(arc
							(start 0.3048 -0.2032)
							(mid 0.275042 -0.275042)
							(end 0.2032 -0.3048)
						)
						(arc
							(start -0.2032 -0.3048)
							(mid -0.275042 -0.275042)
							(end -0.3048 -0.2032)
						)
						(arc
							(start -0.3048 0.2032)
							(mid -0.275042 0.275042)
							(end -0.2032 0.3048)
						)
						(arc
							(start 0.2032 0.3048)
							(mid 0.275042 0.275042)
							(end 0.3048 0.2032)
						)
					)
					(width 0)
					(fill yes)
				)
			)
		)
		(pad "2" smd custom
			(at 0 0.4445 270)
			(size 0.1524 0.1524)
			(layers "F.Cu" "F.Mask" "F.Paste")
			(net "GND")
			(options
				(clearance outline)
				(anchor circle)
			)
			(primitives
				(gr_poly
					(pts
						(arc
							(start 0.3048 -0.2032)
							(mid 0.275042 -0.275042)
							(end 0.2032 -0.3048)
						)
						(arc
							(start -0.2032 -0.3048)
							(mid -0.275042 -0.275042)
							(end -0.3048 -0.2032)
						)
						(arc
							(start -0.3048 0.2032)
							(mid -0.275042 0.275042)
							(end -0.2032 0.3048)
						)
						(arc
							(start 0.2032 0.3048)
							(mid 0.275042 0.275042)
							(end 0.3048 0.2032)
						)
					)
					(width 0)
					(fill yes)
				)
			)
		)
	)
	(footprint ""
		(layer "F.Cu")
		(at 92.583 -74.422 -90)
		(property "Reference" "R106"
			(at 0 0 270)
			(layer "F.SilkS")
			(hide yes)
			(effects
				(font
					(size 1.27 1.27)
				)
			)
		)
		(property "Value" "4K75R2F-1-GP"
			(at 0.064008 -3.993896 270)
			(unlocked yes)
			(layer "F.Fab")
			(hide yes)
			(effects
				(font
					(size 1.016 1.016)
					(thickness 0.1524)
				)
			)
		)
		(property "Device Type" "R402H16"
			(at 0.064008 -5.517896 270)
			(unlocked yes)
			(layer "F.Fab")
			(hide yes)
			(effects
				(font
					(size 1.016 1.016)
					(thickness 0.1524)
				)
			)
		)
		(duplicate_pad_numbers_are_jumpers no)
		(fp_line
			(start -0.508 -0.9398)
			(end -0.508 0.9398)
			(stroke
				(width 0.1524)
				(type default)
			)
			(layer "F.SilkS")
		)
		(fp_line
			(start 0.508 -0.9398)
			(end -0.508 -0.9398)
			(stroke
				(width 0.1524)
				(type default)
			)
			(layer "F.SilkS")
		)
		(fp_rect
			(start -0.508 0.9398)
			(end 0.508 -0.9398)
			(stroke
				(width 0)
				(type default)
			)
			(fill no)
			(layer "F.CrtYd")
		)
		(fp_rect
			(start -0.508 0.9398)
			(end 0.508 -0.9398)
			(stroke
				(width 0)
				(type default)
			)
			(fill no)
			(layer "F.Fab")
		)
		(pad "1" smd custom
			(at 0 -0.4445 270)
			(size 0.1397 0.1397)
			(layers "F.Cu" "F.Mask" "F.Paste")
			(net "LSI_T_N")
			(options
				(clearance outline)
				(anchor circle)
			)
			(primitives
				(gr_poly
					(pts
						(arc
							(start -0.1778 -0.2794)
							(mid -0.249642 -0.249642)
							(end -0.2794 -0.1778)
						)
						(arc
							(start -0.2794 0.1778)
							(mid -0.249642 0.249642)
							(end -0.1778 0.2794)
						)
						(arc
							(start 0.1778 0.2794)
							(mid 0.249642 0.249642)
							(end 0.2794 0.1778)
						)
						(arc
							(start 0.2794 -0.1778)
							(mid 0.249642 -0.249642)
							(end 0.1778 -0.2794)
						)
					)
					(width 0)
					(fill yes)
				)
			)
		)
		(pad "2" smd custom
			(at 0 0.4445 270)
			(size 0.1397 0.1397)
			(layers "F.Cu" "F.Mask" "F.Paste")
			(net "P1V8_E")
			(options
				(clearance outline)
				(anchor circle)
			)
			(primitives
				(gr_poly
					(pts
						(arc
							(start -0.1778 -0.2794)
							(mid -0.249642 -0.249642)
							(end -0.2794 -0.1778)
						)
						(arc
							(start -0.2794 0.1778)
							(mid -0.249642 0.249642)
							(end -0.1778 0.2794)
						)
						(arc
							(start 0.1778 0.2794)
							(mid 0.249642 0.249642)
							(end 0.2794 0.1778)
						)
						(arc
							(start 0.2794 -0.1778)
							(mid 0.249642 -0.249642)
							(end 0.1778 -0.2794)
						)
					)
					(width 0)
					(fill yes)
				)
			)
		)
	)
	(footprint ""
		(layer "F.Cu")
		(at 169.660062 -95.035878 90)
		(property "Reference" "U6"
			(at 0 0 90)
			(layer "F.SilkS")
			(hide yes)
			(effects
				(font
					(size 1.27 1.27)
				)
			)
		)
		(property "Value" "VT235WFQX-ADJ-1-GP"
			(at -5.8166 -7.7216 90)
			(unlocked yes)
			(layer "F.Fab")
			(hide yes)
			(effects
				(font
					(size 1.016 1.016)
					(thickness 0.1524)
				)
			)
		)
		(property "Device Type" "QFN19-1H40"
			(at -5.8166 -9.2456 90)
			(unlocked yes)
			(layer "F.Fab")
			(hide yes)
			(effects
				(font
					(size 1.016 1.016)
					(thickness 0.1524)
				)
			)
		)
		(duplicate_pad_numbers_are_jumpers no)
		(fp_line
			(start -1.4859 -3.0734)
			(end -2.7559 -3.0734)
			(stroke
				(width 0.1524)
				(type default)
			)
			(layer "F.SilkS")
		)
		(fp_line
			(start -2.7559 -3.0734)
			(end -2.7559 -1.8034)
			(stroke
				(width 0.1524)
				(type default)
			)
			(layer "F.SilkS")
		)
		(fp_line
			(start -1.253236 -2.821432)
			(end -1.253236 -3.329432)
			(stroke
				(width 0.1524)
				(type default)
			)
			(layer "F.SilkS")
		)
		(fp_line
			(start 2.821432 0.23876)
			(end 3.329432 0.23876)
			(stroke
				(width 0.1524)
				(type default)
			)
			(layer "F.SilkS")
		)
		(fp_line
			(start -2.7559 1.8034)
			(end -2.7559 3.0734)
			(stroke
				(width 0.1524)
				(type default)
			)
			(layer "F.SilkS")
		)
		(fp_line
			(start 0.766064 2.796032)
			(end 0.766064 3.558032)
			(stroke
				(width 0.1524)
				(type default)
			)
			(layer "F.SilkS")
		)
		(fp_line
			(start 3.0861 3.0734)
			(end 3.0861 1.8034)
			(stroke
				(width 0.1524)
				(type default)
			)
			(layer "F.SilkS")
		)
		(fp_line
			(start 1.8161 3.0734)
			(end 3.0861 3.0734)
			(stroke
				(width 0.1524)
				(type default)
			)
			(layer "F.SilkS")
		)
		(fp_line
			(start -2.7559 3.0734)
			(end -1.4859 3.0734)
			(stroke
				(width 0.1524)
				(type default)
			)
			(layer "F.SilkS")
		)
		(fp_poly
			(pts
				(xy 3.0861 -3.0734) (xy 1.8161 -3.0734) (xy 3.0861 -1.8034)
			)
			(stroke
				(width 0)
				(type default)
			)
			(fill yes)
			(layer "F.SilkS")
		)
		(fp_rect
			(start -2.2479 2.2479)
			(end 2.2479 -2.2479)
			(stroke
				(width 0)
				(type default)
			)
			(fill no)
			(layer "F.CrtYd")
		)
		(fp_poly
			(pts
				(xy -2.7559 -3.0734) (xy -2.7559 3.0734) (xy 3.0861 3.0734) (xy 3.0861 2.0193) (xy 2.2479 2.0193)
				(xy 2.2479 2.2479) (xy -2.2479 2.2479) (xy -2.2479 -2.2479) (xy 2.2479 -2.2479) (xy 2.2479 2.0066)
				(xy 3.0861 2.0066) (xy 3.0861 -3.0734)
			)
			(stroke
				(width 0)
				(type default)
			)
			(fill no)
			(layer "F.CrtYd")
		)
		(fp_rect
			(start -2.7559 3.0734)
			(end 3.0861 -3.0734)
			(stroke
				(width 0)
				(type default)
			)
			(fill no)
			(layer "F.Fab")
		)
		(pad "1" smd rect
			(at 1.249934 -2.135632 90)
			(size 0.3556 0.8382)
			(layers "F.Cu" "F.Mask" "F.Paste")
			(net "AGND_P0V975")
		)
		(pad "2" smd rect
			(at 0.750062 -2.135632 90)
			(size 0.3556 0.8382)
			(layers "F.Cu" "F.Mask" "F.Paste")
			(net "Net_126")
		)
		(pad "3" smd rect
			(at 0.249936 -2.135632 90)
			(size 0.3556 0.8382)
			(layers "F.Cu" "F.Mask" "F.Paste")
			(net "VT235_AVDD")
		)
		(pad "4" smd rect
			(at -0.249936 -0.687832 90)
			(size 0.3556 3.7338)
			(layers "F.Cu" "F.Mask" "F.Paste")
			(net "P12V_SYBY_VDD_U6")
		)
		(pad "5" smd rect
			(at -1.249934 -1.335532 90)
			(size 0.3556 2.4384)
			(layers "F.Cu" "F.Mask" "F.Paste")
			(net "GND")
		)
		(pad "6" smd rect
			(at -1.75006 1.335532 90)
			(size 0.3556 2.4384)
			(layers "F.Cu" "F.Mask" "F.Paste")
			(net "VT235_VX")
		)
		(pad "7" smd rect
			(at -0.750062 1.335532 90)
			(size 0.3556 2.4384)
			(layers "F.Cu" "F.Mask" "F.Paste")
			(net "VT235_VX")
		)
		(pad "8" smd rect
			(at -0.249936 2.135632 90)
			(size 0.3556 0.8382)
			(layers "F.Cu" "F.Mask" "F.Paste")
			(net "VT235_BST")
		)
		(pad "9" smd rect
			(at 0.249936 2.135632 90)
			(size 0.3556 0.8382)
			(layers "F.Cu" "F.Mask" "F.Paste")
			(net "VT235_VDDL")
		)
		(pad "10" smd rect
			(at 0.750062 2.135632 90)
			(size 0.3556 0.8382)
			(layers "F.Cu" "F.Mask" "F.Paste")
			(net "VT235_AVDD")
		)
		(pad "11" smd rect
			(at 1.249934 2.135632 90)
			(size 0.3556 0.8382)
			(layers "F.Cu" "F.Mask" "F.Paste")
			(net "VT235_VFB")
		)
		(pad "12" smd rect
			(at 2.135632 1.75006 90)
			(size 0.8382 0.3556)
			(layers "F.Cu" "F.Mask" "F.Paste")
			(net "VT235_PGIN")
		)
		(pad "13" smd rect
			(at 2.135632 1.249934 90)
			(size 0.8382 0.3556)
			(layers "F.Cu" "F.Mask" "F.Paste")
			(net "VT235_VDES")
		)
		(pad "14" smd rect
			(at 2.135632 0.750062 90)
			(size 0.8382 0.3556)
			(layers "F.Cu" "F.Mask" "F.Paste")
			(net "VT235_VREF")
		)
		(pad "15" smd rect
			(at 2.135632 0.249936 90)
			(size 0.8382 0.3556)
			(layers "F.Cu" "F.Mask" "F.Paste")
			(net "VT235_BIAS")
		)
		(pad "16" smd rect
			(at 2.135632 -0.249936 90)
			(size 0.8382 0.3556)
			(layers "F.Cu" "F.Mask" "F.Paste")
			(net "VT235_IMAX")
		)
		(pad "17" smd rect
			(at 2.135632 -0.750062 90)
			(size 0.8382 0.3556)
			(layers "F.Cu" "F.Mask" "F.Paste")
			(net "P0V975_STAT")
		)
		(pad "18" smd rect
			(at 2.135632 -1.249934 90)
			(size 0.8382 0.3556)
			(layers "F.Cu" "F.Mask" "F.Paste")
			(net "VT235_EN")
		)
		(pad "19" smd rect
			(at 2.135632 -1.75006 90)
			(size 0.8382 0.3556)
			(layers "F.Cu" "F.Mask" "F.Paste")
			(net "VT235_IRIP")
		)
	)
	(footprint ""
		(layer "F.Cu")
		(at 191.253872 -41.676574 -90)
		(property "Reference" "R175"
			(at 0 0 270)
			(layer "F.SilkS")
			(hide yes)
			(effects
				(font
					(size 1.27 1.27)
				)
			)
		)
		(property "Value" "10KR2F-2-GP"
			(at 0.064008 -3.993896 270)
			(unlocked yes)
			(layer "F.Fab")
			(hide yes)
			(effects
				(font
					(size 1.016 1.016)
					(thickness 0.1524)
				)
			)
		)
		(property "Device Type" "R402H16"
			(at 0.064008 -5.517896 270)
			(unlocked yes)
			(layer "F.Fab")
			(hide yes)
			(effects
				(font
					(size 1.016 1.016)
					(thickness 0.1524)
				)
			)
		)
		(duplicate_pad_numbers_are_jumpers no)
		(fp_line
			(start -0.508 -0.9398)
			(end -0.508 0.9398)
			(stroke
				(width 0.1524)
				(type default)
			)
			(layer "F.SilkS")
		)
		(fp_line
			(start 0.508 -0.9398)
			(end -0.508 -0.9398)
			(stroke
				(width 0.1524)
				(type default)
			)
			(layer "F.SilkS")
		)
		(fp_rect
			(start -0.508 0.9398)
			(end 0.508 -0.9398)
			(stroke
				(width 0)
				(type default)
			)
			(fill no)
			(layer "F.CrtYd")
		)
		(fp_rect
			(start -0.508 0.9398)
			(end 0.508 -0.9398)
			(stroke
				(width 0)
				(type default)
			)
			(fill no)
			(layer "F.Fab")
		)
		(pad "1" smd custom
			(at 0 -0.4445 270)
			(size 0.1397 0.1397)
			(layers "F.Cu" "F.Mask" "F.Paste")
			(net "GND")
			(options
				(clearance outline)
				(anchor circle)
			)
			(primitives
				(gr_poly
					(pts
						(arc
							(start -0.1778 -0.2794)
							(mid -0.249642 -0.249642)
							(end -0.2794 -0.1778)
						)
						(arc
							(start -0.2794 0.1778)
							(mid -0.249642 0.249642)
							(end -0.1778 0.2794)
						)
						(arc
							(start 0.1778 0.2794)
							(mid 0.249642 0.249642)
							(end 0.2794 0.1778)
						)
						(arc
							(start 0.2794 -0.1778)
							(mid 0.249642 -0.249642)
							(end 0.1778 -0.2794)
						)
					)
					(width 0)
					(fill yes)
				)
			)
		)
		(pad "2" smd custom
			(at 0 0.4445 270)
			(size 0.1397 0.1397)
			(layers "F.Cu" "F.Mask" "F.Paste")
			(net "IOC_CLK_SEL0")
			(options
				(clearance outline)
				(anchor circle)
			)
			(primitives
				(gr_poly
					(pts
						(arc
							(start -0.1778 -0.2794)
							(mid -0.249642 -0.249642)
							(end -0.2794 -0.1778)
						)
						(arc
							(start -0.2794 0.1778)
							(mid -0.249642 0.249642)
							(end -0.1778 0.2794)
						)
						(arc
							(start 0.1778 0.2794)
							(mid 0.249642 0.249642)
							(end 0.2794 0.1778)
						)
						(arc
							(start 0.2794 -0.1778)
							(mid 0.249642 -0.249642)
							(end 0.1778 -0.2794)
						)
					)
					(width 0)
					(fill yes)
				)
			)
		)
	)
	(footprint ""
		(layer "F.Cu")
		(at 181.03088 -59.974988)
		(property "Reference" "R219"
			(at 0 0 0)
			(layer "F.SilkS")
			(hide yes)
			(effects
				(font
					(size 1.27 1.27)
				)
			)
		)
		(property "Value" "10KR2F-2-GP"
			(at 0.064008 -3.993896 0)
			(unlocked yes)
			(layer "F.Fab")
			(hide yes)
			(effects
				(font
					(size 1.016 1.016)
					(thickness 0.1524)
				)
			)
		)
		(property "Device Type" "R402H16"
			(at 0.064008 -5.517896 0)
			(unlocked yes)
			(layer "F.Fab")
			(hide yes)
			(effects
				(font
					(size 1.016 1.016)
					(thickness 0.1524)
				)
			)
		)
		(duplicate_pad_numbers_are_jumpers no)
		(fp_line
			(start -0.508 -0.9398)
			(end -0.508 0.9398)
			(stroke
				(width 0.1524)
				(type default)
			)
			(layer "F.SilkS")
		)
		(fp_line
			(start 0.508 -0.9398)
			(end -0.508 -0.9398)
			(stroke
				(width 0.1524)
				(type default)
			)
			(layer "F.SilkS")
		)
		(fp_rect
			(start -0.508 0.9398)
			(end 0.508 -0.9398)
			(stroke
				(width 0)
				(type default)
			)
			(fill no)
			(layer "F.CrtYd")
		)
		(fp_rect
			(start -0.508 0.9398)
			(end 0.508 -0.9398)
			(stroke
				(width 0)
				(type default)
			)
			(fill no)
			(layer "F.Fab")
		)
		(pad "1" smd custom
			(at 0 -0.4445)
			(size 0.1397 0.1397)
			(layers "F.Cu" "F.Mask" "F.Paste")
			(net "P1V8_C")
			(options
				(clearance outline)
				(anchor circle)
			)
			(primitives
				(gr_poly
					(pts
						(arc
							(start -0.1778 -0.2794)
							(mid -0.249642 -0.249642)
							(end -0.2794 -0.1778)
						)
						(arc
							(start -0.2794 0.1778)
							(mid -0.249642 0.249642)
							(end -0.1778 0.2794)
						)
						(arc
							(start 0.1778 0.2794)
							(mid 0.249642 0.249642)
							(end 0.2794 0.1778)
						)
						(arc
							(start 0.2794 -0.1778)
							(mid 0.249642 -0.249642)
							(end 0.1778 -0.2794)
						)
					)
					(width 0)
					(fill yes)
				)
			)
		)
		(pad "2" smd custom
			(at 0 0.4445)
			(size 0.1397 0.1397)
			(layers "F.Cu" "F.Mask" "F.Paste")
			(net "XM_CS0_N")
			(options
				(clearance outline)
				(anchor circle)
			)
			(primitives
				(gr_poly
					(pts
						(arc
							(start -0.1778 -0.2794)
							(mid -0.249642 -0.249642)
							(end -0.2794 -0.1778)
						)
						(arc
							(start -0.2794 0.1778)
							(mid -0.249642 0.249642)
							(end -0.1778 0.2794)
						)
						(arc
							(start 0.1778 0.2794)
							(mid 0.249642 0.249642)
							(end 0.2794 0.1778)
						)
						(arc
							(start 0.2794 -0.1778)
							(mid 0.249642 -0.249642)
							(end 0.1778 -0.2794)
						)
					)
					(width 0)
					(fill yes)
				)
			)
		)
	)
	(footprint ""
		(layer "F.Cu")
		(at 133.14553 -44.702984 180)
		(property "Reference" "C41"
			(at 0 0 180)
			(layer "F.SilkS")
			(hide yes)
			(effects
				(font
					(size 1.27 1.27)
				)
			)
		)
		(property "Value" "SCD01U16V1KX-GP"
			(at -2.8321 -1.7399 180)
			(unlocked yes)
			(layer "F.Fab")
			(hide yes)
			(effects
				(font
					(size 1.016 1.016)
					(thickness 0.1524)
				)
			)
		)
		(property "Device Type" "C0201H13"
			(at -2.8321 -3.2639 180)
			(unlocked yes)
			(layer "F.Fab")
			(hide yes)
			(effects
				(font
					(size 1.016 1.016)
					(thickness 0.1524)
				)
			)
		)
		(duplicate_pad_numbers_are_jumpers no)
		(fp_rect
			(start -0.2794 0.6477)
			(end 0.2794 -0.6477)
			(stroke
				(width 0)
				(type default)
			)
			(fill no)
			(layer "F.CrtYd")
		)
		(fp_rect
			(start -0.2794 0.6477)
			(end 0.2794 -0.6477)
			(stroke
				(width 0)
				(type default)
			)
			(fill no)
			(layer "F.Fab")
		)
		(pad "1" smd custom
			(at 0 -0.2794 180)
			(size 0.0762 0.0762)
			(layers "F.Cu" "F.Mask" "F.Paste")
			(net "PHY_IOC_TO_SCC_43_DP")
			(options
				(clearance outline)
				(anchor circle)
			)
			(primitives
				(gr_poly
					(pts
						(arc
							(start 0.1524 -0.127)
							(mid 0.137521 -0.162921)
							(end 0.1016 -0.1778)
						)
						(arc
							(start -0.1016 -0.1778)
							(mid -0.137521 -0.162921)
							(end -0.1524 -0.127)
						)
						(arc
							(start -0.1524 0.127)
							(mid -0.137521 0.162921)
							(end -0.1016 0.1778)
						)
						(arc
							(start 0.1016 0.1778)
							(mid 0.137521 0.162921)
							(end 0.1524 0.127)
						)
					)
					(width 0)
					(fill yes)
				)
			)
		)
		(pad "2" smd custom
			(at 0 0.2794 180)
			(size 0.0762 0.0762)
			(layers "F.Cu" "F.Mask" "F.Paste")
			(net "PHY_IOC_TO_SCC_C_43_DP")
			(options
				(clearance outline)
				(anchor circle)
			)
			(primitives
				(gr_poly
					(pts
						(arc
							(start 0.1524 -0.127)
							(mid 0.137521 -0.162921)
							(end 0.1016 -0.1778)
						)
						(arc
							(start -0.1016 -0.1778)
							(mid -0.137521 -0.162921)
							(end -0.1524 -0.127)
						)
						(arc
							(start -0.1524 0.127)
							(mid -0.137521 0.162921)
							(end -0.1016 0.1778)
						)
						(arc
							(start 0.1016 0.1778)
							(mid 0.137521 0.162921)
							(end 0.1524 0.127)
						)
					)
					(width 0)
					(fill yes)
				)
			)
		)
	)
	(footprint ""
		(layer "F.Cu")
		(at 174.999904 -39.99992)
		(property "Reference" "U2"
			(at 0 0 0)
			(layer "F.SilkS")
			(hide yes)
			(effects
				(font
					(size 1.27 1.27)
				)
			)
		)
		(property "Value" "SAS3008C0-1-DB-500020657-1-GP"
			(at -20.374102 -5.0292 0)
			(unlocked yes)
			(layer "F.Fab")
			(hide yes)
			(effects
				(font
					(size 1.016 1.016)
					(thickness 0.1524)
				)
			)
		)
		(property "Device Type" "BGA896D25H78"
			(at -20.374102 -6.5532 0)
			(unlocked yes)
			(layer "F.Fab")
			(hide yes)
			(effects
				(font
					(size 1.016 1.016)
					(thickness 0.1524)
				)
			)
		)
		(duplicate_pad_numbers_are_jumpers no)
		(fp_line
			(start -12.500102 -12.030202)
			(end -12.500102 -10.86993)
			(stroke
				(width 0.1524)
				(type default)
			)
			(layer "F.SilkS")
		)
		(fp_line
			(start -12.500102 -9.93013)
			(end -12.500102 9.93013)
			(stroke
				(width 0.1524)
				(type default)
			)
			(layer "F.SilkS")
		)
		(fp_line
			(start -12.500102 12.030202)
			(end -12.500102 10.86993)
			(stroke
				(width 0.1524)
				(type default)
			)
			(layer "F.SilkS")
		)
		(fp_line
			(start -12.030202 -12.500102)
			(end -10.86993 -12.500102)
			(stroke
				(width 0.1524)
				(type default)
			)
			(layer "F.SilkS")
		)
		(fp_line
			(start -12.030202 12.500102)
			(end -10.86993 12.500102)
			(stroke
				(width 0.1524)
				(type default)
			)
			(layer "F.SilkS")
		)
		(fp_line
			(start 9.93013 -12.500102)
			(end -9.93013 -12.500102)
			(stroke
				(width 0.1524)
				(type default)
			)
			(layer "F.SilkS")
		)
		(fp_line
			(start 9.93013 12.500102)
			(end -9.93013 12.500102)
			(stroke
				(width 0.1524)
				(type default)
			)
			(layer "F.SilkS")
		)
		(fp_line
			(start 12.030202 -12.500102)
			(end 10.86993 -12.500102)
			(stroke
				(width 0.1524)
				(type default)
			)
			(layer "F.SilkS")
		)
		(fp_line
			(start 12.030202 12.500102)
			(end 10.86993 12.500102)
			(stroke
				(width 0.1524)
				(type default)
			)
			(layer "F.SilkS")
		)
		(fp_line
			(start 12.500102 -12.030202)
			(end 12.500102 -10.86993)
			(stroke
				(width 0.1524)
				(type default)
			)
			(layer "F.SilkS")
		)
		(fp_line
			(start 12.500102 -9.93013)
			(end 12.500102 9.93013)
			(stroke
				(width 0.1524)
				(type default)
			)
			(layer "F.SilkS")
		)
		(fp_line
			(start 12.500102 12.030202)
			(end 12.500102 10.86993)
			(stroke
				(width 0.1524)
				(type default)
			)
			(layer "F.SilkS")
		)
		(fp_circle
			(center -12.500102 -12.500102)
			(end -12.030202 -12.500102)
			(stroke
				(width 0.1524)
				(type default)
			)
			(fill no)
			(layer "F.SilkS")
		)
		(fp_circle
			(center -12.500102 -10.40003)
			(end -12.030202 -10.40003)
			(stroke
				(width 0.1524)
				(type default)
			)
			(fill no)
			(layer "F.SilkS")
		)
		(fp_circle
			(center -12.500102 10.40003)
			(end -12.030202 10.40003)
			(stroke
				(width 0.1524)
				(type default)
			)
			(fill no)
			(layer "F.SilkS")
		)
		(fp_circle
			(center -12.500102 12.500102)
			(end -12.030202 12.500102)
			(stroke
				(width 0.1524)
				(type default)
			)
			(fill no)
			(layer "F.SilkS")
		)
		(fp_circle
			(center -10.40003 -12.500102)
			(end -9.93013 -12.500102)
			(stroke
				(width 0.1524)
				(type default)
			)
			(fill no)
			(layer "F.SilkS")
		)
		(fp_circle
			(center -10.40003 12.500102)
			(end -9.93013 12.500102)
			(stroke
				(width 0.1524)
				(type default)
			)
			(fill no)
			(layer "F.SilkS")
		)
		(fp_circle
			(center 10.40003 -12.500102)
			(end 10.86993 -12.500102)
			(stroke
				(width 0.1524)
				(type default)
			)
			(fill no)
			(layer "F.SilkS")
		)
		(fp_circle
			(center 10.40003 12.500102)
			(end 10.86993 12.500102)
			(stroke
				(width 0.1524)
				(type default)
			)
			(fill no)
			(layer "F.SilkS")
		)
		(fp_circle
			(center 12.500102 -12.500102)
			(end 12.970002 -12.500102)
			(stroke
				(width 0.1524)
				(type default)
			)
			(fill no)
			(layer "F.SilkS")
		)
		(fp_circle
			(center 12.500102 -10.40003)
			(end 12.970002 -10.40003)
			(stroke
				(width 0.1524)
				(type default)
			)
			(fill no)
			(layer "F.SilkS")
		)
		(fp_circle
			(center 12.500102 10.40003)
			(end 12.970002 10.40003)
			(stroke
				(width 0.1524)
				(type default)
			)
			(fill no)
			(layer "F.SilkS")
		)
		(fp_circle
			(center 12.500102 12.500102)
			(end 12.970002 12.500102)
			(stroke
				(width 0.1524)
				(type default)
			)
			(fill no)
			(layer "F.SilkS")
		)
		(fp_poly
			(pts
				(xy -12.931902 -12.931902) (xy -12.931902 -14.455902) (xy -14.455902 -12.931902)
			)
			(stroke
				(width 0)
				(type default)
			)
			(fill yes)
			(layer "F.SilkS")
		)
		(fp_rect
			(start -12.500102 12.500102)
			(end 12.500102 -12.500102)
			(stroke
				(width 0)
				(type default)
			)
			(fill no)
			(layer "F.CrtYd")
		)
		(fp_poly
			(pts
				(xy 13.5001 -12.500102) (xy -12.500102 -12.500102) (xy -12.500102 12.500102) (xy 12.500102 12.500102)
				(xy 12.500102 -12.487402) (xy 13.5001 -12.487402) (xy 13.5001 13.5001) (xy -13.5001 13.5001) (xy -13.5001 -13.5001)
				(xy 13.5001 -13.5001)
			)
			(stroke
				(width 0)
				(type default)
			)
			(fill no)
			(layer "F.CrtYd")
		)
		(fp_rect
			(start -14.500098 14.500098)
			(end 14.500098 -14.500098)
			(stroke
				(width 0)
				(type default)
			)
			(fill no)
			(layer "F.Fab")
		)
		(pad "A2" smd circle
			(at -10.80008 -11.599926)
			(size 0.4064 0.4064)
			(layers "F.Cu" "F.Mask" "F.Paste")
			(net "Net_1158")
		)
		(pad "A3" smd circle
			(at -9.99998 -11.599926)
			(size 0.4064 0.4064)
			(layers "F.Cu" "F.Mask" "F.Paste")
			(net "Net_1159")
		)
		(pad "A4" smd circle
			(at -9.19988 -11.599926)
			(size 0.3556 0.3556)
			(layers "F.Cu" "F.Mask" "F.Paste")
			(net "GND")
		)
		(pad "A5" smd circle
			(at -8.400034 -11.599926)
			(size 0.3556 0.3556)
			(layers "F.Cu" "F.Mask" "F.Paste")
			(net "Net_1160")
		)
		(pad "A6" smd circle
			(at -7.599934 -11.599926)
			(size 0.3556 0.3556)
			(layers "F.Cu" "F.Mask" "F.Paste")
			(net "ICE1_TMS")
		)
		(pad "A7" smd circle
			(at -6.800088 -11.599926)
			(size 0.3556 0.3556)
			(layers "F.Cu" "F.Mask" "F.Paste")
			(net "Net_1161")
		)
		(pad "A8" smd circle
			(at -5.999988 -11.599926)
			(size 0.3556 0.3556)
			(layers "F.Cu" "F.Mask" "F.Paste")
			(net "ICE0_TRST#")
		)
		(pad "A9" smd circle
			(at -5.199888 -11.599926)
			(size 0.3556 0.3556)
			(layers "F.Cu" "F.Mask" "F.Paste")
			(net "ICE0_TCK")
		)
		(pad "A10" smd circle
			(at -4.400042 -11.599926)
			(size 0.3556 0.3556)
			(layers "F.Cu" "F.Mask" "F.Paste")
			(net "ICE1_TDO")
		)
		(pad "A11" smd circle
			(at -3.599942 -11.599926)
			(size 0.3556 0.3556)
			(layers "F.Cu" "F.Mask" "F.Paste")
			(net "GND")
		)
		(pad "A12" smd circle
			(at -2.800096 -11.599926)
			(size 0.3556 0.3556)
			(layers "F.Cu" "F.Mask" "F.Paste")
			(net "PG_CORE")
		)
		(pad "A13" smd circle
			(at -1.999996 -11.599926)
			(size 0.3556 0.3556)
			(layers "F.Cu" "F.Mask" "F.Paste")
			(net "SCC_FULL_PGOOD_LS")
		)
		(pad "A14" smd circle
			(at -1.199896 -11.599926)
			(size 0.3556 0.3556)
			(layers "F.Cu" "F.Mask" "F.Paste")
			(net "HM40ADC_VDDA")
		)
		(pad "A15" smd circle
			(at -0.40005 -11.599926)
			(size 0.3556 0.3556)
			(layers "F.Cu" "F.Mask" "F.Paste")
			(net "GND")
		)
		(pad "A16" smd circle
			(at 0.40005 -11.599926)
			(size 0.3556 0.3556)
			(layers "F.Cu" "F.Mask" "F.Paste")
			(net "IOC_TRST_N")
		)
		(pad "A17" smd circle
			(at 1.199896 -11.599926)
			(size 0.3556 0.3556)
			(layers "F.Cu" "F.Mask" "F.Paste")
			(net "JTAG_IOC_TDI")
		)
		(pad "A18" smd circle
			(at 1.999996 -11.599926)
			(size 0.3556 0.3556)
			(layers "F.Cu" "F.Mask" "F.Paste")
			(net "LSI_IDDT")
		)
		(pad "A19" smd circle
			(at 2.800096 -11.599926)
			(size 0.3556 0.3556)
			(layers "F.Cu" "F.Mask" "F.Paste")
			(net "Net_1152")
		)
		(pad "A20" smd circle
			(at 3.599942 -11.599926)
			(size 0.3556 0.3556)
			(layers "F.Cu" "F.Mask" "F.Paste")
			(net "Net_1153")
		)
		(pad "A21" smd circle
			(at 4.400042 -11.599926)
			(size 0.3556 0.3556)
			(layers "F.Cu" "F.Mask" "F.Paste")
			(net "XM_NOR_CS_N")
		)
		(pad "A22" smd circle
			(at 5.199888 -11.599926)
			(size 0.3556 0.3556)
			(layers "F.Cu" "F.Mask" "F.Paste")
			(net "XM_RB")
		)
		(pad "A23" smd circle
			(at 5.999988 -11.599926)
			(size 0.3556 0.3556)
			(layers "F.Cu" "F.Mask" "F.Paste")
			(net "Net_1148")
		)
		(pad "A24" smd circle
			(at 6.800088 -11.599926)
			(size 0.3556 0.3556)
			(layers "F.Cu" "F.Mask" "F.Paste")
			(net "XM_WE_N")
		)
		(pad "A25" smd circle
			(at 7.599934 -11.599926)
			(size 0.3556 0.3556)
			(layers "F.Cu" "F.Mask" "F.Paste")
			(net "XM_WP")
		)
		(pad "A26" smd circle
			(at 8.400034 -11.599926)
			(size 0.3556 0.3556)
			(layers "F.Cu" "F.Mask" "F.Paste")
			(net "XM_ADDR_3")
		)
		(pad "A27" smd circle
			(at 9.19988 -11.599926)
			(size 0.3556 0.3556)
			(layers "F.Cu" "F.Mask" "F.Paste")
			(net "Net_1149")
		)
		(pad "A28" smd circle
			(at 9.99998 -11.599926)
			(size 0.4064 0.4064)
			(layers "F.Cu" "F.Mask" "F.Paste")
			(net "XM_ADDR_4")
		)
		(pad "A29" smd circle
			(at 10.80008 -11.599926)
			(size 0.4064 0.4064)
			(layers "F.Cu" "F.Mask" "F.Paste")
			(net "XM_DATA_11")
		)
		(pad "AA1" smd circle
			(at -11.599926 4.400042)
			(size 0.3556 0.3556)
			(layers "F.Cu" "F.Mask" "F.Paste")
			(net "PHY_IOC_TO_SCC_45_DP")
		)
		(pad "AA2" smd circle
			(at -10.80008 4.400042)
			(size 0.3556 0.3556)
			(layers "F.Cu" "F.Mask" "F.Paste")
			(net "PHY_IOC_TO_SCC_45_DN")
		)
		(pad "AA3" smd circle
			(at -9.99998 4.400042)
			(size 0.3556 0.3556)
			(layers "F.Cu" "F.Mask" "F.Paste")
			(net "GND")
		)
		(pad "AA4" smd circle
			(at -9.19988 4.400042)
			(size 0.3556 0.3556)
			(layers "F.Cu" "F.Mask" "F.Paste")
			(net "PHY_SCC_TO_IOC_C_45_DP")
		)
		(pad "AA5" smd circle
			(at -8.400034 4.400042)
			(size 0.3556 0.3556)
			(layers "F.Cu" "F.Mask" "F.Paste")
			(net "PHY_SCC_TO_IOC_C_45_DN")
		)
		(pad "AA6" smd circle
			(at -7.599934 4.400042)
			(size 0.3556 0.3556)
			(layers "F.Cu" "F.Mask" "F.Paste")
			(net "GND")
		)
		(pad "AA7" smd circle
			(at -6.800088 4.400042)
			(size 0.3556 0.3556)
			(layers "F.Cu" "F.Mask" "F.Paste")
			(net "GND")
		)
		(pad "AA8" smd circle
			(at -5.999988 4.400042)
			(size 0.3556 0.3556)
			(layers "F.Cu" "F.Mask" "F.Paste")
			(net "GND")
		)
		(pad "AA9" smd circle
			(at -5.199888 4.400042)
			(size 0.3556 0.3556)
			(layers "F.Cu" "F.Mask" "F.Paste")
			(net "GND")
		)
		(pad "AA10" smd circle
			(at -4.400042 4.400042)
			(size 0.3556 0.3556)
			(layers "F.Cu" "F.Mask" "F.Paste")
			(net "GND")
		)
		(pad "AA11" smd circle
			(at -3.599942 4.400042)
			(size 0.3556 0.3556)
			(layers "F.Cu" "F.Mask" "F.Paste")
			(net "GND")
		)
		(pad "AA12" smd circle
			(at -2.800096 4.400042)
			(size 0.3556 0.3556)
			(layers "F.Cu" "F.Mask" "F.Paste")
			(net "GND")
		)
		(pad "AA13" smd circle
			(at -1.999996 4.400042)
			(size 0.3556 0.3556)
			(layers "F.Cu" "F.Mask" "F.Paste")
			(net "GND")
		)
		(pad "AA14" smd circle
			(at -1.199896 4.400042)
			(size 0.3556 0.3556)
			(layers "F.Cu" "F.Mask" "F.Paste")
			(net "GND")
		)
		(pad "AA15" smd circle
			(at -0.40005 4.400042)
			(size 0.3556 0.3556)
			(layers "F.Cu" "F.Mask" "F.Paste")
			(net "GND")
		)
		(pad "AA16" smd circle
			(at 0.40005 4.400042)
			(size 0.3556 0.3556)
			(layers "F.Cu" "F.Mask" "F.Paste")
			(net "GND")
		)
		(pad "AA17" smd circle
			(at 1.199896 4.400042)
			(size 0.3556 0.3556)
			(layers "F.Cu" "F.Mask" "F.Paste")
			(net "GND")
		)
		(pad "AA18" smd circle
			(at 1.999996 4.400042)
			(size 0.3556 0.3556)
			(layers "F.Cu" "F.Mask" "F.Paste")
			(net "GND")
		)
		(pad "AA19" smd circle
			(at 2.800096 4.400042)
			(size 0.3556 0.3556)
			(layers "F.Cu" "F.Mask" "F.Paste")
			(net "GND")
		)
		(pad "AA20" smd circle
			(at 3.599942 4.400042)
			(size 0.3556 0.3556)
			(layers "F.Cu" "F.Mask" "F.Paste")
			(net "GND")
		)
		(pad "AA21" smd circle
			(at 4.400042 4.400042)
			(size 0.3556 0.3556)
			(layers "F.Cu" "F.Mask" "F.Paste")
			(net "GND")
		)
		(pad "AA22" smd circle
			(at 5.199888 4.400042)
			(size 0.3556 0.3556)
			(layers "F.Cu" "F.Mask" "F.Paste")
			(net "GND")
		)
		(pad "AA23" smd circle
			(at 5.999988 4.400042)
			(size 0.3556 0.3556)
			(layers "F.Cu" "F.Mask" "F.Paste")
			(net "PLL_VDD")
		)
		(pad "AA24" smd circle
			(at 6.800088 4.400042)
			(size 0.3556 0.3556)
			(layers "F.Cu" "F.Mask" "F.Paste")
			(net "GND")
		)
		(pad "AA25" smd circle
			(at 7.599934 4.400042)
			(size 0.3556 0.3556)
			(layers "F.Cu" "F.Mask" "F.Paste")
			(net "GND")
		)
		(pad "AA26" smd circle
			(at 8.400034 4.400042)
			(size 0.3556 0.3556)
			(layers "F.Cu" "F.Mask" "F.Paste")
			(net "GND")
		)
		(pad "AA27" smd circle
			(at 9.19988 4.400042)
			(size 0.3556 0.3556)
			(layers "F.Cu" "F.Mask" "F.Paste")
			(net "P1V8_C")
		)
		(pad "AA28" smd circle
			(at 9.99998 4.400042)
			(size 0.3556 0.3556)
			(layers "F.Cu" "F.Mask" "F.Paste")
			(net "IOC_GPIO_36")
		)
		(pad "AA29" smd circle
			(at 10.80008 4.400042)
			(size 0.3556 0.3556)
			(layers "F.Cu" "F.Mask" "F.Paste")
			(net "IOC_GPIO_33")
		)
		(pad "AA30" smd circle
			(at 11.599926 4.400042)
			(size 0.3556 0.3556)
			(layers "F.Cu" "F.Mask" "F.Paste")
			(net "IOC_GPIO_37")
		)
		(pad "AB1" smd circle
			(at -11.599926 5.199888)
			(size 0.3556 0.3556)
			(layers "F.Cu" "F.Mask" "F.Paste")
			(net "PHY_IOC_TO_SCC_44_DP")
		)
		(pad "AB2" smd circle
			(at -10.80008 5.199888)
			(size 0.3556 0.3556)
			(layers "F.Cu" "F.Mask" "F.Paste")
			(net "PHY_IOC_TO_SCC_44_DN")
		)
		(pad "AB3" smd circle
			(at -9.99998 5.199888)
			(size 0.3556 0.3556)
			(layers "F.Cu" "F.Mask" "F.Paste")
			(net "GND")
		)
		(pad "AB4" smd circle
			(at -9.19988 5.199888)
			(size 0.3556 0.3556)
			(layers "F.Cu" "F.Mask" "F.Paste")
			(net "PHY_SCC_TO_IOC_C_44_DP")
		)
		(pad "AB5" smd circle
			(at -8.400034 5.199888)
			(size 0.3556 0.3556)
			(layers "F.Cu" "F.Mask" "F.Paste")
			(net "PHY_SCC_TO_IOC_C_44_DN")
		)
		(pad "AB6" smd circle
			(at -7.599934 5.199888)
			(size 0.3556 0.3556)
			(layers "F.Cu" "F.Mask" "F.Paste")
			(net "GND")
		)
		(pad "AB7" smd circle
			(at -6.800088 5.199888)
			(size 0.3556 0.3556)
			(layers "F.Cu" "F.Mask" "F.Paste")
			(net "SAS0_AVDD")
		)
		(pad "AB8" smd circle
			(at -5.999988 5.199888)
			(size 0.3556 0.3556)
			(layers "F.Cu" "F.Mask" "F.Paste")
			(net "GND")
		)
		(pad "AB9" smd circle
			(at -5.199888 5.199888)
			(size 0.3556 0.3556)
			(layers "F.Cu" "F.Mask" "F.Paste")
			(net "GND")
		)
		(pad "AB10" smd circle
			(at -4.400042 5.199888)
			(size 0.3556 0.3556)
			(layers "F.Cu" "F.Mask" "F.Paste")
			(net "GND")
		)
		(pad "AB11" smd circle
			(at -3.599942 5.199888)
			(size 0.3556 0.3556)
			(layers "F.Cu" "F.Mask" "F.Paste")
			(net "GND")
		)
		(pad "AB12" smd circle
			(at -2.800096 5.199888)
			(size 0.3556 0.3556)
			(layers "F.Cu" "F.Mask" "F.Paste")
			(net "GND")
		)
		(pad "AB13" smd circle
			(at -1.999996 5.199888)
			(size 0.3556 0.3556)
			(layers "F.Cu" "F.Mask" "F.Paste")
			(net "GND")
		)
		(pad "AB14" smd circle
			(at -1.199896 5.199888)
			(size 0.3556 0.3556)
			(layers "F.Cu" "F.Mask" "F.Paste")
			(net "GND")
		)
		(pad "AB15" smd circle
			(at -0.40005 5.199888)
			(size 0.3556 0.3556)
			(layers "F.Cu" "F.Mask" "F.Paste")
			(net "GND")
		)
		(pad "AB16" smd circle
			(at 0.40005 5.199888)
			(size 0.3556 0.3556)
			(layers "F.Cu" "F.Mask" "F.Paste")
			(net "GND")
		)
		(pad "AB17" smd circle
			(at 1.199896 5.199888)
			(size 0.3556 0.3556)
			(layers "F.Cu" "F.Mask" "F.Paste")
			(net "GND")
		)
		(pad "AB18" smd circle
			(at 1.999996 5.199888)
			(size 0.3556 0.3556)
			(layers "F.Cu" "F.Mask" "F.Paste")
			(net "GND")
		)
		(pad "AB19" smd circle
			(at 2.800096 5.199888)
			(size 0.3556 0.3556)
			(layers "F.Cu" "F.Mask" "F.Paste")
			(net "GND")
		)
		(pad "AB20" smd circle
			(at 3.599942 5.199888)
			(size 0.3556 0.3556)
			(layers "F.Cu" "F.Mask" "F.Paste")
			(net "GND")
		)
		(pad "AB21" smd circle
			(at 4.400042 5.199888)
			(size 0.3556 0.3556)
			(layers "F.Cu" "F.Mask" "F.Paste")
			(net "GND")
		)
		(pad "AB22" smd circle
			(at 5.199888 5.199888)
			(size 0.3556 0.3556)
			(layers "F.Cu" "F.Mask" "F.Paste")
			(net "GND")
		)
		(pad "AB23" smd circle
			(at 5.999988 5.199888)
			(size 0.3556 0.3556)
			(layers "F.Cu" "F.Mask" "F.Paste")
			(net "GND")
		)
		(pad "AB24" smd circle
			(at 6.800088 5.199888)
			(size 0.3556 0.3556)
			(layers "F.Cu" "F.Mask" "F.Paste")
			(net "GND")
		)
		(pad "AB25" smd circle
			(at 7.599934 5.199888)
			(size 0.3556 0.3556)
			(layers "F.Cu" "F.Mask" "F.Paste")
			(net "GND")
		)
		(pad "AB26" smd circle
			(at 8.400034 5.199888)
			(size 0.3556 0.3556)
			(layers "F.Cu" "F.Mask" "F.Paste")
			(net "P1V8_C")
		)
		(pad "AB27" smd circle
			(at 9.19988 5.199888)
			(size 0.3556 0.3556)
			(layers "F.Cu" "F.Mask" "F.Paste")
			(net "GND")
		)
		(pad "AB28" smd circle
			(at 9.99998 5.199888)
			(size 0.3556 0.3556)
			(layers "F.Cu" "F.Mask" "F.Paste")
			(net "IOC_GPIO_34")
		)
		(pad "AB29" smd circle
			(at 10.80008 5.199888)
			(size 0.3556 0.3556)
			(layers "F.Cu" "F.Mask" "F.Paste")
			(net "IOC_GPIO_23")
		)
		(pad "AB30" smd circle
			(at 11.599926 5.199888)
			(size 0.3556 0.3556)
			(layers "F.Cu" "F.Mask" "F.Paste")
			(net "IOC_GPIO_35")
		)
		(pad "AC1" smd circle
			(at -11.599926 5.999988)
			(size 0.3556 0.3556)
			(layers "F.Cu" "F.Mask" "F.Paste")
			(net "SAS0_VDDH")
		)
		(pad "AC2" smd circle
			(at -10.80008 5.999988)
			(size 0.3556 0.3556)
			(layers "F.Cu" "F.Mask" "F.Paste")
			(net "GND")
		)
		(pad "AC3" smd circle
			(at -9.99998 5.999988)
			(size 0.3556 0.3556)
			(layers "F.Cu" "F.Mask" "F.Paste")
			(net "GND")
		)
		(pad "AC4" smd circle
			(at -9.19988 5.999988)
			(size 0.3556 0.3556)
			(layers "F.Cu" "F.Mask" "F.Paste")
			(net "SAS0_AVDD")
		)
		(pad "AC5" smd circle
			(at -8.400034 5.999988)
			(size 0.3556 0.3556)
			(layers "F.Cu" "F.Mask" "F.Paste")
			(net "GND")
		)
		(pad "AC6" smd circle
			(at -7.599934 5.999988)
			(size 0.3556 0.3556)
			(layers "F.Cu" "F.Mask" "F.Paste")
			(net "SAS0_VDDH")
		)
		(pad "AC7" smd circle
			(at -6.800088 5.999988)
			(size 0.3556 0.3556)
			(layers "F.Cu" "F.Mask" "F.Paste")
			(net "GND")
		)
		(pad "AC8" smd circle
			(at -5.999988 5.999988)
			(size 0.3556 0.3556)
			(layers "F.Cu" "F.Mask" "F.Paste")
			(net "GND")
		)
		(pad "AC9" smd circle
			(at -5.199888 5.999988)
			(size 0.3556 0.3556)
			(layers "F.Cu" "F.Mask" "F.Paste")
			(net "GND")
		)
		(pad "AC10" smd circle
			(at -4.400042 5.999988)
			(size 0.3556 0.3556)
			(layers "F.Cu" "F.Mask" "F.Paste")
			(net "GND")
		)
		(pad "AC11" smd circle
			(at -3.599942 5.999988)
			(size 0.3556 0.3556)
			(layers "F.Cu" "F.Mask" "F.Paste")
			(net "PCE_AVDD")
		)
		(pad "AC12" smd circle
			(at -2.800096 5.999988)
			(size 0.3556 0.3556)
			(layers "F.Cu" "F.Mask" "F.Paste")
			(net "GND")
		)
		(pad "AC13" smd circle
			(at -1.999996 5.999988)
			(size 0.3556 0.3556)
			(layers "F.Cu" "F.Mask" "F.Paste")
			(net "GND")
		)
		(pad "AC14" smd circle
			(at -1.199896 5.999988)
			(size 0.3556 0.3556)
			(layers "F.Cu" "F.Mask" "F.Paste")
			(net "GND")
		)
		(pad "AC15" smd circle
			(at -0.40005 5.999988)
			(size 0.3556 0.3556)
			(layers "F.Cu" "F.Mask" "F.Paste")
			(net "GND")
		)
		(pad "AC16" smd circle
			(at 0.40005 5.999988)
			(size 0.3556 0.3556)
			(layers "F.Cu" "F.Mask" "F.Paste")
			(net "GND")
		)
		(pad "AC17" smd circle
			(at 1.199896 5.999988)
			(size 0.3556 0.3556)
			(layers "F.Cu" "F.Mask" "F.Paste")
			(net "GND")
		)
		(pad "AC18" smd circle
			(at 1.999996 5.999988)
			(size 0.3556 0.3556)
			(layers "F.Cu" "F.Mask" "F.Paste")
			(net "GND")
		)
		(pad "AC19" smd circle
			(at 2.800096 5.999988)
			(size 0.3556 0.3556)
			(layers "F.Cu" "F.Mask" "F.Paste")
			(net "GND")
		)
		(pad "AC20" smd circle
			(at 3.599942 5.999988)
			(size 0.3556 0.3556)
			(layers "F.Cu" "F.Mask" "F.Paste")
			(net "GND")
		)
		(pad "AC21" smd circle
			(at 4.400042 5.999988)
			(size 0.3556 0.3556)
			(layers "F.Cu" "F.Mask" "F.Paste")
			(net "GND")
		)
		(pad "AC22" smd circle
			(at 5.199888 5.999988)
			(size 0.3556 0.3556)
			(layers "F.Cu" "F.Mask" "F.Paste")
			(net "GND")
		)
		(pad "AC23" smd circle
			(at 5.999988 5.999988)
			(size 0.3556 0.3556)
			(layers "F.Cu" "F.Mask" "F.Paste")
			(net "GND")
		)
		(pad "AC24" smd circle
			(at 6.800088 5.999988)
			(size 0.3556 0.3556)
			(layers "F.Cu" "F.Mask" "F.Paste")
			(net "GND")
		)
		(pad "AC25" smd circle
			(at 7.599934 5.999988)
			(size 0.3556 0.3556)
			(layers "F.Cu" "F.Mask" "F.Paste")
			(net "GND")
		)
		(pad "AC26" smd circle
			(at 8.400034 5.999988)
			(size 0.3556 0.3556)
			(layers "F.Cu" "F.Mask" "F.Paste")
			(net "GND")
		)
		(pad "AC27" smd circle
			(at 9.19988 5.999988)
			(size 0.3556 0.3556)
			(layers "F.Cu" "F.Mask" "F.Paste")
			(net "P1V8_C")
		)
		(pad "AC28" smd circle
			(at 9.99998 5.999988)
			(size 0.3556 0.3556)
			(layers "F.Cu" "F.Mask" "F.Paste")
			(net "IOC_GPIO_28")
		)
		(pad "AC29" smd circle
			(at 10.80008 5.999988)
			(size 0.3556 0.3556)
			(layers "F.Cu" "F.Mask" "F.Paste")
			(net "IOC_GPIO_30")
		)
		(pad "AC30" smd circle
			(at 11.599926 5.999988)
			(size 0.3556 0.3556)
			(layers "F.Cu" "F.Mask" "F.Paste")
			(net "IOC_GPIO_8")
		)
		(pad "AD1" smd circle
			(at -11.599926 6.800088)
			(size 0.3556 0.3556)
			(layers "F.Cu" "F.Mask" "F.Paste")
			(net "PHY_IOC_TO_SCC_43_DP")
		)
		(pad "AD2" smd circle
			(at -10.80008 6.800088)
			(size 0.3556 0.3556)
			(layers "F.Cu" "F.Mask" "F.Paste")
			(net "PHY_IOC_TO_SCC_43_DN")
		)
		(pad "AD3" smd circle
			(at -9.99998 6.800088)
			(size 0.3556 0.3556)
			(layers "F.Cu" "F.Mask" "F.Paste")
			(net "GND")
		)
		(pad "AD4" smd circle
			(at -9.19988 6.800088)
			(size 0.3556 0.3556)
			(layers "F.Cu" "F.Mask" "F.Paste")
			(net "PHY_SCC_TO_IOC_C_43_DP")
		)
		(pad "AD5" smd circle
			(at -8.400034 6.800088)
			(size 0.3556 0.3556)
			(layers "F.Cu" "F.Mask" "F.Paste")
			(net "PHY_SCC_TO_IOC_C_43_DN")
		)
		(pad "AD6" smd circle
			(at -7.599934 6.800088)
			(size 0.3556 0.3556)
			(layers "F.Cu" "F.Mask" "F.Paste")
			(net "GND")
		)
		(pad "AD7" smd circle
			(at -6.800088 6.800088)
			(size 0.3556 0.3556)
			(layers "F.Cu" "F.Mask" "F.Paste")
			(net "SAS0_AVDD")
		)
		(pad "AD8" smd circle
			(at -5.999988 6.800088)
			(size 0.3556 0.3556)
			(layers "F.Cu" "F.Mask" "F.Paste")
			(net "GND")
		)
		(pad "AD9" smd circle
			(at -5.199888 6.800088)
			(size 0.3556 0.3556)
			(layers "F.Cu" "F.Mask" "F.Paste")
			(net "PCE_AVDD")
		)
		(pad "AD10" smd circle
			(at -4.400042 6.800088)
			(size 0.3556 0.3556)
			(layers "F.Cu" "F.Mask" "F.Paste")
			(net "GND")
		)
		(pad "AD11" smd circle
			(at -3.599942 6.800088)
			(size 0.3556 0.3556)
			(layers "F.Cu" "F.Mask" "F.Paste")
			(net "PCE_AVDD")
		)
		(pad "AD12" smd circle
			(at -2.800096 6.800088)
			(size 0.3556 0.3556)
			(layers "F.Cu" "F.Mask" "F.Paste")
			(net "GND")
		)
		(pad "AD13" smd circle
			(at -1.999996 6.800088)
			(size 0.3556 0.3556)
			(layers "F.Cu" "F.Mask" "F.Paste")
			(net "PCE_AVDD")
		)
		(pad "AD14" smd circle
			(at -1.199896 6.800088)
			(size 0.3556 0.3556)
			(layers "F.Cu" "F.Mask" "F.Paste")
			(net "GND")
		)
		(pad "AD15" smd circle
			(at -0.40005 6.800088)
			(size 0.3556 0.3556)
			(layers "F.Cu" "F.Mask" "F.Paste")
			(net "PCE_AVDD")
		)
		(pad "AD16" smd circle
			(at 0.40005 6.800088)
			(size 0.3556 0.3556)
			(layers "F.Cu" "F.Mask" "F.Paste")
			(net "GND")
		)
		(pad "AD17" smd circle
			(at 1.199896 6.800088)
			(size 0.3556 0.3556)
			(layers "F.Cu" "F.Mask" "F.Paste")
			(net "GND")
		)
		(pad "AD18" smd circle
			(at 1.999996 6.800088)
			(size 0.3556 0.3556)
			(layers "F.Cu" "F.Mask" "F.Paste")
			(net "GND")
		)
		(pad "AD19" smd circle
			(at 2.800096 6.800088)
			(size 0.3556 0.3556)
			(layers "F.Cu" "F.Mask" "F.Paste")
			(net "GND")
		)
		(pad "AD20" smd circle
			(at 3.599942 6.800088)
			(size 0.3556 0.3556)
			(layers "F.Cu" "F.Mask" "F.Paste")
			(net "GND")
		)
		(pad "AD21" smd circle
			(at 4.400042 6.800088)
			(size 0.3556 0.3556)
			(layers "F.Cu" "F.Mask" "F.Paste")
			(net "GND")
		)
		(pad "AD22" smd circle
			(at 5.199888 6.800088)
			(size 0.3556 0.3556)
			(layers "F.Cu" "F.Mask" "F.Paste")
			(net "GND")
		)
		(pad "AD23" smd circle
			(at 5.999988 6.800088)
			(size 0.3556 0.3556)
			(layers "F.Cu" "F.Mask" "F.Paste")
			(net "GND")
		)
		(pad "AD24" smd circle
			(at 6.800088 6.800088)
			(size 0.3556 0.3556)
			(layers "F.Cu" "F.Mask" "F.Paste")
			(net "GND")
		)
		(pad "AD25" smd circle
			(at 7.599934 6.800088)
			(size 0.3556 0.3556)
			(layers "F.Cu" "F.Mask" "F.Paste")
			(net "GND")
		)
		(pad "AD26" smd circle
			(at 8.400034 6.800088)
			(size 0.3556 0.3556)
			(layers "F.Cu" "F.Mask" "F.Paste")
			(net "P1V8_C")
		)
		(pad "AD27" smd circle
			(at 9.19988 6.800088)
			(size 0.3556 0.3556)
			(layers "F.Cu" "F.Mask" "F.Paste")
			(net "GND")
		)
		(pad "AD28" smd circle
			(at 9.99998 6.800088)
			(size 0.3556 0.3556)
			(layers "F.Cu" "F.Mask" "F.Paste")
			(net "IOC_GPIO_29")
		)
		(pad "AD29" smd circle
			(at 10.80008 6.800088)
			(size 0.3556 0.3556)
			(layers "F.Cu" "F.Mask" "F.Paste")
			(net "IOC_GPIO_27")
		)
		(pad "AD30" smd circle
			(at 11.599926 6.800088)
			(size 0.3556 0.3556)
			(layers "F.Cu" "F.Mask" "F.Paste")
			(net "IOC_GPIO_17")
		)
		(pad "AE1" smd circle
			(at -11.599926 7.599934)
			(size 0.3556 0.3556)
			(layers "F.Cu" "F.Mask" "F.Paste")
			(net "PHY_IOC_TO_SCC_42_DP")
		)
		(pad "AE2" smd circle
			(at -10.80008 7.599934)
			(size 0.3556 0.3556)
			(layers "F.Cu" "F.Mask" "F.Paste")
			(net "PHY_IOC_TO_SCC_42_DN")
		)
		(pad "AE3" smd circle
			(at -9.99998 7.599934)
			(size 0.3556 0.3556)
			(layers "F.Cu" "F.Mask" "F.Paste")
			(net "GND")
		)
		(pad "AE4" smd circle
			(at -9.19988 7.599934)
			(size 0.3556 0.3556)
			(layers "F.Cu" "F.Mask" "F.Paste")
			(net "PHY_SCC_TO_IOC_C_42_DP")
		)
		(pad "AE5" smd circle
			(at -8.400034 7.599934)
			(size 0.3556 0.3556)
			(layers "F.Cu" "F.Mask" "F.Paste")
			(net "PHY_SCC_TO_IOC_C_42_DN")
		)
		(pad "AE6" smd circle
			(at -7.599934 7.599934)
			(size 0.3556 0.3556)
			(layers "F.Cu" "F.Mask" "F.Paste")
			(net "GND")
		)
		(pad "AE7" smd circle
			(at -6.800088 7.599934)
			(size 0.3556 0.3556)
			(layers "F.Cu" "F.Mask" "F.Paste")
			(net "GND")
		)
		(pad "AE8" smd circle
			(at -5.999988 7.599934)
			(size 0.3556 0.3556)
			(layers "F.Cu" "F.Mask" "F.Paste")
			(net "PCE_VDDH")
		)
		(pad "AE9" smd circle
			(at -5.199888 7.599934)
			(size 0.3556 0.3556)
			(layers "F.Cu" "F.Mask" "F.Paste")
			(net "GND")
		)
		(pad "AE10" smd circle
			(at -4.400042 7.599934)
			(size 0.3556 0.3556)
			(layers "F.Cu" "F.Mask" "F.Paste")
			(net "PCE_VDDH")
		)
		(pad "AE11" smd circle
			(at -3.599942 7.599934)
			(size 0.3556 0.3556)
			(layers "F.Cu" "F.Mask" "F.Paste")
			(net "GND")
		)
		(pad "AE12" smd circle
			(at -2.800096 7.599934)
			(size 0.3556 0.3556)
			(layers "F.Cu" "F.Mask" "F.Paste")
			(net "PCE_VDDH")
		)
		(pad "AE13" smd circle
			(at -1.999996 7.599934)
			(size 0.3556 0.3556)
			(layers "F.Cu" "F.Mask" "F.Paste")
			(net "GND")
		)
		(pad "AE14" smd circle
			(at -1.199896 7.599934)
			(size 0.3556 0.3556)
			(layers "F.Cu" "F.Mask" "F.Paste")
			(net "PCE_VDDH")
		)
		(pad "AE15" smd circle
			(at -0.40005 7.599934)
			(size 0.3556 0.3556)
			(layers "F.Cu" "F.Mask" "F.Paste")
			(net "GND")
		)
		(pad "AE16" smd circle
			(at 0.40005 7.599934)
			(size 0.3556 0.3556)
			(layers "F.Cu" "F.Mask" "F.Paste")
			(net "PCE_VDDH")
		)
		(pad "AE17" smd circle
			(at 1.199896 7.599934)
			(size 0.3556 0.3556)
			(layers "F.Cu" "F.Mask" "F.Paste")
			(net "GND")
		)
		(pad "AE18" smd circle
			(at 1.999996 7.599934)
			(size 0.3556 0.3556)
			(layers "F.Cu" "F.Mask" "F.Paste")
			(net "GND")
		)
		(pad "AE19" smd circle
			(at 2.800096 7.599934)
			(size 0.3556 0.3556)
			(layers "F.Cu" "F.Mask" "F.Paste")
			(net "SPARE5")
		)
		(pad "AE20" smd circle
			(at 3.599942 7.599934)
			(size 0.3556 0.3556)
			(layers "F.Cu" "F.Mask" "F.Paste")
			(net "SPARE3")
		)
		(pad "AE21" smd circle
			(at 4.400042 7.599934)
			(size 0.3556 0.3556)
			(layers "F.Cu" "F.Mask" "F.Paste")
			(net "IOC_GPIO_7")
		)
		(pad "AE22" smd circle
			(at 5.199888 7.599934)
			(size 0.3556 0.3556)
			(layers "F.Cu" "F.Mask" "F.Paste")
			(net "SYS_DBMODE0")
		)
		(pad "AE23" smd circle
			(at 5.999988 7.599934)
			(size 0.3556 0.3556)
			(layers "F.Cu" "F.Mask" "F.Paste")
			(net "SYS_RST_N_1")
		)
		(pad "AE24" smd circle
			(at 6.800088 7.599934)
			(size 0.3556 0.3556)
			(layers "F.Cu" "F.Mask" "F.Paste")
			(net "GND")
		)
		(pad "AE25" smd circle
			(at 7.599934 7.599934)
			(size 0.3556 0.3556)
			(layers "F.Cu" "F.Mask" "F.Paste")
			(net "GND")
		)
		(pad "AE26" smd circle
			(at 8.400034 7.599934)
			(size 0.3556 0.3556)
			(layers "F.Cu" "F.Mask" "F.Paste")
			(net "GND")
		)
		(pad "AE27" smd circle
			(at 9.19988 7.599934)
			(size 0.3556 0.3556)
			(layers "F.Cu" "F.Mask" "F.Paste")
			(net "P1V8_C")
		)
		(pad "AE28" smd circle
			(at 9.99998 7.599934)
			(size 0.3556 0.3556)
			(layers "F.Cu" "F.Mask" "F.Paste")
			(net "UART_SERCLK")
		)
		(pad "AE29" smd circle
			(at 10.80008 7.599934)
			(size 0.3556 0.3556)
			(layers "F.Cu" "F.Mask" "F.Paste")
			(net "IOC_GPIO_39")
		)
		(pad "AE30" smd circle
			(at 11.599926 7.599934)
			(size 0.3556 0.3556)
			(layers "F.Cu" "F.Mask" "F.Paste")
			(net "IOC_GPIO_31")
		)
		(pad "AF1" smd circle
			(at -11.599926 8.400034)
			(size 0.3556 0.3556)
			(layers "F.Cu" "F.Mask" "F.Paste")
			(net "SAS0_VDDH")
		)
		(pad "AF2" smd circle
			(at -10.80008 8.400034)
			(size 0.3556 0.3556)
			(layers "F.Cu" "F.Mask" "F.Paste")
			(net "GND")
		)
		(pad "AF3" smd circle
			(at -9.99998 8.400034)
			(size 0.3556 0.3556)
			(layers "F.Cu" "F.Mask" "F.Paste")
			(net "GND")
		)
		(pad "AF4" smd circle
			(at -9.19988 8.400034)
			(size 0.3556 0.3556)
			(layers "F.Cu" "F.Mask" "F.Paste")
			(net "SAS0_AVDD")
		)
		(pad "AF5" smd circle
			(at -8.400034 8.400034)
			(size 0.3556 0.3556)
			(layers "F.Cu" "F.Mask" "F.Paste")
			(net "GND")
		)
		(pad "AF6" smd circle
			(at -7.599934 8.400034)
			(size 0.3556 0.3556)
			(layers "F.Cu" "F.Mask" "F.Paste")
			(net "GND")
		)
		(pad "AF7" smd circle
			(at -6.800088 8.400034)
			(size 0.3556 0.3556)
			(layers "F.Cu" "F.Mask" "F.Paste")
			(net "PCIE_SCC_TO_COMP_C_0_DN")
		)
		(pad "AF8" smd circle
			(at -5.999988 8.400034)
			(size 0.3556 0.3556)
			(layers "F.Cu" "F.Mask" "F.Paste")
			(net "PCIE_SCC_TO_COMP_C_1_DN")
		)
		(pad "AF9" smd circle
			(at -5.199888 8.400034)
			(size 0.3556 0.3556)
			(layers "F.Cu" "F.Mask" "F.Paste")
			(net "GND")
		)
		(pad "AF10" smd circle
			(at -4.400042 8.400034)
			(size 0.3556 0.3556)
			(layers "F.Cu" "F.Mask" "F.Paste")
			(net "PCIE_SCC_TO_COMP_C_2_DN")
		)
		(pad "AF11" smd circle
			(at -3.599942 8.400034)
			(size 0.3556 0.3556)
			(layers "F.Cu" "F.Mask" "F.Paste")
			(net "PCIE_SCC_TO_COMP_C_3_DN")
		)
		(pad "AF12" smd circle
			(at -2.800096 8.400034)
			(size 0.3556 0.3556)
			(layers "F.Cu" "F.Mask" "F.Paste")
			(net "GND")
		)
		(pad "AF13" smd circle
			(at -1.999996 8.400034)
			(size 0.3556 0.3556)
			(layers "F.Cu" "F.Mask" "F.Paste")
			(net "PCIE_SCC_TO_COMP_C_4_DN")
		)
		(pad "AF14" smd circle
			(at -1.199896 8.400034)
			(size 0.3556 0.3556)
			(layers "F.Cu" "F.Mask" "F.Paste")
			(net "PCIE_SCC_TO_COMP_C_5_DN")
		)
		(pad "AF15" smd circle
			(at -0.40005 8.400034)
			(size 0.3556 0.3556)
			(layers "F.Cu" "F.Mask" "F.Paste")
			(net "GND")
		)
		(pad "AF16" smd circle
			(at 0.40005 8.400034)
			(size 0.3556 0.3556)
			(layers "F.Cu" "F.Mask" "F.Paste")
			(net "PCIE_SCC_TO_COMP_C_6_DN")
		)
		(pad "AF17" smd circle
			(at 1.199896 8.400034)
			(size 0.3556 0.3556)
			(layers "F.Cu" "F.Mask" "F.Paste")
			(net "PCIE_SCC_TO_COMP_C_7_DN")
		)
		(pad "AF18" smd circle
			(at 1.999996 8.400034)
			(size 0.3556 0.3556)
			(layers "F.Cu" "F.Mask" "F.Paste")
			(net "GND")
		)
		(pad "AF19" smd circle
			(at 2.800096 8.400034)
			(size 0.3556 0.3556)
			(layers "F.Cu" "F.Mask" "F.Paste")
			(net "GND")
		)
		(pad "AF20" smd circle
			(at 3.599942 8.400034)
			(size 0.3556 0.3556)
			(layers "F.Cu" "F.Mask" "F.Paste")
			(net "P1V8_C")
		)
		(pad "AF21" smd circle
			(at 4.400042 8.400034)
			(size 0.3556 0.3556)
			(layers "F.Cu" "F.Mask" "F.Paste")
			(net "GND")
		)
		(pad "AF22" smd circle
			(at 5.199888 8.400034)
			(size 0.3556 0.3556)
			(layers "F.Cu" "F.Mask" "F.Paste")
			(net "P1V8_C")
		)
		(pad "AF23" smd circle
			(at 5.999988 8.400034)
			(size 0.3556 0.3556)
			(layers "F.Cu" "F.Mask" "F.Paste")
			(net "GND")
		)
		(pad "AF24" smd circle
			(at 6.800088 8.400034)
			(size 0.3556 0.3556)
			(layers "F.Cu" "F.Mask" "F.Paste")
			(net "P1V8_C")
		)
		(pad "AF25" smd circle
			(at 7.599934 8.400034)
			(size 0.3556 0.3556)
			(layers "F.Cu" "F.Mask" "F.Paste")
			(net "GND")
		)
		(pad "AF26" smd circle
			(at 8.400034 8.400034)
			(size 0.3556 0.3556)
			(layers "F.Cu" "F.Mask" "F.Paste")
			(net "P1V8_C")
		)
		(pad "AF27" smd circle
			(at 9.19988 8.400034)
			(size 0.3556 0.3556)
			(layers "F.Cu" "F.Mask" "F.Paste")
			(net "GND")
		)
		(pad "AF28" smd circle
			(at 9.99998 8.400034)
			(size 0.3556 0.3556)
			(layers "F.Cu" "F.Mask" "F.Paste")
			(net "IOC_GPIO_26")
		)
		(pad "AF29" smd circle
			(at 10.80008 8.400034)
			(size 0.3556 0.3556)
			(layers "F.Cu" "F.Mask" "F.Paste")
			(net "IOC_GPIO_0")
		)
		(pad "AF30" smd circle
			(at 11.599926 8.400034)
			(size 0.3556 0.3556)
			(layers "F.Cu" "F.Mask" "F.Paste")
			(net "IOC_GPIO_16")
		)
		(pad "AG1" smd circle
			(at -11.599926 9.19988)
			(size 0.3556 0.3556)
			(layers "F.Cu" "F.Mask" "F.Paste")
			(net "PHY_IOC_TO_SCC_41_DP")
		)
		(pad "AG2" smd circle
			(at -10.80008 9.19988)
			(size 0.3556 0.3556)
			(layers "F.Cu" "F.Mask" "F.Paste")
			(net "PHY_IOC_TO_SCC_41_DN")
		)
		(pad "AG3" smd circle
			(at -9.99998 9.19988)
			(size 0.3556 0.3556)
			(layers "F.Cu" "F.Mask" "F.Paste")
			(net "GND")
		)
		(pad "AG4" smd circle
			(at -9.19988 9.19988)
			(size 0.3556 0.3556)
			(layers "F.Cu" "F.Mask" "F.Paste")
			(net "PHY_SCC_TO_IOC_C_41_DP")
		)
		(pad "AG5" smd circle
			(at -8.400034 9.19988)
			(size 0.3556 0.3556)
			(layers "F.Cu" "F.Mask" "F.Paste")
			(net "PHY_SCC_TO_IOC_C_41_DN")
		)
		(pad "AG6" smd circle
			(at -7.599934 9.19988)
			(size 0.3556 0.3556)
			(layers "F.Cu" "F.Mask" "F.Paste")
			(net "GND")
		)
		(pad "AG7" smd circle
			(at -6.800088 9.19988)
			(size 0.3556 0.3556)
			(layers "F.Cu" "F.Mask" "F.Paste")
			(net "PCIE_SCC_TO_COMP_C_0_DP")
		)
		(pad "AG8" smd circle
			(at -5.999988 9.19988)
			(size 0.3556 0.3556)
			(layers "F.Cu" "F.Mask" "F.Paste")
			(net "PCIE_SCC_TO_COMP_C_1_DP")
		)
		(pad "AG9" smd circle
			(at -5.199888 9.19988)
			(size 0.3556 0.3556)
			(layers "F.Cu" "F.Mask" "F.Paste")
			(net "PCE_VDDH")
		)
		(pad "AG10" smd circle
			(at -4.400042 9.19988)
			(size 0.3556 0.3556)
			(layers "F.Cu" "F.Mask" "F.Paste")
			(net "PCIE_SCC_TO_COMP_C_2_DP")
		)
		(pad "AG11" smd circle
			(at -3.599942 9.19988)
			(size 0.3556 0.3556)
			(layers "F.Cu" "F.Mask" "F.Paste")
			(net "PCIE_SCC_TO_COMP_C_3_DP")
		)
		(pad "AG12" smd circle
			(at -2.800096 9.19988)
			(size 0.3556 0.3556)
			(layers "F.Cu" "F.Mask" "F.Paste")
			(net "PCE_VDDH")
		)
		(pad "AG13" smd circle
			(at -1.999996 9.19988)
			(size 0.3556 0.3556)
			(layers "F.Cu" "F.Mask" "F.Paste")
			(net "PCIE_SCC_TO_COMP_C_4_DP")
		)
		(pad "AG14" smd circle
			(at -1.199896 9.19988)
			(size 0.3556 0.3556)
			(layers "F.Cu" "F.Mask" "F.Paste")
			(net "PCIE_SCC_TO_COMP_C_5_DP")
		)
		(pad "AG15" smd circle
			(at -0.40005 9.19988)
			(size 0.3556 0.3556)
			(layers "F.Cu" "F.Mask" "F.Paste")
			(net "GND")
		)
		(pad "AG16" smd circle
			(at 0.40005 9.19988)
			(size 0.3556 0.3556)
			(layers "F.Cu" "F.Mask" "F.Paste")
			(net "PCIE_SCC_TO_COMP_C_6_DP")
		)
		(pad "AG17" smd circle
			(at 1.199896 9.19988)
			(size 0.3556 0.3556)
			(layers "F.Cu" "F.Mask" "F.Paste")
			(net "PCIE_SCC_TO_COMP_C_7_DP")
		)
		(pad "AG18" smd circle
			(at 1.999996 9.19988)
			(size 0.3556 0.3556)
			(layers "F.Cu" "F.Mask" "F.Paste")
			(net "PCE_VDDH")
		)
		(pad "AG19" smd circle
			(at 2.800096 9.19988)
			(size 0.3556 0.3556)
			(layers "F.Cu" "F.Mask" "F.Paste")
			(net "P1V8_C")
		)
		(pad "AG20" smd circle
			(at 3.599942 9.19988)
			(size 0.3556 0.3556)
			(layers "F.Cu" "F.Mask" "F.Paste")
			(net "GND")
		)
		(pad "AG21" smd circle
			(at 4.400042 9.19988)
			(size 0.3556 0.3556)
			(layers "F.Cu" "F.Mask" "F.Paste")
			(net "P1V8_C")
		)
		(pad "AG22" smd circle
			(at 5.199888 9.19988)
			(size 0.3556 0.3556)
			(layers "F.Cu" "F.Mask" "F.Paste")
			(net "GND")
		)
		(pad "AG23" smd circle
			(at 5.999988 9.19988)
			(size 0.3556 0.3556)
			(layers "F.Cu" "F.Mask" "F.Paste")
			(net "P1V8_C")
		)
		(pad "AG24" smd circle
			(at 6.800088 9.19988)
			(size 0.3556 0.3556)
			(layers "F.Cu" "F.Mask" "F.Paste")
			(net "GND")
		)
		(pad "AG25" smd circle
			(at 7.599934 9.19988)
			(size 0.3556 0.3556)
			(layers "F.Cu" "F.Mask" "F.Paste")
			(net "P1V8_C")
		)
		(pad "AG26" smd circle
			(at 8.400034 9.19988)
			(size 0.3556 0.3556)
			(layers "F.Cu" "F.Mask" "F.Paste")
			(net "GND")
		)
		(pad "AG27" smd circle
			(at 9.19988 9.19988)
			(size 0.3556 0.3556)
			(layers "F.Cu" "F.Mask" "F.Paste")
			(net "P1V8_C")
		)
		(pad "AG28" smd circle
			(at 9.99998 9.19988)
			(size 0.3556 0.3556)
			(layers "F.Cu" "F.Mask" "F.Paste")
			(net "IOC_GPIO_25")
		)
		(pad "AG29" smd circle
			(at 10.80008 9.19988)
			(size 0.3556 0.3556)
			(layers "F.Cu" "F.Mask" "F.Paste")
			(net "IOC_GPIO_18")
		)
		(pad "AG30" smd circle
			(at 11.599926 9.19988)
			(size 0.3556 0.3556)
			(layers "F.Cu" "F.Mask" "F.Paste")
			(net "IOC_GPIO_21")
		)
		(pad "AH1" smd circle
			(at -11.599926 9.99998)
			(size 0.4064 0.4064)
			(layers "F.Cu" "F.Mask" "F.Paste")
			(net "PHY_IOC_TO_SCC_40_DP")
		)
		(pad "AH2" smd circle
			(at -10.80008 9.99998)
			(size 0.4064 0.4064)
			(layers "F.Cu" "F.Mask" "F.Paste")
			(net "PHY_IOC_TO_SCC_40_DN")
		)
		(pad "AH3" smd circle
			(at -9.99998 9.99998)
			(size 0.4064 0.4064)
			(layers "F.Cu" "F.Mask" "F.Paste")
			(net "GND")
		)
		(pad "AH4" smd circle
			(at -9.19988 9.99998)
			(size 0.3556 0.3556)
			(layers "F.Cu" "F.Mask" "F.Paste")
			(net "PHY_SCC_TO_IOC_C_40_DP")
		)
		(pad "AH5" smd circle
			(at -8.400034 9.99998)
			(size 0.3556 0.3556)
			(layers "F.Cu" "F.Mask" "F.Paste")
			(net "PHY_SCC_TO_IOC_C_40_DN")
		)
		(pad "AH6" smd circle
			(at -7.599934 9.99998)
			(size 0.3556 0.3556)
			(layers "F.Cu" "F.Mask" "F.Paste")
			(net "GND")
		)
		(pad "AH7" smd circle
			(at -6.800088 9.99998)
			(size 0.3556 0.3556)
			(layers "F.Cu" "F.Mask" "F.Paste")
			(net "GND")
		)
		(pad "AH8" smd circle
			(at -5.999988 9.99998)
			(size 0.3556 0.3556)
			(layers "F.Cu" "F.Mask" "F.Paste")
			(net "GND")
		)
		(pad "AH9" smd circle
			(at -5.199888 9.99998)
			(size 0.3556 0.3556)
			(layers "F.Cu" "F.Mask" "F.Paste")
			(net "GND")
		)
		(pad "AH10" smd circle
			(at -4.400042 9.99998)
			(size 0.3556 0.3556)
			(layers "F.Cu" "F.Mask" "F.Paste")
			(net "GND")
		)
		(pad "AH11" smd circle
			(at -3.599942 9.99998)
			(size 0.3556 0.3556)
			(layers "F.Cu" "F.Mask" "F.Paste")
			(net "GND")
		)
		(pad "AH12" smd circle
			(at -2.800096 9.99998)
			(size 0.3556 0.3556)
			(layers "F.Cu" "F.Mask" "F.Paste")
			(net "GND")
		)
		(pad "AH13" smd circle
			(at -1.999996 9.99998)
			(size 0.3556 0.3556)
			(layers "F.Cu" "F.Mask" "F.Paste")
			(net "GND")
		)
		(pad "AH14" smd circle
			(at -1.199896 9.99998)
			(size 0.3556 0.3556)
			(layers "F.Cu" "F.Mask" "F.Paste")
			(net "GND")
		)
		(pad "AH15" smd circle
			(at -0.40005 9.99998)
			(size 0.3556 0.3556)
			(layers "F.Cu" "F.Mask" "F.Paste")
			(net "PCE_VDDH")
		)
		(pad "AH16" smd circle
			(at 0.40005 9.99998)
			(size 0.3556 0.3556)
			(layers "F.Cu" "F.Mask" "F.Paste")
			(net "GND")
		)
		(pad "AH17" smd circle
			(at 1.199896 9.99998)
			(size 0.3556 0.3556)
			(layers "F.Cu" "F.Mask" "F.Paste")
			(net "GND")
		)
		(pad "AH18" smd circle
			(at 1.999996 9.99998)
			(size 0.3556 0.3556)
			(layers "F.Cu" "F.Mask" "F.Paste")
			(net "GND")
		)
		(pad "AH19" smd circle
			(at 2.800096 9.99998)
			(size 0.3556 0.3556)
			(layers "F.Cu" "F.Mask" "F.Paste")
			(net "Net_1155")
		)
		(pad "AH20" smd circle
			(at 3.599942 9.99998)
			(size 0.3556 0.3556)
			(layers "F.Cu" "F.Mask" "F.Paste")
			(net "PCIE_RST_N")
		)
		(pad "AH21" smd circle
			(at 4.400042 9.99998)
			(size 0.3556 0.3556)
			(layers "F.Cu" "F.Mask" "F.Paste")
			(net "IOC_UART_1_TX")
		)
		(pad "AH22" smd circle
			(at 5.199888 9.99998)
			(size 0.3556 0.3556)
			(layers "F.Cu" "F.Mask" "F.Paste")
			(net "IOC_GPIO_2")
		)
		(pad "AH23" smd circle
			(at 5.999988 9.99998)
			(size 0.3556 0.3556)
			(layers "F.Cu" "F.Mask" "F.Paste")
			(net "IOC_GPIO_3")
		)
		(pad "AH24" smd circle
			(at 6.800088 9.99998)
			(size 0.3556 0.3556)
			(layers "F.Cu" "F.Mask" "F.Paste")
			(net "IOC_GPIO_5")
		)
		(pad "AH25" smd circle
			(at 7.599934 9.99998)
			(size 0.3556 0.3556)
			(layers "F.Cu" "F.Mask" "F.Paste")
			(net "IOC_GPIO_6")
		)
		(pad "AH26" smd circle
			(at 8.400034 9.99998)
			(size 0.3556 0.3556)
			(layers "F.Cu" "F.Mask" "F.Paste")
			(net "IOC_UART_1_RX")
		)
		(pad "AH27" smd circle
			(at 9.19988 9.99998)
			(size 0.3556 0.3556)
			(layers "F.Cu" "F.Mask" "F.Paste")
			(net "SPARE0")
		)
		(pad "AH28" smd circle
			(at 9.99998 9.99998)
			(size 0.4064 0.4064)
			(layers "F.Cu" "F.Mask" "F.Paste")
			(net "IOC_GPIO_10")
		)
		(pad "AH29" smd circle
			(at 10.80008 9.99998)
			(size 0.4064 0.4064)
			(layers "F.Cu" "F.Mask" "F.Paste")
			(net "IOC_GPIO_22")
		)
		(pad "AH30" smd circle
			(at 11.599926 9.99998)
			(size 0.4064 0.4064)
			(layers "F.Cu" "F.Mask" "F.Paste")
			(net "IOC_GPIO_11")
		)
		(pad "AJ1" smd circle
			(at -11.599926 10.80008)
			(size 0.4064 0.4064)
			(layers "F.Cu" "F.Mask" "F.Paste")
			(net "SAS0_VDDH")
		)
		(pad "AJ2" smd circle
			(at -10.80008 10.80008)
			(size 0.4064 0.4064)
			(layers "F.Cu" "F.Mask" "F.Paste")
			(net "GND")
		)
		(pad "AJ3" smd circle
			(at -9.99998 10.80008)
			(size 0.4064 0.4064)
			(layers "F.Cu" "F.Mask" "F.Paste")
			(net "SAS0_AVDD")
		)
		(pad "AJ4" smd circle
			(at -9.19988 10.80008)
			(size 0.3556 0.3556)
			(layers "F.Cu" "F.Mask" "F.Paste")
			(net "GND")
		)
		(pad "AJ5" smd circle
			(at -8.400034 10.80008)
			(size 0.3556 0.3556)
			(layers "F.Cu" "F.Mask" "F.Paste")
			(net "GND")
		)
		(pad "AJ6" smd circle
			(at -7.599934 10.80008)
			(size 0.3556 0.3556)
			(layers "F.Cu" "F.Mask" "F.Paste")
			(net "GND")
		)
		(pad "AJ7" smd circle
			(at -6.800088 10.80008)
			(size 0.3556 0.3556)
			(layers "F.Cu" "F.Mask" "F.Paste")
			(net "PCIE_COMP_TO_SCC_0_DN")
		)
		(pad "AJ8" smd circle
			(at -5.999988 10.80008)
			(size 0.3556 0.3556)
			(layers "F.Cu" "F.Mask" "F.Paste")
			(net "PCIE_COMP_TO_SCC_1_DN")
		)
		(pad "AJ9" smd circle
			(at -5.199888 10.80008)
			(size 0.3556 0.3556)
			(layers "F.Cu" "F.Mask" "F.Paste")
			(net "GND")
		)
		(pad "AJ10" smd circle
			(at -4.400042 10.80008)
			(size 0.3556 0.3556)
			(layers "F.Cu" "F.Mask" "F.Paste")
			(net "PCIE_COMP_TO_SCC_2_DN")
		)
		(pad "AJ11" smd circle
			(at -3.599942 10.80008)
			(size 0.3556 0.3556)
			(layers "F.Cu" "F.Mask" "F.Paste")
			(net "PCIE_COMP_TO_SCC_3_DN")
		)
		(pad "AJ12" smd circle
			(at -2.800096 10.80008)
			(size 0.3556 0.3556)
			(layers "F.Cu" "F.Mask" "F.Paste")
			(net "GND")
		)
		(pad "AJ13" smd circle
			(at -1.999996 10.80008)
			(size 0.3556 0.3556)
			(layers "F.Cu" "F.Mask" "F.Paste")
			(net "PCIE_COMP_TO_SCC_4_DN")
		)
		(pad "AJ14" smd circle
			(at -1.199896 10.80008)
			(size 0.3556 0.3556)
			(layers "F.Cu" "F.Mask" "F.Paste")
			(net "PCIE_COMP_TO_SCC_5_DN")
		)
		(pad "AJ15" smd circle
			(at -0.40005 10.80008)
			(size 0.3556 0.3556)
			(layers "F.Cu" "F.Mask" "F.Paste")
			(net "GND")
		)
		(pad "AJ16" smd circle
			(at 0.40005 10.80008)
			(size 0.3556 0.3556)
			(layers "F.Cu" "F.Mask" "F.Paste")
			(net "PCIE_COMP_TO_SCC_6_DN")
		)
		(pad "AJ17" smd circle
			(at 1.199896 10.80008)
			(size 0.3556 0.3556)
			(layers "F.Cu" "F.Mask" "F.Paste")
			(net "PCIE_COMP_TO_SCC_7_DN")
		)
		(pad "AJ18" smd circle
			(at 1.999996 10.80008)
			(size 0.3556 0.3556)
			(layers "F.Cu" "F.Mask" "F.Paste")
			(net "GND")
		)
		(pad "AJ19" smd circle
			(at 2.800096 10.80008)
			(size 0.3556 0.3556)
			(layers "F.Cu" "F.Mask" "F.Paste")
			(net "Net_1156")
		)
		(pad "AJ20" smd circle
			(at 3.599942 10.80008)
			(size 0.3556 0.3556)
			(layers "F.Cu" "F.Mask" "F.Paste")
			(net "SYS_ERR_0")
		)
		(pad "AJ21" smd circle
			(at 4.400042 10.80008)
			(size 0.3556 0.3556)
			(layers "F.Cu" "F.Mask" "F.Paste")
			(net "IOC_RESET_N")
		)
		(pad "AJ22" smd circle
			(at 5.199888 10.80008)
			(size 0.3556 0.3556)
			(layers "F.Cu" "F.Mask" "F.Paste")
			(net "SPARE2")
		)
		(pad "AJ23" smd circle
			(at 5.999988 10.80008)
			(size 0.3556 0.3556)
			(layers "F.Cu" "F.Mask" "F.Paste")
			(net "SYS_DBMODE3")
		)
		(pad "AJ24" smd circle
			(at 6.800088 10.80008)
			(size 0.3556 0.3556)
			(layers "F.Cu" "F.Mask" "F.Paste")
			(net "IOC_UART_0_RX")
		)
		(pad "AJ25" smd circle
			(at 7.599934 10.80008)
			(size 0.3556 0.3556)
			(layers "F.Cu" "F.Mask" "F.Paste")
			(net "IOC_GPIO_13")
		)
		(pad "AJ26" smd circle
			(at 8.400034 10.80008)
			(size 0.3556 0.3556)
			(layers "F.Cu" "F.Mask" "F.Paste")
			(net "IOC_GPIO_1")
		)
		(pad "AJ27" smd circle
			(at 9.19988 10.80008)
			(size 0.3556 0.3556)
			(layers "F.Cu" "F.Mask" "F.Paste")
			(net "IOC_GPIO_14")
		)
		(pad "AJ28" smd circle
			(at 9.99998 10.80008)
			(size 0.4064 0.4064)
			(layers "F.Cu" "F.Mask" "F.Paste")
			(net "IOC_GPIO_20")
		)
		(pad "AJ29" smd circle
			(at 10.80008 10.80008)
			(size 0.4064 0.4064)
			(layers "F.Cu" "F.Mask" "F.Paste")
			(net "IOC_GPIO_12")
		)
		(pad "AJ30" smd circle
			(at 11.599926 10.80008)
			(size 0.4064 0.4064)
			(layers "F.Cu" "F.Mask" "F.Paste")
			(net "IOC_GPIO_4")
		)
		(pad "AK2" smd circle
			(at -10.80008 11.599926)
			(size 0.4064 0.4064)
			(layers "F.Cu" "F.Mask" "F.Paste")
			(net "GND")
		)
		(pad "AK3" smd circle
			(at -9.99998 11.599926)
			(size 0.4064 0.4064)
			(layers "F.Cu" "F.Mask" "F.Paste")
			(net "GND")
		)
		(pad "AK4" smd circle
			(at -9.19988 11.599926)
			(size 0.3556 0.3556)
			(layers "F.Cu" "F.Mask" "F.Paste")
			(net "PCIE_CLK_R_P")
		)
		(pad "AK5" smd circle
			(at -8.400034 11.599926)
			(size 0.3556 0.3556)
			(layers "F.Cu" "F.Mask" "F.Paste")
			(net "PCIE_CLK_R_N")
		)
		(pad "AK6" smd circle
			(at -7.599934 11.599926)
			(size 0.3556 0.3556)
			(layers "F.Cu" "F.Mask" "F.Paste")
			(net "PCE_AVDD")
		)
		(pad "AK7" smd circle
			(at -6.800088 11.599926)
			(size 0.3556 0.3556)
			(layers "F.Cu" "F.Mask" "F.Paste")
			(net "PCIE_COMP_TO_SCC_0_DP")
		)
		(pad "AK8" smd circle
			(at -5.999988 11.599926)
			(size 0.3556 0.3556)
			(layers "F.Cu" "F.Mask" "F.Paste")
			(net "PCIE_COMP_TO_SCC_1_DP")
		)
		(pad "AK9" smd circle
			(at -5.199888 11.599926)
			(size 0.3556 0.3556)
			(layers "F.Cu" "F.Mask" "F.Paste")
			(net "PCE_AVDD")
		)
		(pad "AK10" smd circle
			(at -4.400042 11.599926)
			(size 0.3556 0.3556)
			(layers "F.Cu" "F.Mask" "F.Paste")
			(net "PCIE_COMP_TO_SCC_2_DP")
		)
		(pad "AK11" smd circle
			(at -3.599942 11.599926)
			(size 0.3556 0.3556)
			(layers "F.Cu" "F.Mask" "F.Paste")
			(net "PCIE_COMP_TO_SCC_3_DP")
		)
		(pad "AK12" smd circle
			(at -2.800096 11.599926)
			(size 0.3556 0.3556)
			(layers "F.Cu" "F.Mask" "F.Paste")
			(net "PCE_AVDD")
		)
		(pad "AK13" smd circle
			(at -1.999996 11.599926)
			(size 0.3556 0.3556)
			(layers "F.Cu" "F.Mask" "F.Paste")
			(net "PCIE_COMP_TO_SCC_4_DP")
		)
		(pad "AK14" smd circle
			(at -1.199896 11.599926)
			(size 0.3556 0.3556)
			(layers "F.Cu" "F.Mask" "F.Paste")
			(net "PCIE_COMP_TO_SCC_5_DP")
		)
		(pad "AK15" smd circle
			(at -0.40005 11.599926)
			(size 0.3556 0.3556)
			(layers "F.Cu" "F.Mask" "F.Paste")
			(net "PCE_AVDD")
		)
		(pad "AK16" smd circle
			(at 0.40005 11.599926)
			(size 0.3556 0.3556)
			(layers "F.Cu" "F.Mask" "F.Paste")
			(net "PCIE_COMP_TO_SCC_6_DP")
		)
		(pad "AK17" smd circle
			(at 1.199896 11.599926)
			(size 0.3556 0.3556)
			(layers "F.Cu" "F.Mask" "F.Paste")
			(net "PCIE_COMP_TO_SCC_7_DP")
		)
		(pad "AK18" smd circle
			(at 1.999996 11.599926)
			(size 0.3556 0.3556)
			(layers "F.Cu" "F.Mask" "F.Paste")
			(net "PCE_AVDD")
		)
		(pad "AK19" smd circle
			(at 2.800096 11.599926)
			(size 0.3556 0.3556)
			(layers "F.Cu" "F.Mask" "F.Paste")
			(net "Net_1157")
		)
		(pad "AK20" smd circle
			(at 3.599942 11.599926)
			(size 0.3556 0.3556)
			(layers "F.Cu" "F.Mask" "F.Paste")
			(net "SYS_DBMODE1")
		)
		(pad "AK21" smd circle
			(at 4.400042 11.599926)
			(size 0.3556 0.3556)
			(layers "F.Cu" "F.Mask" "F.Paste")
			(net "SYS_DBMODE4")
		)
		(pad "AK22" smd circle
			(at 5.199888 11.599926)
			(size 0.3556 0.3556)
			(layers "F.Cu" "F.Mask" "F.Paste")
			(net "SYS_ERROR1")
		)
		(pad "AK23" smd circle
			(at 5.999988 11.599926)
			(size 0.3556 0.3556)
			(layers "F.Cu" "F.Mask" "F.Paste")
			(net "SYS_HALT0#")
		)
		(pad "AK24" smd circle
			(at 6.800088 11.599926)
			(size 0.3556 0.3556)
			(layers "F.Cu" "F.Mask" "F.Paste")
			(net "SYS_DBMODE2")
		)
		(pad "AK25" smd circle
			(at 7.599934 11.599926)
			(size 0.3556 0.3556)
			(layers "F.Cu" "F.Mask" "F.Paste")
			(net "SPARE1")
		)
		(pad "AK26" smd circle
			(at 8.400034 11.599926)
			(size 0.3556 0.3556)
			(layers "F.Cu" "F.Mask" "F.Paste")
			(net "SYS_HALT1#")
		)
		(pad "AK27" smd circle
			(at 9.19988 11.599926)
			(size 0.3556 0.3556)
			(layers "F.Cu" "F.Mask" "F.Paste")
			(net "IOC_UART_0_TX")
		)
		(pad "AK28" smd circle
			(at 9.99998 11.599926)
			(size 0.4064 0.4064)
			(layers "F.Cu" "F.Mask" "F.Paste")
			(net "IOC_GPIO_19")
		)
		(pad "AK29" smd circle
			(at 10.80008 11.599926)
			(size 0.4064 0.4064)
			(layers "F.Cu" "F.Mask" "F.Paste")
			(net "IOC_GPIO_9")
		)
		(pad "B1" smd circle
			(at -11.599926 -10.80008)
			(size 0.4064 0.4064)
			(layers "F.Cu" "F.Mask" "F.Paste")
			(net "Net_1196")
		)
		(pad "B2" smd circle
			(at -10.80008 -10.80008)
			(size 0.4064 0.4064)
			(layers "F.Cu" "F.Mask" "F.Paste")
			(net "GND")
		)
		(pad "B3" smd circle
			(at -9.99998 -10.80008)
			(size 0.4064 0.4064)
			(layers "F.Cu" "F.Mask" "F.Paste")
			(net "Net_1162")
		)
		(pad "B4" smd circle
			(at -9.19988 -10.80008)
			(size 0.3556 0.3556)
			(layers "F.Cu" "F.Mask" "F.Paste")
			(net "Net_1163")
		)
		(pad "B5" smd circle
			(at -8.400034 -10.80008)
			(size 0.3556 0.3556)
			(layers "F.Cu" "F.Mask" "F.Paste")
			(net "Net_1164")
		)
		(pad "B6" smd circle
			(at -7.599934 -10.80008)
			(size 0.3556 0.3556)
			(layers "F.Cu" "F.Mask" "F.Paste")
			(net "GND")
		)
		(pad "B7" smd circle
			(at -6.800088 -10.80008)
			(size 0.3556 0.3556)
			(layers "F.Cu" "F.Mask" "F.Paste")
			(net "ICE1_TCK")
		)
		(pad "B8" smd circle
			(at -5.999988 -10.80008)
			(size 0.3556 0.3556)
			(layers "F.Cu" "F.Mask" "F.Paste")
			(net "ICE0_TDI")
		)
		(pad "B9" smd circle
			(at -5.199888 -10.80008)
			(size 0.3556 0.3556)
			(layers "F.Cu" "F.Mask" "F.Paste")
			(net "IOC_VREF_SET")
		)
		(pad "B10" smd circle
			(at -4.400042 -10.80008)
			(size 0.3556 0.3556)
			(layers "F.Cu" "F.Mask" "F.Paste")
			(net "Net_1165")
		)
		(pad "B11" smd circle
			(at -3.599942 -10.80008)
			(size 0.3556 0.3556)
			(layers "F.Cu" "F.Mask" "F.Paste")
			(net "GND")
		)
		(pad "B12" smd circle
			(at -2.800096 -10.80008)
			(size 0.3556 0.3556)
			(layers "F.Cu" "F.Mask" "F.Paste")
			(net "AVSO_IDDTN18")
		)
		(pad "B13" smd circle
			(at -1.999996 -10.80008)
			(size 0.3556 0.3556)
			(layers "F.Cu" "F.Mask" "F.Paste")
			(net "AVSO_VREF")
		)
		(pad "B14" smd circle
			(at -1.199896 -10.80008)
			(size 0.3556 0.3556)
			(layers "F.Cu" "F.Mask" "F.Paste")
			(net "GND")
		)
		(pad "B15" smd circle
			(at -0.40005 -10.80008)
			(size 0.3556 0.3556)
			(layers "F.Cu" "F.Mask" "F.Paste")
			(net "GND")
		)
		(pad "B16" smd circle
			(at 0.40005 -10.80008)
			(size 0.3556 0.3556)
			(layers "F.Cu" "F.Mask" "F.Paste")
			(net "LSI_JTAG_EN_N")
		)
		(pad "B17" smd circle
			(at 1.199896 -10.80008)
			(size 0.3556 0.3556)
			(layers "F.Cu" "F.Mask" "F.Paste")
			(net "LSI_SCAN_EN")
		)
		(pad "B18" smd circle
			(at 1.999996 -10.80008)
			(size 0.3556 0.3556)
			(layers "F.Cu" "F.Mask" "F.Paste")
			(net "JTAG_IOC_TMS")
		)
		(pad "B19" smd circle
			(at 2.800096 -10.80008)
			(size 0.3556 0.3556)
			(layers "F.Cu" "F.Mask" "F.Paste")
			(net "XM_CS0_N")
		)
		(pad "B20" smd circle
			(at 3.599942 -10.80008)
			(size 0.3556 0.3556)
			(layers "F.Cu" "F.Mask" "F.Paste")
			(net "XM_F_RST_N")
		)
		(pad "B21" smd circle
			(at 4.400042 -10.80008)
			(size 0.3556 0.3556)
			(layers "F.Cu" "F.Mask" "F.Paste")
			(net "XM_NAND_CS_N")
		)
		(pad "B22" smd circle
			(at 5.199888 -10.80008)
			(size 0.3556 0.3556)
			(layers "F.Cu" "F.Mask" "F.Paste")
			(net "XM_OE_N")
		)
		(pad "B23" smd circle
			(at 5.999988 -10.80008)
			(size 0.3556 0.3556)
			(layers "F.Cu" "F.Mask" "F.Paste")
			(net "Net_1150")
		)
		(pad "B24" smd circle
			(at 6.800088 -10.80008)
			(size 0.3556 0.3556)
			(layers "F.Cu" "F.Mask" "F.Paste")
			(net "Net_1151")
		)
		(pad "B25" smd circle
			(at 7.599934 -10.80008)
			(size 0.3556 0.3556)
			(layers "F.Cu" "F.Mask" "F.Paste")
			(net "XM_ADDR_0")
		)
		(pad "B26" smd circle
			(at 8.400034 -10.80008)
			(size 0.3556 0.3556)
			(layers "F.Cu" "F.Mask" "F.Paste")
			(net "XM_ALE")
		)
		(pad "B27" smd circle
			(at 9.19988 -10.80008)
			(size 0.3556 0.3556)
			(layers "F.Cu" "F.Mask" "F.Paste")
			(net "XM_ADDR_1")
		)
		(pad "B28" smd circle
			(at 9.99998 -10.80008)
			(size 0.4064 0.4064)
			(layers "F.Cu" "F.Mask" "F.Paste")
			(net "XM_ADDR_6")
		)
		(pad "B29" smd circle
			(at 10.80008 -10.80008)
			(size 0.4064 0.4064)
			(layers "F.Cu" "F.Mask" "F.Paste")
			(net "XM_ADDR_8")
		)
		(pad "B30" smd circle
			(at 11.599926 -10.80008)
			(size 0.4064 0.4064)
			(layers "F.Cu" "F.Mask" "F.Paste")
			(net "XM_ADDR_7")
		)
		(pad "C1" smd circle
			(at -11.599926 -9.99998)
			(size 0.4064 0.4064)
			(layers "F.Cu" "F.Mask" "F.Paste")
			(net "GND")
		)
		(pad "C2" smd circle
			(at -10.80008 -9.99998)
			(size 0.4064 0.4064)
			(layers "F.Cu" "F.Mask" "F.Paste")
			(net "Net_1166")
		)
		(pad "C3" smd circle
			(at -9.99998 -9.99998)
			(size 0.4064 0.4064)
			(layers "F.Cu" "F.Mask" "F.Paste")
			(net "Net_1167")
		)
		(pad "C4" smd circle
			(at -9.19988 -9.99998)
			(size 0.3556 0.3556)
			(layers "F.Cu" "F.Mask" "F.Paste")
			(net "Net_1168")
		)
		(pad "C5" smd circle
			(at -8.400034 -9.99998)
			(size 0.3556 0.3556)
			(layers "F.Cu" "F.Mask" "F.Paste")
			(net "GND")
		)
		(pad "C6" smd circle
			(at -7.599934 -9.99998)
			(size 0.3556 0.3556)
			(layers "F.Cu" "F.Mask" "F.Paste")
			(net "ICE1_TRST#")
		)
		(pad "C7" smd circle
			(at -6.800088 -9.99998)
			(size 0.3556 0.3556)
			(layers "F.Cu" "F.Mask" "F.Paste")
			(net "ICE0_TMS")
		)
		(pad "C8" smd circle
			(at -5.999988 -9.99998)
			(size 0.3556 0.3556)
			(layers "F.Cu" "F.Mask" "F.Paste")
			(net "ICE0_TDO")
		)
		(pad "C9" smd circle
			(at -5.199888 -9.99998)
			(size 0.3556 0.3556)
			(layers "F.Cu" "F.Mask" "F.Paste")
			(net "Net_1169")
		)
		(pad "C10" smd circle
			(at -4.400042 -9.99998)
			(size 0.3556 0.3556)
			(layers "F.Cu" "F.Mask" "F.Paste")
			(net "Net_1170")
		)
		(pad "C11" smd circle
			(at -3.599942 -9.99998)
			(size 0.3556 0.3556)
			(layers "F.Cu" "F.Mask" "F.Paste")
			(net "GND")
		)
		(pad "C12" smd circle
			(at -2.800096 -9.99998)
			(size 0.3556 0.3556)
			(layers "F.Cu" "F.Mask" "F.Paste")
			(net "P1V8_C_PG_LS")
		)
		(pad "C13" smd circle
			(at -1.999996 -9.99998)
			(size 0.3556 0.3556)
			(layers "F.Cu" "F.Mask" "F.Paste")
			(net "Net_1154")
		)
		(pad "C14" smd circle
			(at -1.199896 -9.99998)
			(size 0.3556 0.3556)
			(layers "F.Cu" "F.Mask" "F.Paste")
			(net "GND")
		)
		(pad "C15" smd circle
			(at -0.40005 -9.99998)
			(size 0.3556 0.3556)
			(layers "F.Cu" "F.Mask" "F.Paste")
			(net "GND")
		)
		(pad "C16" smd circle
			(at 0.40005 -9.99998)
			(size 0.3556 0.3556)
			(layers "F.Cu" "F.Mask" "F.Paste")
			(net "LSI_TN")
		)
		(pad "C17" smd circle
			(at 1.199896 -9.99998)
			(size 0.3556 0.3556)
			(layers "F.Cu" "F.Mask" "F.Paste")
			(net "JTAG_IOC_TCK")
		)
		(pad "C18" smd circle
			(at 1.999996 -9.99998)
			(size 0.3556 0.3556)
			(layers "F.Cu" "F.Mask" "F.Paste")
			(net "IOC_TDO")
		)
		(pad "C19" smd circle
			(at 2.800096 -9.99998)
			(size 0.3556 0.3556)
			(layers "F.Cu" "F.Mask" "F.Paste")
			(net "XM_DATA_15")
		)
		(pad "C20" smd circle
			(at 3.599942 -9.99998)
			(size 0.3556 0.3556)
			(layers "F.Cu" "F.Mask" "F.Paste")
			(net "XM_DATA_6")
		)
		(pad "C21" smd circle
			(at 4.400042 -9.99998)
			(size 0.3556 0.3556)
			(layers "F.Cu" "F.Mask" "F.Paste")
			(net "XM_DATA_8")
		)
		(pad "C22" smd circle
			(at 5.199888 -9.99998)
			(size 0.3556 0.3556)
			(layers "F.Cu" "F.Mask" "F.Paste")
			(net "XM_DATA_5")
		)
		(pad "C23" smd circle
			(at 5.999988 -9.99998)
			(size 0.3556 0.3556)
			(layers "F.Cu" "F.Mask" "F.Paste")
			(net "XM_CLE")
		)
		(pad "C24" smd circle
			(at 6.800088 -9.99998)
			(size 0.3556 0.3556)
			(layers "F.Cu" "F.Mask" "F.Paste")
			(net "XM_DATA_7")
		)
		(pad "C25" smd circle
			(at 7.599934 -9.99998)
			(size 0.3556 0.3556)
			(layers "F.Cu" "F.Mask" "F.Paste")
			(net "XM_DATA_10")
		)
		(pad "C26" smd circle
			(at 8.400034 -9.99998)
			(size 0.3556 0.3556)
			(layers "F.Cu" "F.Mask" "F.Paste")
			(net "XM_DATA_9")
		)
		(pad "C27" smd circle
			(at 9.19988 -9.99998)
			(size 0.3556 0.3556)
			(layers "F.Cu" "F.Mask" "F.Paste")
			(net "XM_ADDR_2")
		)
		(pad "C28" smd circle
			(at 9.99998 -9.99998)
			(size 0.4064 0.4064)
			(layers "F.Cu" "F.Mask" "F.Paste")
			(net "XM_ADDR_5")
		)
		(pad "C29" smd circle
			(at 10.80008 -9.99998)
			(size 0.4064 0.4064)
			(layers "F.Cu" "F.Mask" "F.Paste")
			(net "XM_ADDR_11")
		)
		(pad "C30" smd circle
			(at 11.599926 -9.99998)
			(size 0.4064 0.4064)
			(layers "F.Cu" "F.Mask" "F.Paste")
			(net "XM_ADDR_13")
		)
		(pad "D1" smd circle
			(at -11.599926 -9.19988)
			(size 0.3556 0.3556)
			(layers "F.Cu" "F.Mask" "F.Paste")
			(net "Net_1197")
		)
		(pad "D2" smd circle
			(at -10.80008 -9.19988)
			(size 0.3556 0.3556)
			(layers "F.Cu" "F.Mask" "F.Paste")
			(net "Net_1171")
		)
		(pad "D3" smd circle
			(at -9.99998 -9.19988)
			(size 0.3556 0.3556)
			(layers "F.Cu" "F.Mask" "F.Paste")
			(net "Net_1172")
		)
		(pad "D4" smd circle
			(at -9.19988 -9.19988)
			(size 0.3556 0.3556)
			(layers "F.Cu" "F.Mask" "F.Paste")
			(net "P1V8_C")
		)
		(pad "D5" smd circle
			(at -8.400034 -9.19988)
			(size 0.3556 0.3556)
			(layers "F.Cu" "F.Mask" "F.Paste")
			(net "GND")
		)
		(pad "D6" smd circle
			(at -7.599934 -9.19988)
			(size 0.3556 0.3556)
			(layers "F.Cu" "F.Mask" "F.Paste")
			(net "P1V8_C")
		)
		(pad "D7" smd circle
			(at -6.800088 -9.19988)
			(size 0.3556 0.3556)
			(layers "F.Cu" "F.Mask" "F.Paste")
			(net "GND")
		)
		(pad "D8" smd circle
			(at -5.999988 -9.19988)
			(size 0.3556 0.3556)
			(layers "F.Cu" "F.Mask" "F.Paste")
			(net "P1V8_C")
		)
		(pad "D9" smd circle
			(at -5.199888 -9.19988)
			(size 0.3556 0.3556)
			(layers "F.Cu" "F.Mask" "F.Paste")
			(net "GND")
		)
		(pad "D10" smd circle
			(at -4.400042 -9.19988)
			(size 0.3556 0.3556)
			(layers "F.Cu" "F.Mask" "F.Paste")
			(net "P1V8_C")
		)
		(pad "D11" smd circle
			(at -3.599942 -9.19988)
			(size 0.3556 0.3556)
			(layers "F.Cu" "F.Mask" "F.Paste")
			(net "GND")
		)
		(pad "D12" smd circle
			(at -2.800096 -9.19988)
			(size 0.3556 0.3556)
			(layers "F.Cu" "F.Mask" "F.Paste")
			(net "GND")
		)
		(pad "D13" smd circle
			(at -1.999996 -9.19988)
			(size 0.3556 0.3556)
			(layers "F.Cu" "F.Mask" "F.Paste")
			(net "GND")
		)
		(pad "D14" smd circle
			(at -1.199896 -9.19988)
			(size 0.3556 0.3556)
			(layers "F.Cu" "F.Mask" "F.Paste")
			(net "GND")
		)
		(pad "D15" smd circle
			(at -0.40005 -9.19988)
			(size 0.3556 0.3556)
			(layers "F.Cu" "F.Mask" "F.Paste")
			(net "GND")
		)
		(pad "D16" smd circle
			(at 0.40005 -9.19988)
			(size 0.3556 0.3556)
			(layers "F.Cu" "F.Mask" "F.Paste")
			(net "P1V8_C")
		)
		(pad "D17" smd circle
			(at 1.199896 -9.19988)
			(size 0.3556 0.3556)
			(layers "F.Cu" "F.Mask" "F.Paste")
			(net "GND")
		)
		(pad "D18" smd circle
			(at 1.999996 -9.19988)
			(size 0.3556 0.3556)
			(layers "F.Cu" "F.Mask" "F.Paste")
			(net "P1V8_C")
		)
		(pad "D19" smd circle
			(at 2.800096 -9.19988)
			(size 0.3556 0.3556)
			(layers "F.Cu" "F.Mask" "F.Paste")
			(net "GND")
		)
		(pad "D20" smd circle
			(at 3.599942 -9.19988)
			(size 0.3556 0.3556)
			(layers "F.Cu" "F.Mask" "F.Paste")
			(net "P1V8_C")
		)
		(pad "D21" smd circle
			(at 4.400042 -9.19988)
			(size 0.3556 0.3556)
			(layers "F.Cu" "F.Mask" "F.Paste")
			(net "GND")
		)
		(pad "D22" smd circle
			(at 5.199888 -9.19988)
			(size 0.3556 0.3556)
			(layers "F.Cu" "F.Mask" "F.Paste")
			(net "P1V8_C")
		)
		(pad "D23" smd circle
			(at 5.999988 -9.19988)
			(size 0.3556 0.3556)
			(layers "F.Cu" "F.Mask" "F.Paste")
			(net "GND")
		)
		(pad "D24" smd circle
			(at 6.800088 -9.19988)
			(size 0.3556 0.3556)
			(layers "F.Cu" "F.Mask" "F.Paste")
			(net "P1V8_C")
		)
		(pad "D25" smd circle
			(at 7.599934 -9.19988)
			(size 0.3556 0.3556)
			(layers "F.Cu" "F.Mask" "F.Paste")
			(net "GND")
		)
		(pad "D26" smd circle
			(at 8.400034 -9.19988)
			(size 0.3556 0.3556)
			(layers "F.Cu" "F.Mask" "F.Paste")
			(net "P1V8_C")
		)
		(pad "D27" smd circle
			(at 9.19988 -9.19988)
			(size 0.3556 0.3556)
			(layers "F.Cu" "F.Mask" "F.Paste")
			(net "GND")
		)
		(pad "D28" smd circle
			(at 9.99998 -9.19988)
			(size 0.3556 0.3556)
			(layers "F.Cu" "F.Mask" "F.Paste")
			(net "XM_ADDR_9")
		)
		(pad "D29" smd circle
			(at 10.80008 -9.19988)
			(size 0.3556 0.3556)
			(layers "F.Cu" "F.Mask" "F.Paste")
			(net "XM_ADDR_10")
		)
		(pad "D30" smd circle
			(at 11.599926 -9.19988)
			(size 0.3556 0.3556)
			(layers "F.Cu" "F.Mask" "F.Paste")
			(net "XM_ADDR_17")
		)
		(pad "E1" smd circle
			(at -11.599926 -8.400034)
			(size 0.3556 0.3556)
			(layers "F.Cu" "F.Mask" "F.Paste")
			(net "Net_1198")
		)
		(pad "E2" smd circle
			(at -10.80008 -8.400034)
			(size 0.3556 0.3556)
			(layers "F.Cu" "F.Mask" "F.Paste")
			(net "Net_1173")
		)
		(pad "E3" smd circle
			(at -9.99998 -8.400034)
			(size 0.3556 0.3556)
			(layers "F.Cu" "F.Mask" "F.Paste")
			(net "GND")
		)
		(pad "E4" smd circle
			(at -9.19988 -8.400034)
			(size 0.3556 0.3556)
			(layers "F.Cu" "F.Mask" "F.Paste")
			(net "GND")
		)
		(pad "E5" smd circle
			(at -8.400034 -8.400034)
			(size 0.3556 0.3556)
			(layers "F.Cu" "F.Mask" "F.Paste")
			(net "P1V8_C")
		)
		(pad "E6" smd circle
			(at -7.599934 -8.400034)
			(size 0.3556 0.3556)
			(layers "F.Cu" "F.Mask" "F.Paste")
			(net "GND")
		)
		(pad "E7" smd circle
			(at -6.800088 -8.400034)
			(size 0.3556 0.3556)
			(layers "F.Cu" "F.Mask" "F.Paste")
			(net "P1V8_C")
		)
		(pad "E8" smd circle
			(at -5.999988 -8.400034)
			(size 0.3556 0.3556)
			(layers "F.Cu" "F.Mask" "F.Paste")
			(net "GND")
		)
		(pad "E9" smd circle
			(at -5.199888 -8.400034)
			(size 0.3556 0.3556)
			(layers "F.Cu" "F.Mask" "F.Paste")
			(net "P1V8_C")
		)
		(pad "E10" smd circle
			(at -4.400042 -8.400034)
			(size 0.3556 0.3556)
			(layers "F.Cu" "F.Mask" "F.Paste")
			(net "GND")
		)
		(pad "E11" smd circle
			(at -3.599942 -8.400034)
			(size 0.3556 0.3556)
			(layers "F.Cu" "F.Mask" "F.Paste")
			(net "GND")
		)
		(pad "E12" smd circle
			(at -2.800096 -8.400034)
			(size 0.3556 0.3556)
			(layers "F.Cu" "F.Mask" "F.Paste")
			(net "GND")
		)
		(pad "E13" smd circle
			(at -1.999996 -8.400034)
			(size 0.3556 0.3556)
			(layers "F.Cu" "F.Mask" "F.Paste")
			(net "GND")
		)
		(pad "E14" smd circle
			(at -1.199896 -8.400034)
			(size 0.3556 0.3556)
			(layers "F.Cu" "F.Mask" "F.Paste")
			(net "GND")
		)
		(pad "E15" smd circle
			(at -0.40005 -8.400034)
			(size 0.3556 0.3556)
			(layers "F.Cu" "F.Mask" "F.Paste")
			(net "P1V8_C")
		)
		(pad "E16" smd circle
			(at 0.40005 -8.400034)
			(size 0.3556 0.3556)
			(layers "F.Cu" "F.Mask" "F.Paste")
			(net "GND")
		)
		(pad "E17" smd circle
			(at 1.199896 -8.400034)
			(size 0.3556 0.3556)
			(layers "F.Cu" "F.Mask" "F.Paste")
			(net "P1V8_C")
		)
		(pad "E18" smd circle
			(at 1.999996 -8.400034)
			(size 0.3556 0.3556)
			(layers "F.Cu" "F.Mask" "F.Paste")
			(net "GND")
		)
		(pad "E19" smd circle
			(at 2.800096 -8.400034)
			(size 0.3556 0.3556)
			(layers "F.Cu" "F.Mask" "F.Paste")
			(net "P1V8_C")
		)
		(pad "E20" smd circle
			(at 3.599942 -8.400034)
			(size 0.3556 0.3556)
			(layers "F.Cu" "F.Mask" "F.Paste")
			(net "GND")
		)
		(pad "E21" smd circle
			(at 4.400042 -8.400034)
			(size 0.3556 0.3556)
			(layers "F.Cu" "F.Mask" "F.Paste")
			(net "P1V8_C")
		)
		(pad "E22" smd circle
			(at 5.199888 -8.400034)
			(size 0.3556 0.3556)
			(layers "F.Cu" "F.Mask" "F.Paste")
			(net "GND")
		)
		(pad "E23" smd circle
			(at 5.999988 -8.400034)
			(size 0.3556 0.3556)
			(layers "F.Cu" "F.Mask" "F.Paste")
			(net "P1V8_C")
		)
		(pad "E24" smd circle
			(at 6.800088 -8.400034)
			(size 0.3556 0.3556)
			(layers "F.Cu" "F.Mask" "F.Paste")
			(net "GND")
		)
		(pad "E25" smd circle
			(at 7.599934 -8.400034)
			(size 0.3556 0.3556)
			(layers "F.Cu" "F.Mask" "F.Paste")
			(net "P1V8_C")
		)
		(pad "E26" smd circle
			(at 8.400034 -8.400034)
			(size 0.3556 0.3556)
			(layers "F.Cu" "F.Mask" "F.Paste")
			(net "GND")
		)
		(pad "E27" smd circle
			(at 9.19988 -8.400034)
			(size 0.3556 0.3556)
			(layers "F.Cu" "F.Mask" "F.Paste")
			(net "P1V8_C")
		)
		(pad "E28" smd circle
			(at 9.99998 -8.400034)
			(size 0.3556 0.3556)
			(layers "F.Cu" "F.Mask" "F.Paste")
			(net "XM_ADDR_12")
		)
		(pad "E29" smd circle
			(at 10.80008 -8.400034)
			(size 0.3556 0.3556)
			(layers "F.Cu" "F.Mask" "F.Paste")
			(net "XM_DATA_14")
		)
		(pad "E30" smd circle
			(at 11.599926 -8.400034)
			(size 0.3556 0.3556)
			(layers "F.Cu" "F.Mask" "F.Paste")
			(net "XM_ADDR_14")
		)
		(pad "F1" smd circle
			(at -11.599926 -7.599934)
			(size 0.3556 0.3556)
			(layers "F.Cu" "F.Mask" "F.Paste")
			(net "Net_1199")
		)
		(pad "F2" smd circle
			(at -10.80008 -7.599934)
			(size 0.3556 0.3556)
			(layers "F.Cu" "F.Mask" "F.Paste")
			(net "Net_1174")
		)
		(pad "F3" smd circle
			(at -9.99998 -7.599934)
			(size 0.3556 0.3556)
			(layers "F.Cu" "F.Mask" "F.Paste")
			(net "Net_1175")
		)
		(pad "F4" smd circle
			(at -9.19988 -7.599934)
			(size 0.3556 0.3556)
			(layers "F.Cu" "F.Mask" "F.Paste")
			(net "P1V8_C")
		)
		(pad "F5" smd circle
			(at -8.400034 -7.599934)
			(size 0.3556 0.3556)
			(layers "F.Cu" "F.Mask" "F.Paste")
			(net "GND")
		)
		(pad "F6" smd circle
			(at -7.599934 -7.599934)
			(size 0.3556 0.3556)
			(layers "F.Cu" "F.Mask" "F.Paste")
			(net "Net_1176")
		)
		(pad "F7" smd circle
			(at -6.800088 -7.599934)
			(size 0.3556 0.3556)
			(layers "F.Cu" "F.Mask" "F.Paste")
			(net "Net_1177")
		)
		(pad "F8" smd circle
			(at -5.999988 -7.599934)
			(size 0.3556 0.3556)
			(layers "F.Cu" "F.Mask" "F.Paste")
			(net "Net_1178")
		)
		(pad "F9" smd circle
			(at -5.199888 -7.599934)
			(size 0.3556 0.3556)
			(layers "F.Cu" "F.Mask" "F.Paste")
			(net "Net_1179")
		)
		(pad "F10" smd circle
			(at -4.400042 -7.599934)
			(size 0.3556 0.3556)
			(layers "F.Cu" "F.Mask" "F.Paste")
			(net "Net_1180")
		)
		(pad "F11" smd circle
			(at -3.599942 -7.599934)
			(size 0.3556 0.3556)
			(layers "F.Cu" "F.Mask" "F.Paste")
			(net "GND")
		)
		(pad "F12" smd circle
			(at -2.800096 -7.599934)
			(size 0.3556 0.3556)
			(layers "F.Cu" "F.Mask" "F.Paste")
			(net "GND")
		)
		(pad "F13" smd circle
			(at -1.999996 -7.599934)
			(size 0.3556 0.3556)
			(layers "F.Cu" "F.Mask" "F.Paste")
			(net "GND")
		)
		(pad "F14" smd circle
			(at -1.199896 -7.599934)
			(size 0.3556 0.3556)
			(layers "F.Cu" "F.Mask" "F.Paste")
			(net "GND")
		)
		(pad "F15" smd circle
			(at -0.40005 -7.599934)
			(size 0.3556 0.3556)
			(layers "F.Cu" "F.Mask" "F.Paste")
			(net "GND")
		)
		(pad "F16" smd circle
			(at 0.40005 -7.599934)
			(size 0.3556 0.3556)
			(layers "F.Cu" "F.Mask" "F.Paste")
			(net "GND")
		)
		(pad "F17" smd circle
			(at 1.199896 -7.599934)
			(size 0.3556 0.3556)
			(layers "F.Cu" "F.Mask" "F.Paste")
			(net "GND")
		)
		(pad "F18" smd circle
			(at 1.999996 -7.599934)
			(size 0.3556 0.3556)
			(layers "F.Cu" "F.Mask" "F.Paste")
			(net "GND")
		)
		(pad "F19" smd circle
			(at 2.800096 -7.599934)
			(size 0.3556 0.3556)
			(layers "F.Cu" "F.Mask" "F.Paste")
			(net "GND")
		)
		(pad "F20" smd circle
			(at 3.599942 -7.599934)
			(size 0.3556 0.3556)
			(layers "F.Cu" "F.Mask" "F.Paste")
			(net "GND")
		)
		(pad "F21" smd circle
			(at 4.400042 -7.599934)
			(size 0.3556 0.3556)
			(layers "F.Cu" "F.Mask" "F.Paste")
			(net "GND")
		)
		(pad "F22" smd circle
			(at 5.199888 -7.599934)
			(size 0.3556 0.3556)
			(layers "F.Cu" "F.Mask" "F.Paste")
			(net "GND")
		)
		(pad "F23" smd circle
			(at 5.999988 -7.599934)
			(size 0.3556 0.3556)
			(layers "F.Cu" "F.Mask" "F.Paste")
			(net "GND")
		)
		(pad "F24" smd circle
			(at 6.800088 -7.599934)
			(size 0.3556 0.3556)
			(layers "F.Cu" "F.Mask" "F.Paste")
			(net "GND")
		)
		(pad "F25" smd circle
			(at 7.599934 -7.599934)
			(size 0.3556 0.3556)
			(layers "F.Cu" "F.Mask" "F.Paste")
			(net "GND")
		)
		(pad "F26" smd circle
			(at 8.400034 -7.599934)
			(size 0.3556 0.3556)
			(layers "F.Cu" "F.Mask" "F.Paste")
			(net "P1V8_C")
		)
		(pad "F27" smd circle
			(at 9.19988 -7.599934)
			(size 0.3556 0.3556)
			(layers "F.Cu" "F.Mask" "F.Paste")
			(net "GND")
		)
		(pad "F28" smd circle
			(at 9.99998 -7.599934)
			(size 0.3556 0.3556)
			(layers "F.Cu" "F.Mask" "F.Paste")
			(net "XM_ADDR_19")
		)
		(pad "F29" smd circle
			(at 10.80008 -7.599934)
			(size 0.3556 0.3556)
			(layers "F.Cu" "F.Mask" "F.Paste")
			(net "XM_ADDR_16")
		)
		(pad "F30" smd circle
			(at 11.599926 -7.599934)
			(size 0.3556 0.3556)
			(layers "F.Cu" "F.Mask" "F.Paste")
			(net "XM_ADDR_20")
		)
		(pad "G1" smd circle
			(at -11.599926 -6.800088)
			(size 0.3556 0.3556)
			(layers "F.Cu" "F.Mask" "F.Paste")
			(net "Net_1200")
		)
		(pad "G2" smd circle
			(at -10.80008 -6.800088)
			(size 0.3556 0.3556)
			(layers "F.Cu" "F.Mask" "F.Paste")
			(net "Net_1181")
		)
		(pad "G3" smd circle
			(at -9.99998 -6.800088)
			(size 0.3556 0.3556)
			(layers "F.Cu" "F.Mask" "F.Paste")
			(net "Net_1182")
		)
		(pad "G4" smd circle
			(at -9.19988 -6.800088)
			(size 0.3556 0.3556)
			(layers "F.Cu" "F.Mask" "F.Paste")
			(net "GND")
		)
		(pad "G5" smd circle
			(at -8.400034 -6.800088)
			(size 0.3556 0.3556)
			(layers "F.Cu" "F.Mask" "F.Paste")
			(net "P1V8_C")
		)
		(pad "G6" smd circle
			(at -7.599934 -6.800088)
			(size 0.3556 0.3556)
			(layers "F.Cu" "F.Mask" "F.Paste")
			(net "Net_1183")
		)
		(pad "G7" smd circle
			(at -6.800088 -6.800088)
			(size 0.3556 0.3556)
			(layers "F.Cu" "F.Mask" "F.Paste")
			(net "GND")
		)
		(pad "G8" smd circle
			(at -5.999988 -6.800088)
			(size 0.3556 0.3556)
			(layers "F.Cu" "F.Mask" "F.Paste")
			(net "GND")
		)
		(pad "G9" smd circle
			(at -5.199888 -6.800088)
			(size 0.3556 0.3556)
			(layers "F.Cu" "F.Mask" "F.Paste")
			(net "GND")
		)
		(pad "G10" smd circle
			(at -4.400042 -6.800088)
			(size 0.3556 0.3556)
			(layers "F.Cu" "F.Mask" "F.Paste")
			(net "GND")
		)
		(pad "G11" smd circle
			(at -3.599942 -6.800088)
			(size 0.3556 0.3556)
			(layers "F.Cu" "F.Mask" "F.Paste")
			(net "GND")
		)
		(pad "G12" smd circle
			(at -2.800096 -6.800088)
			(size 0.3556 0.3556)
			(layers "F.Cu" "F.Mask" "F.Paste")
			(net "GND")
		)
		(pad "G13" smd circle
			(at -1.999996 -6.800088)
			(size 0.3556 0.3556)
			(layers "F.Cu" "F.Mask" "F.Paste")
			(net "GND")
		)
		(pad "G14" smd circle
			(at -1.199896 -6.800088)
			(size 0.3556 0.3556)
			(layers "F.Cu" "F.Mask" "F.Paste")
			(net "GND")
		)
		(pad "G15" smd circle
			(at -0.40005 -6.800088)
			(size 0.3556 0.3556)
			(layers "F.Cu" "F.Mask" "F.Paste")
			(net "GND")
		)
		(pad "G16" smd circle
			(at 0.40005 -6.800088)
			(size 0.3556 0.3556)
			(layers "F.Cu" "F.Mask" "F.Paste")
			(net "GND")
		)
		(pad "G17" smd circle
			(at 1.199896 -6.800088)
			(size 0.3556 0.3556)
			(layers "F.Cu" "F.Mask" "F.Paste")
			(net "GND")
		)
		(pad "G18" smd circle
			(at 1.999996 -6.800088)
			(size 0.3556 0.3556)
			(layers "F.Cu" "F.Mask" "F.Paste")
			(net "GND")
		)
		(pad "G19" smd circle
			(at 2.800096 -6.800088)
			(size 0.3556 0.3556)
			(layers "F.Cu" "F.Mask" "F.Paste")
			(net "GND")
		)
		(pad "G20" smd circle
			(at 3.599942 -6.800088)
			(size 0.3556 0.3556)
			(layers "F.Cu" "F.Mask" "F.Paste")
			(net "GND")
		)
		(pad "G21" smd circle
			(at 4.400042 -6.800088)
			(size 0.3556 0.3556)
			(layers "F.Cu" "F.Mask" "F.Paste")
			(net "GND")
		)
		(pad "G22" smd circle
			(at 5.199888 -6.800088)
			(size 0.3556 0.3556)
			(layers "F.Cu" "F.Mask" "F.Paste")
			(net "GND")
		)
		(pad "G23" smd circle
			(at 5.999988 -6.800088)
			(size 0.3556 0.3556)
			(layers "F.Cu" "F.Mask" "F.Paste")
			(net "GND")
		)
		(pad "G24" smd circle
			(at 6.800088 -6.800088)
			(size 0.3556 0.3556)
			(layers "F.Cu" "F.Mask" "F.Paste")
			(net "GND")
		)
		(pad "G25" smd circle
			(at 7.599934 -6.800088)
			(size 0.3556 0.3556)
			(layers "F.Cu" "F.Mask" "F.Paste")
			(net "GND")
		)
		(pad "G26" smd circle
			(at 8.400034 -6.800088)
			(size 0.3556 0.3556)
			(layers "F.Cu" "F.Mask" "F.Paste")
			(net "GND")
		)
		(pad "G27" smd circle
			(at 9.19988 -6.800088)
			(size 0.3556 0.3556)
			(layers "F.Cu" "F.Mask" "F.Paste")
			(net "P1V8_C")
		)
		(pad "G28" smd circle
			(at 9.99998 -6.800088)
			(size 0.3556 0.3556)
			(layers "F.Cu" "F.Mask" "F.Paste")
			(net "XM_ADDR_15")
		)
		(pad "G29" smd circle
			(at 10.80008 -6.800088)
			(size 0.3556 0.3556)
			(layers "F.Cu" "F.Mask" "F.Paste")
			(net "XM_ADDR_21")
		)
		(pad "G30" smd circle
			(at 11.599926 -6.800088)
			(size 0.3556 0.3556)
			(layers "F.Cu" "F.Mask" "F.Paste")
			(net "XM_DATA_13")
		)
		(pad "H1" smd circle
			(at -11.599926 -5.999988)
			(size 0.3556 0.3556)
			(layers "F.Cu" "F.Mask" "F.Paste")
			(net "GND")
		)
		(pad "H2" smd circle
			(at -10.80008 -5.999988)
			(size 0.3556 0.3556)
			(layers "F.Cu" "F.Mask" "F.Paste")
			(net "Net_1184")
		)
		(pad "H3" smd circle
			(at -9.99998 -5.999988)
			(size 0.3556 0.3556)
			(layers "F.Cu" "F.Mask" "F.Paste")
			(net "Net_1185")
		)
		(pad "H4" smd circle
			(at -9.19988 -5.999988)
			(size 0.3556 0.3556)
			(layers "F.Cu" "F.Mask" "F.Paste")
			(net "P1V8_C")
		)
		(pad "H5" smd circle
			(at -8.400034 -5.999988)
			(size 0.3556 0.3556)
			(layers "F.Cu" "F.Mask" "F.Paste")
			(net "GND")
		)
		(pad "H6" smd circle
			(at -7.599934 -5.999988)
			(size 0.3556 0.3556)
			(layers "F.Cu" "F.Mask" "F.Paste")
			(net "Net_1186")
		)
		(pad "H7" smd circle
			(at -6.800088 -5.999988)
			(size 0.3556 0.3556)
			(layers "F.Cu" "F.Mask" "F.Paste")
			(net "GND")
		)
		(pad "H8" smd circle
			(at -5.999988 -5.999988)
			(size 0.3556 0.3556)
			(layers "F.Cu" "F.Mask" "F.Paste")
			(net "GND")
		)
		(pad "H9" smd circle
			(at -5.199888 -5.999988)
			(size 0.3556 0.3556)
			(layers "F.Cu" "F.Mask" "F.Paste")
			(net "GND")
		)
		(pad "H10" smd circle
			(at -4.400042 -5.999988)
			(size 0.3556 0.3556)
			(layers "F.Cu" "F.Mask" "F.Paste")
			(net "GND")
		)
		(pad "H11" smd circle
			(at -3.599942 -5.999988)
			(size 0.3556 0.3556)
			(layers "F.Cu" "F.Mask" "F.Paste")
			(net "GND")
		)
		(pad "H12" smd circle
			(at -2.800096 -5.999988)
			(size 0.3556 0.3556)
			(layers "F.Cu" "F.Mask" "F.Paste")
			(net "GND")
		)
		(pad "H13" smd circle
			(at -1.999996 -5.999988)
			(size 0.3556 0.3556)
			(layers "F.Cu" "F.Mask" "F.Paste")
			(net "GND")
		)
		(pad "H14" smd circle
			(at -1.199896 -5.999988)
			(size 0.3556 0.3556)
			(layers "F.Cu" "F.Mask" "F.Paste")
			(net "GND")
		)
		(pad "H15" smd circle
			(at -0.40005 -5.999988)
			(size 0.3556 0.3556)
			(layers "F.Cu" "F.Mask" "F.Paste")
			(net "GND")
		)
		(pad "H16" smd circle
			(at 0.40005 -5.999988)
			(size 0.3556 0.3556)
			(layers "F.Cu" "F.Mask" "F.Paste")
			(net "GND")
		)
		(pad "H17" smd circle
			(at 1.199896 -5.999988)
			(size 0.3556 0.3556)
			(layers "F.Cu" "F.Mask" "F.Paste")
			(net "GND")
		)
		(pad "H18" smd circle
			(at 1.999996 -5.999988)
			(size 0.3556 0.3556)
			(layers "F.Cu" "F.Mask" "F.Paste")
			(net "GND")
		)
		(pad "H19" smd circle
			(at 2.800096 -5.999988)
			(size 0.3556 0.3556)
			(layers "F.Cu" "F.Mask" "F.Paste")
			(net "GND")
		)
		(pad "H20" smd circle
			(at 3.599942 -5.999988)
			(size 0.3556 0.3556)
			(layers "F.Cu" "F.Mask" "F.Paste")
			(net "GND")
		)
		(pad "H21" smd circle
			(at 4.400042 -5.999988)
			(size 0.3556 0.3556)
			(layers "F.Cu" "F.Mask" "F.Paste")
			(net "GND")
		)
		(pad "H22" smd circle
			(at 5.199888 -5.999988)
			(size 0.3556 0.3556)
			(layers "F.Cu" "F.Mask" "F.Paste")
			(net "GND")
		)
		(pad "H23" smd circle
			(at 5.999988 -5.999988)
			(size 0.3556 0.3556)
			(layers "F.Cu" "F.Mask" "F.Paste")
			(net "GND")
		)
		(pad "H24" smd circle
			(at 6.800088 -5.999988)
			(size 0.3556 0.3556)
			(layers "F.Cu" "F.Mask" "F.Paste")
			(net "GND")
		)
		(pad "H25" smd circle
			(at 7.599934 -5.999988)
			(size 0.3556 0.3556)
			(layers "F.Cu" "F.Mask" "F.Paste")
			(net "GND")
		)
		(pad "H26" smd circle
			(at 8.400034 -5.999988)
			(size 0.3556 0.3556)
			(layers "F.Cu" "F.Mask" "F.Paste")
			(net "P1V8_C")
		)
		(pad "H27" smd circle
			(at 9.19988 -5.999988)
			(size 0.3556 0.3556)
			(layers "F.Cu" "F.Mask" "F.Paste")
			(net "GND")
		)
		(pad "H28" smd circle
			(at 9.99998 -5.999988)
			(size 0.3556 0.3556)
			(layers "F.Cu" "F.Mask" "F.Paste")
			(net "XM_DATA_0")
		)
		(pad "H29" smd circle
			(at 10.80008 -5.999988)
			(size 0.3556 0.3556)
			(layers "F.Cu" "F.Mask" "F.Paste")
			(net "XM_ADDR_25")
		)
		(pad "H30" smd circle
			(at 11.599926 -5.999988)
			(size 0.3556 0.3556)
			(layers "F.Cu" "F.Mask" "F.Paste")
			(net "XM_ADDR_18")
		)
		(pad "J1" smd circle
			(at -11.599926 -5.199888)
			(size 0.3556 0.3556)
			(layers "F.Cu" "F.Mask" "F.Paste")
			(net "Net_1201")
		)
		(pad "J2" smd circle
			(at -10.80008 -5.199888)
			(size 0.3556 0.3556)
			(layers "F.Cu" "F.Mask" "F.Paste")
			(net "Net_1187")
		)
		(pad "J3" smd circle
			(at -9.99998 -5.199888)
			(size 0.3556 0.3556)
			(layers "F.Cu" "F.Mask" "F.Paste")
			(net "Net_1188")
		)
		(pad "J4" smd circle
			(at -9.19988 -5.199888)
			(size 0.3556 0.3556)
			(layers "F.Cu" "F.Mask" "F.Paste")
			(net "GND")
		)
		(pad "J5" smd circle
			(at -8.400034 -5.199888)
			(size 0.3556 0.3556)
			(layers "F.Cu" "F.Mask" "F.Paste")
			(net "P1V8_C")
		)
		(pad "J6" smd circle
			(at -7.599934 -5.199888)
			(size 0.3556 0.3556)
			(layers "F.Cu" "F.Mask" "F.Paste")
			(net "Net_1189")
		)
		(pad "J7" smd circle
			(at -6.800088 -5.199888)
			(size 0.3556 0.3556)
			(layers "F.Cu" "F.Mask" "F.Paste")
			(net "GND")
		)
		(pad "J8" smd circle
			(at -5.999988 -5.199888)
			(size 0.3556 0.3556)
			(layers "F.Cu" "F.Mask" "F.Paste")
			(net "GND")
		)
		(pad "J9" smd circle
			(at -5.199888 -5.199888)
			(size 0.3556 0.3556)
			(layers "F.Cu" "F.Mask" "F.Paste")
			(net "GND")
		)
		(pad "J10" smd circle
			(at -4.400042 -5.199888)
			(size 0.3556 0.3556)
			(layers "F.Cu" "F.Mask" "F.Paste")
			(net "GND")
		)
		(pad "J11" smd circle
			(at -3.599942 -5.199888)
			(size 0.3556 0.3556)
			(layers "F.Cu" "F.Mask" "F.Paste")
			(net "GND")
		)
		(pad "J12" smd circle
			(at -2.800096 -5.199888)
			(size 0.3556 0.3556)
			(layers "F.Cu" "F.Mask" "F.Paste")
			(net "P0V975")
		)
		(pad "J13" smd circle
			(at -1.999996 -5.199888)
			(size 0.3556 0.3556)
			(layers "F.Cu" "F.Mask" "F.Paste")
			(net "GND")
		)
		(pad "J14" smd circle
			(at -1.199896 -5.199888)
			(size 0.3556 0.3556)
			(layers "F.Cu" "F.Mask" "F.Paste")
			(net "GND")
		)
		(pad "J15" smd circle
			(at -0.40005 -5.199888)
			(size 0.3556 0.3556)
			(layers "F.Cu" "F.Mask" "F.Paste")
			(net "GND")
		)
		(pad "J16" smd circle
			(at 0.40005 -5.199888)
			(size 0.3556 0.3556)
			(layers "F.Cu" "F.Mask" "F.Paste")
			(net "GND")
		)
		(pad "J17" smd circle
			(at 1.199896 -5.199888)
			(size 0.3556 0.3556)
			(layers "F.Cu" "F.Mask" "F.Paste")
			(net "GND")
		)
		(pad "J18" smd circle
			(at 1.999996 -5.199888)
			(size 0.3556 0.3556)
			(layers "F.Cu" "F.Mask" "F.Paste")
			(net "GND")
		)
		(pad "J19" smd circle
			(at 2.800096 -5.199888)
			(size 0.3556 0.3556)
			(layers "F.Cu" "F.Mask" "F.Paste")
			(net "GND")
		)
		(pad "J20" smd circle
			(at 3.599942 -5.199888)
			(size 0.3556 0.3556)
			(layers "F.Cu" "F.Mask" "F.Paste")
			(net "GND")
		)
		(pad "J21" smd circle
			(at 4.400042 -5.199888)
			(size 0.3556 0.3556)
			(layers "F.Cu" "F.Mask" "F.Paste")
			(net "GND")
		)
		(pad "J22" smd circle
			(at 5.199888 -5.199888)
			(size 0.3556 0.3556)
			(layers "F.Cu" "F.Mask" "F.Paste")
			(net "GND")
		)
		(pad "J23" smd circle
			(at 5.999988 -5.199888)
			(size 0.3556 0.3556)
			(layers "F.Cu" "F.Mask" "F.Paste")
			(net "GND")
		)
		(pad "J24" smd circle
			(at 6.800088 -5.199888)
			(size 0.3556 0.3556)
			(layers "F.Cu" "F.Mask" "F.Paste")
			(net "GND")
		)
		(pad "J25" smd circle
			(at 7.599934 -5.199888)
			(size 0.3556 0.3556)
			(layers "F.Cu" "F.Mask" "F.Paste")
			(net "GND")
		)
		(pad "J26" smd circle
			(at 8.400034 -5.199888)
			(size 0.3556 0.3556)
			(layers "F.Cu" "F.Mask" "F.Paste")
			(net "GND")
		)
		(pad "J27" smd circle
			(at 9.19988 -5.199888)
			(size 0.3556 0.3556)
			(layers "F.Cu" "F.Mask" "F.Paste")
			(net "P1V8_C")
		)
		(pad "J28" smd circle
			(at 9.99998 -5.199888)
			(size 0.3556 0.3556)
			(layers "F.Cu" "F.Mask" "F.Paste")
			(net "XM_DATA_12")
		)
		(pad "J29" smd circle
			(at 10.80008 -5.199888)
			(size 0.3556 0.3556)
			(layers "F.Cu" "F.Mask" "F.Paste")
			(net "XM_ADDR_22")
		)
		(pad "J30" smd circle
			(at 11.599926 -5.199888)
			(size 0.3556 0.3556)
			(layers "F.Cu" "F.Mask" "F.Paste")
			(net "XM_ADDR_24")
		)
		(pad "K1" smd circle
			(at -11.599926 -4.400042)
			(size 0.3556 0.3556)
			(layers "F.Cu" "F.Mask" "F.Paste")
			(net "SIO_LOAD_1")
		)
		(pad "K2" smd circle
			(at -10.80008 -4.400042)
			(size 0.3556 0.3556)
			(layers "F.Cu" "F.Mask" "F.Paste")
			(net "SIO_DOUT_0")
		)
		(pad "K3" smd circle
			(at -9.99998 -4.400042)
			(size 0.3556 0.3556)
			(layers "F.Cu" "F.Mask" "F.Paste")
			(net "GND")
		)
		(pad "K4" smd circle
			(at -9.19988 -4.400042)
			(size 0.3556 0.3556)
			(layers "F.Cu" "F.Mask" "F.Paste")
			(net "P1V8_C")
		)
		(pad "K5" smd circle
			(at -8.400034 -4.400042)
			(size 0.3556 0.3556)
			(layers "F.Cu" "F.Mask" "F.Paste")
			(net "GND")
		)
		(pad "K6" smd circle
			(at -7.599934 -4.400042)
			(size 0.3556 0.3556)
			(layers "F.Cu" "F.Mask" "F.Paste")
			(net "Net_1190")
		)
		(pad "K7" smd circle
			(at -6.800088 -4.400042)
			(size 0.3556 0.3556)
			(layers "F.Cu" "F.Mask" "F.Paste")
			(net "GND")
		)
		(pad "K8" smd circle
			(at -5.999988 -4.400042)
			(size 0.3556 0.3556)
			(layers "F.Cu" "F.Mask" "F.Paste")
			(net "GND")
		)
		(pad "K9" smd circle
			(at -5.199888 -4.400042)
			(size 0.3556 0.3556)
			(layers "F.Cu" "F.Mask" "F.Paste")
			(net "GND")
		)
		(pad "K10" smd circle
			(at -4.400042 -4.400042)
			(size 0.3556 0.3556)
			(layers "F.Cu" "F.Mask" "F.Paste")
			(net "GND")
		)
		(pad "K11" smd circle
			(at -3.599942 -4.400042)
			(size 0.3556 0.3556)
			(layers "F.Cu" "F.Mask" "F.Paste")
			(net "GND")
		)
		(pad "K12" smd circle
			(at -2.800096 -4.400042)
			(size 0.3556 0.3556)
			(layers "F.Cu" "F.Mask" "F.Paste")
			(net "GND")
		)
		(pad "K13" smd circle
			(at -1.999996 -4.400042)
			(size 0.3556 0.3556)
			(layers "F.Cu" "F.Mask" "F.Paste")
			(net "P0V975")
		)
		(pad "K14" smd circle
			(at -1.199896 -4.400042)
			(size 0.3556 0.3556)
			(layers "F.Cu" "F.Mask" "F.Paste")
			(net "GND")
		)
		(pad "K15" smd circle
			(at -0.40005 -4.400042)
			(size 0.3556 0.3556)
			(layers "F.Cu" "F.Mask" "F.Paste")
			(net "GND")
		)
		(pad "K16" smd circle
			(at 0.40005 -4.400042)
			(size 0.3556 0.3556)
			(layers "F.Cu" "F.Mask" "F.Paste")
			(net "GND")
		)
		(pad "K17" smd circle
			(at 1.199896 -4.400042)
			(size 0.3556 0.3556)
			(layers "F.Cu" "F.Mask" "F.Paste")
			(net "GND")
		)
		(pad "K18" smd circle
			(at 1.999996 -4.400042)
			(size 0.3556 0.3556)
			(layers "F.Cu" "F.Mask" "F.Paste")
			(net "GND")
		)
		(pad "K19" smd circle
			(at 2.800096 -4.400042)
			(size 0.3556 0.3556)
			(layers "F.Cu" "F.Mask" "F.Paste")
			(net "GND")
		)
		(pad "K20" smd circle
			(at 3.599942 -4.400042)
			(size 0.3556 0.3556)
			(layers "F.Cu" "F.Mask" "F.Paste")
			(net "GND")
		)
		(pad "K21" smd circle
			(at 4.400042 -4.400042)
			(size 0.3556 0.3556)
			(layers "F.Cu" "F.Mask" "F.Paste")
			(net "P0V975")
		)
		(pad "K22" smd circle
			(at 5.199888 -4.400042)
			(size 0.3556 0.3556)
			(layers "F.Cu" "F.Mask" "F.Paste")
			(net "GND")
		)
		(pad "K23" smd circle
			(at 5.999988 -4.400042)
			(size 0.3556 0.3556)
			(layers "F.Cu" "F.Mask" "F.Paste")
			(net "GND")
		)
		(pad "K24" smd circle
			(at 6.800088 -4.400042)
			(size 0.3556 0.3556)
			(layers "F.Cu" "F.Mask" "F.Paste")
			(net "GND")
		)
		(pad "K25" smd circle
			(at 7.599934 -4.400042)
			(size 0.3556 0.3556)
			(layers "F.Cu" "F.Mask" "F.Paste")
			(net "GND")
		)
		(pad "K26" smd circle
			(at 8.400034 -4.400042)
			(size 0.3556 0.3556)
			(layers "F.Cu" "F.Mask" "F.Paste")
			(net "P1V8_C")
		)
		(pad "K27" smd circle
			(at 9.19988 -4.400042)
			(size 0.3556 0.3556)
			(layers "F.Cu" "F.Mask" "F.Paste")
			(net "GND")
		)
		(pad "K28" smd circle
			(at 9.99998 -4.400042)
			(size 0.3556 0.3556)
			(layers "F.Cu" "F.Mask" "F.Paste")
			(net "XM_DATA_2")
		)
		(pad "K29" smd circle
			(at 10.80008 -4.400042)
			(size 0.3556 0.3556)
			(layers "F.Cu" "F.Mask" "F.Paste")
			(net "XM_ADDR_23")
		)
		(pad "K30" smd circle
			(at 11.599926 -4.400042)
			(size 0.3556 0.3556)
			(layers "F.Cu" "F.Mask" "F.Paste")
			(net "XM_DATA_1")
		)
		(pad "L1" smd circle
			(at -11.599926 -3.599942)
			(size 0.3556 0.3556)
			(layers "F.Cu" "F.Mask" "F.Paste")
			(net "SIO_CLK_1")
		)
		(pad "L2" smd circle
			(at -10.80008 -3.599942)
			(size 0.3556 0.3556)
			(layers "F.Cu" "F.Mask" "F.Paste")
			(net "SIO_DIN_1")
		)
		(pad "L3" smd circle
			(at -9.99998 -3.599942)
			(size 0.3556 0.3556)
			(layers "F.Cu" "F.Mask" "F.Paste")
			(net "Net_1191")
		)
		(pad "L4" smd circle
			(at -9.19988 -3.599942)
			(size 0.3556 0.3556)
			(layers "F.Cu" "F.Mask" "F.Paste")
			(net "GND")
		)
		(pad "L5" smd circle
			(at -8.400034 -3.599942)
			(size 0.3556 0.3556)
			(layers "F.Cu" "F.Mask" "F.Paste")
			(net "P1V8_C")
		)
		(pad "L6" smd circle
			(at -7.599934 -3.599942)
			(size 0.3556 0.3556)
			(layers "F.Cu" "F.Mask" "F.Paste")
			(net "ICE1_TDI")
		)
		(pad "L7" smd circle
			(at -6.800088 -3.599942)
			(size 0.3556 0.3556)
			(layers "F.Cu" "F.Mask" "F.Paste")
			(net "GND")
		)
		(pad "L8" smd circle
			(at -5.999988 -3.599942)
			(size 0.3556 0.3556)
			(layers "F.Cu" "F.Mask" "F.Paste")
			(net "GND")
		)
		(pad "L9" smd circle
			(at -5.199888 -3.599942)
			(size 0.3556 0.3556)
			(layers "F.Cu" "F.Mask" "F.Paste")
			(net "GND")
		)
		(pad "L10" smd circle
			(at -4.400042 -3.599942)
			(size 0.3556 0.3556)
			(layers "F.Cu" "F.Mask" "F.Paste")
			(net "GND")
		)
		(pad "L11" smd circle
			(at -3.599942 -3.599942)
			(size 0.3556 0.3556)
			(layers "F.Cu" "F.Mask" "F.Paste")
			(net "GND")
		)
		(pad "L12" smd circle
			(at -2.800096 -3.599942)
			(size 0.3556 0.3556)
			(layers "F.Cu" "F.Mask" "F.Paste")
			(net "GND")
		)
		(pad "L13" smd circle
			(at -1.999996 -3.599942)
			(size 0.3556 0.3556)
			(layers "F.Cu" "F.Mask" "F.Paste")
			(net "GND")
		)
		(pad "L14" smd circle
			(at -1.199896 -3.599942)
			(size 0.3556 0.3556)
			(layers "F.Cu" "F.Mask" "F.Paste")
			(net "P0V975")
		)
		(pad "L15" smd circle
			(at -0.40005 -3.599942)
			(size 0.3556 0.3556)
			(layers "F.Cu" "F.Mask" "F.Paste")
			(net "GND")
		)
		(pad "L16" smd circle
			(at 0.40005 -3.599942)
			(size 0.3556 0.3556)
			(layers "F.Cu" "F.Mask" "F.Paste")
			(net "P0V975")
		)
		(pad "L17" smd circle
			(at 1.199896 -3.599942)
			(size 0.3556 0.3556)
			(layers "F.Cu" "F.Mask" "F.Paste")
			(net "GND")
		)
		(pad "L18" smd circle
			(at 1.999996 -3.599942)
			(size 0.3556 0.3556)
			(layers "F.Cu" "F.Mask" "F.Paste")
			(net "P0V975")
		)
		(pad "L19" smd circle
			(at 2.800096 -3.599942)
			(size 0.3556 0.3556)
			(layers "F.Cu" "F.Mask" "F.Paste")
			(net "GND")
		)
		(pad "L20" smd circle
			(at 3.599942 -3.599942)
			(size 0.3556 0.3556)
			(layers "F.Cu" "F.Mask" "F.Paste")
			(net "P0V975")
		)
		(pad "L21" smd circle
			(at 4.400042 -3.599942)
			(size 0.3556 0.3556)
			(layers "F.Cu" "F.Mask" "F.Paste")
			(net "GND")
		)
		(pad "L22" smd circle
			(at 5.199888 -3.599942)
			(size 0.3556 0.3556)
			(layers "F.Cu" "F.Mask" "F.Paste")
			(net "VDDIO_15")
		)
		(pad "L23" smd circle
			(at 5.999988 -3.599942)
			(size 0.3556 0.3556)
			(layers "F.Cu" "F.Mask" "F.Paste")
			(net "GND")
		)
		(pad "L24" smd circle
			(at 6.800088 -3.599942)
			(size 0.3556 0.3556)
			(layers "F.Cu" "F.Mask" "F.Paste")
			(net "GND")
		)
		(pad "L25" smd circle
			(at 7.599934 -3.599942)
			(size 0.3556 0.3556)
			(layers "F.Cu" "F.Mask" "F.Paste")
			(net "GND")
		)
		(pad "L26" smd circle
			(at 8.400034 -3.599942)
			(size 0.3556 0.3556)
			(layers "F.Cu" "F.Mask" "F.Paste")
			(net "GND")
		)
		(pad "L27" smd circle
			(at 9.19988 -3.599942)
			(size 0.3556 0.3556)
			(layers "F.Cu" "F.Mask" "F.Paste")
			(net "P1V8_C")
		)
		(pad "L28" smd circle
			(at 9.99998 -3.599942)
			(size 0.3556 0.3556)
			(layers "F.Cu" "F.Mask" "F.Paste")
			(net "GND")
		)
		(pad "L29" smd circle
			(at 10.80008 -3.599942)
			(size 0.3556 0.3556)
			(layers "F.Cu" "F.Mask" "F.Paste")
			(net "XM_DATA_4")
		)
		(pad "L30" smd circle
			(at 11.599926 -3.599942)
			(size 0.3556 0.3556)
			(layers "F.Cu" "F.Mask" "F.Paste")
			(net "XM_DATA_3")
		)
		(pad "M1" smd circle
			(at -11.599926 -2.800096)
			(size 0.3556 0.3556)
			(layers "F.Cu" "F.Mask" "F.Paste")
			(net "SIO_CLK_0")
		)
		(pad "M2" smd circle
			(at -10.80008 -2.800096)
			(size 0.3556 0.3556)
			(layers "F.Cu" "F.Mask" "F.Paste")
			(net "SIO_DOUT_1")
		)
		(pad "M3" smd circle
			(at -9.99998 -2.800096)
			(size 0.3556 0.3556)
			(layers "F.Cu" "F.Mask" "F.Paste")
			(net "SIO_LOAD_0")
		)
		(pad "M4" smd circle
			(at -9.19988 -2.800096)
			(size 0.3556 0.3556)
			(layers "F.Cu" "F.Mask" "F.Paste")
			(net "P1V8_C")
		)
		(pad "M5" smd circle
			(at -8.400034 -2.800096)
			(size 0.3556 0.3556)
			(layers "F.Cu" "F.Mask" "F.Paste")
			(net "GND")
		)
		(pad "M6" smd circle
			(at -7.599934 -2.800096)
			(size 0.3556 0.3556)
			(layers "F.Cu" "F.Mask" "F.Paste")
			(net "ICE_SEL")
		)
		(pad "M7" smd circle
			(at -6.800088 -2.800096)
			(size 0.3556 0.3556)
			(layers "F.Cu" "F.Mask" "F.Paste")
			(net "GND")
		)
		(pad "M8" smd circle
			(at -5.999988 -2.800096)
			(size 0.3556 0.3556)
			(layers "F.Cu" "F.Mask" "F.Paste")
			(net "GND")
		)
		(pad "M9" smd circle
			(at -5.199888 -2.800096)
			(size 0.3556 0.3556)
			(layers "F.Cu" "F.Mask" "F.Paste")
			(net "P1V8_C")
		)
		(pad "M10" smd circle
			(at -4.400042 -2.800096)
			(size 0.3556 0.3556)
			(layers "F.Cu" "F.Mask" "F.Paste")
			(net "GND")
		)
		(pad "M11" smd circle
			(at -3.599942 -2.800096)
			(size 0.3556 0.3556)
			(layers "F.Cu" "F.Mask" "F.Paste")
			(net "P0V975")
		)
		(pad "M12" smd circle
			(at -2.800096 -2.800096)
			(size 0.3556 0.3556)
			(layers "F.Cu" "F.Mask" "F.Paste")
			(net "GND")
		)
		(pad "M13" smd circle
			(at -1.999996 -2.800096)
			(size 0.3556 0.3556)
			(layers "F.Cu" "F.Mask" "F.Paste")
			(net "P0V975")
		)
		(pad "M14" smd circle
			(at -1.199896 -2.800096)
			(size 0.3556 0.3556)
			(layers "F.Cu" "F.Mask" "F.Paste")
			(net "GND")
		)
		(pad "M15" smd circle
			(at -0.40005 -2.800096)
			(size 0.3556 0.3556)
			(layers "F.Cu" "F.Mask" "F.Paste")
			(net "P0V975")
		)
		(pad "M16" smd circle
			(at 0.40005 -2.800096)
			(size 0.3556 0.3556)
			(layers "F.Cu" "F.Mask" "F.Paste")
			(net "GND")
		)
		(pad "M17" smd circle
			(at 1.199896 -2.800096)
			(size 0.3556 0.3556)
			(layers "F.Cu" "F.Mask" "F.Paste")
			(net "P0V975")
		)
		(pad "M18" smd circle
			(at 1.999996 -2.800096)
			(size 0.3556 0.3556)
			(layers "F.Cu" "F.Mask" "F.Paste")
			(net "GND")
		)
		(pad "M19" smd circle
			(at 2.800096 -2.800096)
			(size 0.3556 0.3556)
			(layers "F.Cu" "F.Mask" "F.Paste")
			(net "P0V975")
		)
		(pad "M20" smd circle
			(at 3.599942 -2.800096)
			(size 0.3556 0.3556)
			(layers "F.Cu" "F.Mask" "F.Paste")
			(net "GND")
		)
		(pad "M21" smd circle
			(at 4.400042 -2.800096)
			(size 0.3556 0.3556)
			(layers "F.Cu" "F.Mask" "F.Paste")
			(net "P0V975")
		)
		(pad "M22" smd circle
			(at 5.199888 -2.800096)
			(size 0.3556 0.3556)
			(layers "F.Cu" "F.Mask" "F.Paste")
			(net "GND")
		)
		(pad "M23" smd circle
			(at 5.999988 -2.800096)
			(size 0.3556 0.3556)
			(layers "F.Cu" "F.Mask" "F.Paste")
			(net "GND")
		)
		(pad "M24" smd circle
			(at 6.800088 -2.800096)
			(size 0.3556 0.3556)
			(layers "F.Cu" "F.Mask" "F.Paste")
			(net "GND")
		)
		(pad "M25" smd circle
			(at 7.599934 -2.800096)
			(size 0.3556 0.3556)
			(layers "F.Cu" "F.Mask" "F.Paste")
			(net "GND")
		)
		(pad "M26" smd circle
			(at 8.400034 -2.800096)
			(size 0.3556 0.3556)
			(layers "F.Cu" "F.Mask" "F.Paste")
			(net "GND")
		)
		(pad "M27" smd circle
			(at 9.19988 -2.800096)
			(size 0.3556 0.3556)
			(layers "F.Cu" "F.Mask" "F.Paste")
			(net "GND")
		)
		(pad "M28" smd circle
			(at 9.99998 -2.800096)
			(size 0.3556 0.3556)
			(layers "F.Cu" "F.Mask" "F.Paste")
			(net "GND")
		)
		(pad "M29" smd circle
			(at 10.80008 -2.800096)
			(size 0.3556 0.3556)
			(layers "F.Cu" "F.Mask" "F.Paste")
			(net "GND")
		)
		(pad "M30" smd circle
			(at 11.599926 -2.800096)
			(size 0.3556 0.3556)
			(layers "F.Cu" "F.Mask" "F.Paste")
			(net "GND")
		)
		(pad "N1" smd circle
			(at -11.599926 -1.999996)
			(size 0.3556 0.3556)
			(layers "F.Cu" "F.Mask" "F.Paste")
			(net "GND")
		)
		(pad "N2" smd circle
			(at -10.80008 -1.999996)
			(size 0.3556 0.3556)
			(layers "F.Cu" "F.Mask" "F.Paste")
			(net "GND")
		)
		(pad "N3" smd circle
			(at -9.99998 -1.999996)
			(size 0.3556 0.3556)
			(layers "F.Cu" "F.Mask" "F.Paste")
			(net "P1V8_C")
		)
		(pad "N4" smd circle
			(at -9.19988 -1.999996)
			(size 0.3556 0.3556)
			(layers "F.Cu" "F.Mask" "F.Paste")
			(net "GND")
		)
		(pad "N5" smd circle
			(at -8.400034 -1.999996)
			(size 0.3556 0.3556)
			(layers "F.Cu" "F.Mask" "F.Paste")
			(net "Net_1192")
		)
		(pad "N6" smd circle
			(at -7.599934 -1.999996)
			(size 0.3556 0.3556)
			(layers "F.Cu" "F.Mask" "F.Paste")
			(net "Net_1193")
		)
		(pad "N7" smd circle
			(at -6.800088 -1.999996)
			(size 0.3556 0.3556)
			(layers "F.Cu" "F.Mask" "F.Paste")
			(net "GND")
		)
		(pad "N8" smd circle
			(at -5.999988 -1.999996)
			(size 0.3556 0.3556)
			(layers "F.Cu" "F.Mask" "F.Paste")
			(net "GND")
		)
		(pad "N9" smd circle
			(at -5.199888 -1.999996)
			(size 0.3556 0.3556)
			(layers "F.Cu" "F.Mask" "F.Paste")
			(net "GND")
		)
		(pad "N10" smd circle
			(at -4.400042 -1.999996)
			(size 0.3556 0.3556)
			(layers "F.Cu" "F.Mask" "F.Paste")
			(net "GND")
		)
		(pad "N11" smd circle
			(at -3.599942 -1.999996)
			(size 0.3556 0.3556)
			(layers "F.Cu" "F.Mask" "F.Paste")
			(net "GND")
		)
		(pad "N12" smd circle
			(at -2.800096 -1.999996)
			(size 0.3556 0.3556)
			(layers "F.Cu" "F.Mask" "F.Paste")
			(net "P0V975")
		)
		(pad "N13" smd circle
			(at -1.999996 -1.999996)
			(size 0.3556 0.3556)
			(layers "F.Cu" "F.Mask" "F.Paste")
			(net "GND")
		)
		(pad "N14" smd circle
			(at -1.199896 -1.999996)
			(size 0.3556 0.3556)
			(layers "F.Cu" "F.Mask" "F.Paste")
			(net "P0V975")
		)
		(pad "N15" smd circle
			(at -0.40005 -1.999996)
			(size 0.3556 0.3556)
			(layers "F.Cu" "F.Mask" "F.Paste")
			(net "GND")
		)
		(pad "N16" smd circle
			(at 0.40005 -1.999996)
			(size 0.3556 0.3556)
			(layers "F.Cu" "F.Mask" "F.Paste")
			(net "P0V975")
		)
		(pad "N17" smd circle
			(at 1.199896 -1.999996)
			(size 0.3556 0.3556)
			(layers "F.Cu" "F.Mask" "F.Paste")
			(net "GND")
		)
		(pad "N18" smd circle
			(at 1.999996 -1.999996)
			(size 0.3556 0.3556)
			(layers "F.Cu" "F.Mask" "F.Paste")
			(net "P0V975")
		)
		(pad "N19" smd circle
			(at 2.800096 -1.999996)
			(size 0.3556 0.3556)
			(layers "F.Cu" "F.Mask" "F.Paste")
			(net "GND")
		)
		(pad "N20" smd circle
			(at 3.599942 -1.999996)
			(size 0.3556 0.3556)
			(layers "F.Cu" "F.Mask" "F.Paste")
			(net "P0V975")
		)
		(pad "N21" smd circle
			(at 4.400042 -1.999996)
			(size 0.3556 0.3556)
			(layers "F.Cu" "F.Mask" "F.Paste")
			(net "GND")
		)
		(pad "N22" smd circle
			(at 5.199888 -1.999996)
			(size 0.3556 0.3556)
			(layers "F.Cu" "F.Mask" "F.Paste")
			(net "GND")
		)
		(pad "N23" smd circle
			(at 5.999988 -1.999996)
			(size 0.3556 0.3556)
			(layers "F.Cu" "F.Mask" "F.Paste")
			(net "GND")
		)
		(pad "N24" smd circle
			(at 6.800088 -1.999996)
			(size 0.3556 0.3556)
			(layers "F.Cu" "F.Mask" "F.Paste")
			(net "GND")
		)
		(pad "N25" smd circle
			(at 7.599934 -1.999996)
			(size 0.3556 0.3556)
			(layers "F.Cu" "F.Mask" "F.Paste")
			(net "GND")
		)
		(pad "N26" smd circle
			(at 8.400034 -1.999996)
			(size 0.3556 0.3556)
			(layers "F.Cu" "F.Mask" "F.Paste")
			(net "GND")
		)
		(pad "N27" smd circle
			(at 9.19988 -1.999996)
			(size 0.3556 0.3556)
			(layers "F.Cu" "F.Mask" "F.Paste")
			(net "P1V8_C")
		)
		(pad "N28" smd circle
			(at 9.99998 -1.999996)
			(size 0.3556 0.3556)
			(layers "F.Cu" "F.Mask" "F.Paste")
			(net "IOC_GPIO_32")
		)
		(pad "N29" smd circle
			(at 10.80008 -1.999996)
			(size 0.3556 0.3556)
			(layers "F.Cu" "F.Mask" "F.Paste")
			(net "MEM_CLK_SEL")
		)
		(pad "N30" smd circle
			(at 11.599926 -1.999996)
			(size 0.3556 0.3556)
			(layers "F.Cu" "F.Mask" "F.Paste")
			(net "SBL_SDA")
		)
		(pad "P1" smd circle
			(at -11.599926 -1.199896)
			(size 0.3556 0.3556)
			(layers "F.Cu" "F.Mask" "F.Paste")
			(net "IOC_REF_CLK_P")
		)
		(pad "P2" smd circle
			(at -10.80008 -1.199896)
			(size 0.3556 0.3556)
			(layers "F.Cu" "F.Mask" "F.Paste")
			(net "IOC_REF_CLK_N")
		)
		(pad "P3" smd circle
			(at -9.99998 -1.199896)
			(size 0.3556 0.3556)
			(layers "F.Cu" "F.Mask" "F.Paste")
			(net "GND")
		)
		(pad "P4" smd circle
			(at -9.19988 -1.199896)
			(size 0.3556 0.3556)
			(layers "F.Cu" "F.Mask" "F.Paste")
			(net "P1V8_C")
		)
		(pad "P5" smd circle
			(at -8.400034 -1.199896)
			(size 0.3556 0.3556)
			(layers "F.Cu" "F.Mask" "F.Paste")
			(net "Net_1194")
		)
		(pad "P6" smd circle
			(at -7.599934 -1.199896)
			(size 0.3556 0.3556)
			(layers "F.Cu" "F.Mask" "F.Paste")
			(net "Net_1195")
		)
		(pad "P7" smd circle
			(at -6.800088 -1.199896)
			(size 0.3556 0.3556)
			(layers "F.Cu" "F.Mask" "F.Paste")
			(net "GND")
		)
		(pad "P8" smd circle
			(at -5.999988 -1.199896)
			(size 0.3556 0.3556)
			(layers "F.Cu" "F.Mask" "F.Paste")
			(net "GND")
		)
		(pad "P9" smd circle
			(at -5.199888 -1.199896)
			(size 0.3556 0.3556)
			(layers "F.Cu" "F.Mask" "F.Paste")
			(net "GND")
		)
		(pad "P10" smd circle
			(at -4.400042 -1.199896)
			(size 0.3556 0.3556)
			(layers "F.Cu" "F.Mask" "F.Paste")
			(net "GND")
		)
		(pad "P11" smd circle
			(at -3.599942 -1.199896)
			(size 0.3556 0.3556)
			(layers "F.Cu" "F.Mask" "F.Paste")
			(net "GND")
		)
		(pad "P12" smd circle
			(at -2.800096 -1.199896)
			(size 0.3556 0.3556)
			(layers "F.Cu" "F.Mask" "F.Paste")
			(net "GND")
		)
		(pad "P13" smd circle
			(at -1.999996 -1.199896)
			(size 0.3556 0.3556)
			(layers "F.Cu" "F.Mask" "F.Paste")
			(net "P0V975")
		)
		(pad "P14" smd circle
			(at -1.199896 -1.199896)
			(size 0.3556 0.3556)
			(layers "F.Cu" "F.Mask" "F.Paste")
			(net "GND")
		)
		(pad "P15" smd circle
			(at -0.40005 -1.199896)
			(size 0.3556 0.3556)
			(layers "F.Cu" "F.Mask" "F.Paste")
			(net "P0V975")
		)
		(pad "P16" smd circle
			(at 0.40005 -1.199896)
			(size 0.3556 0.3556)
			(layers "F.Cu" "F.Mask" "F.Paste")
			(net "GND")
		)
		(pad "P17" smd circle
			(at 1.199896 -1.199896)
			(size 0.3556 0.3556)
			(layers "F.Cu" "F.Mask" "F.Paste")
			(net "P0V975")
		)
		(pad "P18" smd circle
			(at 1.999996 -1.199896)
			(size 0.3556 0.3556)
			(layers "F.Cu" "F.Mask" "F.Paste")
			(net "GND")
		)
		(pad "P19" smd circle
			(at 2.800096 -1.199896)
			(size 0.3556 0.3556)
			(layers "F.Cu" "F.Mask" "F.Paste")
			(net "P0V975")
		)
		(pad "P20" smd circle
			(at 3.599942 -1.199896)
			(size 0.3556 0.3556)
			(layers "F.Cu" "F.Mask" "F.Paste")
			(net "GND")
		)
		(pad "P21" smd circle
			(at 4.400042 -1.199896)
			(size 0.3556 0.3556)
			(layers "F.Cu" "F.Mask" "F.Paste")
			(net "P0V975")
		)
		(pad "P22" smd circle
			(at 5.199888 -1.199896)
			(size 0.3556 0.3556)
			(layers "F.Cu" "F.Mask" "F.Paste")
			(net "GND")
		)
		(pad "P23" smd circle
			(at 5.999988 -1.199896)
			(size 0.3556 0.3556)
			(layers "F.Cu" "F.Mask" "F.Paste")
			(net "GND")
		)
		(pad "P24" smd circle
			(at 6.800088 -1.199896)
			(size 0.3556 0.3556)
			(layers "F.Cu" "F.Mask" "F.Paste")
			(net "GND")
		)
		(pad "P25" smd circle
			(at 7.599934 -1.199896)
			(size 0.3556 0.3556)
			(layers "F.Cu" "F.Mask" "F.Paste")
			(net "GND")
		)
		(pad "P26" smd circle
			(at 8.400034 -1.199896)
			(size 0.3556 0.3556)
			(layers "F.Cu" "F.Mask" "F.Paste")
			(net "P1V8_C")
		)
		(pad "P27" smd circle
			(at 9.19988 -1.199896)
			(size 0.3556 0.3556)
			(layers "F.Cu" "F.Mask" "F.Paste")
			(net "GND")
		)
		(pad "P28" smd circle
			(at 9.99998 -1.199896)
			(size 0.3556 0.3556)
			(layers "F.Cu" "F.Mask" "F.Paste")
			(net "I2C_IOC_3_SCL")
		)
		(pad "P29" smd circle
			(at 10.80008 -1.199896)
			(size 0.3556 0.3556)
			(layers "F.Cu" "F.Mask" "F.Paste")
			(net "IOC_CLK_SEL0")
		)
		(pad "P30" smd circle
			(at 11.599926 -1.199896)
			(size 0.3556 0.3556)
			(layers "F.Cu" "F.Mask" "F.Paste")
			(net "I2C_IOC_1_SCL")
		)
		(pad "R1" smd circle
			(at -11.599926 -0.40005)
			(size 0.3556 0.3556)
			(layers "F.Cu" "F.Mask" "F.Paste")
			(net "GND")
		)
		(pad "R2" smd circle
			(at -10.80008 -0.40005)
			(size 0.3556 0.3556)
			(layers "F.Cu" "F.Mask" "F.Paste")
			(net "GND")
		)
		(pad "R3" smd circle
			(at -9.99998 -0.40005)
			(size 0.3556 0.3556)
			(layers "F.Cu" "F.Mask" "F.Paste")
			(net "GND")
		)
		(pad "R4" smd circle
			(at -9.19988 -0.40005)
			(size 0.3556 0.3556)
			(layers "F.Cu" "F.Mask" "F.Paste")
			(net "GND")
		)
		(pad "R5" smd circle
			(at -8.400034 -0.40005)
			(size 0.3556 0.3556)
			(layers "F.Cu" "F.Mask" "F.Paste")
			(net "IOC_SIO_BLINK")
		)
		(pad "R6" smd circle
			(at -7.599934 -0.40005)
			(size 0.3556 0.3556)
			(layers "F.Cu" "F.Mask" "F.Paste")
			(net "POWERLOSS#")
		)
		(pad "R7" smd circle
			(at -6.800088 -0.40005)
			(size 0.3556 0.3556)
			(layers "F.Cu" "F.Mask" "F.Paste")
			(net "GND")
		)
		(pad "R8" smd circle
			(at -5.999988 -0.40005)
			(size 0.3556 0.3556)
			(layers "F.Cu" "F.Mask" "F.Paste")
			(net "GND")
		)
		(pad "R9" smd circle
			(at -5.199888 -0.40005)
			(size 0.3556 0.3556)
			(layers "F.Cu" "F.Mask" "F.Paste")
			(net "GND")
		)
		(pad "R10" smd circle
			(at -4.400042 -0.40005)
			(size 0.3556 0.3556)
			(layers "F.Cu" "F.Mask" "F.Paste")
			(net "GND")
		)
		(pad "R11" smd circle
			(at -3.599942 -0.40005)
			(size 0.3556 0.3556)
			(layers "F.Cu" "F.Mask" "F.Paste")
			(net "GND")
		)
		(pad "R12" smd circle
			(at -2.800096 -0.40005)
			(size 0.3556 0.3556)
			(layers "F.Cu" "F.Mask" "F.Paste")
			(net "P0V975")
		)
		(pad "R13" smd circle
			(at -1.999996 -0.40005)
			(size 0.3556 0.3556)
			(layers "F.Cu" "F.Mask" "F.Paste")
			(net "GND")
		)
		(pad "R14" smd circle
			(at -1.199896 -0.40005)
			(size 0.3556 0.3556)
			(layers "F.Cu" "F.Mask" "F.Paste")
			(net "P0V975")
		)
		(pad "R15" smd circle
			(at -0.40005 -0.40005)
			(size 0.3556 0.3556)
			(layers "F.Cu" "F.Mask" "F.Paste")
			(net "GND")
		)
		(pad "R16" smd circle
			(at 0.40005 -0.40005)
			(size 0.3556 0.3556)
			(layers "F.Cu" "F.Mask" "F.Paste")
			(net "P0V975")
		)
		(pad "R17" smd circle
			(at 1.199896 -0.40005)
			(size 0.3556 0.3556)
			(layers "F.Cu" "F.Mask" "F.Paste")
			(net "GND")
		)
		(pad "R18" smd circle
			(at 1.999996 -0.40005)
			(size 0.3556 0.3556)
			(layers "F.Cu" "F.Mask" "F.Paste")
			(net "P0V975")
		)
		(pad "R19" smd circle
			(at 2.800096 -0.40005)
			(size 0.3556 0.3556)
			(layers "F.Cu" "F.Mask" "F.Paste")
			(net "GND")
		)
		(pad "R20" smd circle
			(at 3.599942 -0.40005)
			(size 0.3556 0.3556)
			(layers "F.Cu" "F.Mask" "F.Paste")
			(net "P0V975")
		)
		(pad "R21" smd circle
			(at 4.400042 -0.40005)
			(size 0.3556 0.3556)
			(layers "F.Cu" "F.Mask" "F.Paste")
			(net "GND")
		)
		(pad "R22" smd circle
			(at 5.199888 -0.40005)
			(size 0.3556 0.3556)
			(layers "F.Cu" "F.Mask" "F.Paste")
			(net "GND")
		)
		(pad "R23" smd circle
			(at 5.999988 -0.40005)
			(size 0.3556 0.3556)
			(layers "F.Cu" "F.Mask" "F.Paste")
			(net "GND")
		)
		(pad "R24" smd circle
			(at 6.800088 -0.40005)
			(size 0.3556 0.3556)
			(layers "F.Cu" "F.Mask" "F.Paste")
			(net "GND")
		)
		(pad "R25" smd circle
			(at 7.599934 -0.40005)
			(size 0.3556 0.3556)
			(layers "F.Cu" "F.Mask" "F.Paste")
			(net "GND")
		)
		(pad "R26" smd circle
			(at 8.400034 -0.40005)
			(size 0.3556 0.3556)
			(layers "F.Cu" "F.Mask" "F.Paste")
			(net "GND")
		)
		(pad "R27" smd circle
			(at 9.19988 -0.40005)
			(size 0.3556 0.3556)
			(layers "F.Cu" "F.Mask" "F.Paste")
			(net "P1V8_C")
		)
		(pad "R28" smd circle
			(at 9.99998 -0.40005)
			(size 0.3556 0.3556)
			(layers "F.Cu" "F.Mask" "F.Paste")
			(net "I2C_IOC_4_SDA")
		)
		(pad "R29" smd circle
			(at 10.80008 -0.40005)
			(size 0.3556 0.3556)
			(layers "F.Cu" "F.Mask" "F.Paste")
			(net "I2C_IOC_0_SDA")
		)
		(pad "R30" smd circle
			(at 11.599926 -0.40005)
			(size 0.3556 0.3556)
			(layers "F.Cu" "F.Mask" "F.Paste")
			(net "SYS_CORE_TRI#")
		)
		(pad "T1" smd circle
			(at -11.599926 0.40005)
			(size 0.3556 0.3556)
			(layers "F.Cu" "F.Mask" "F.Paste")
			(net "RTRIM")
		)
		(pad "T2" smd circle
			(at -10.80008 0.40005)
			(size 0.3556 0.3556)
			(layers "F.Cu" "F.Mask" "F.Paste")
			(net "RTRIM#")
		)
		(pad "T3" smd circle
			(at -9.99998 0.40005)
			(size 0.3556 0.3556)
			(layers "F.Cu" "F.Mask" "F.Paste")
			(net "GND")
		)
		(pad "T4" smd circle
			(at -9.19988 0.40005)
			(size 0.3556 0.3556)
			(layers "F.Cu" "F.Mask" "F.Paste")
			(net "OSC_REF_CLK")
		)
		(pad "T5" smd circle
			(at -8.400034 0.40005)
			(size 0.3556 0.3556)
			(layers "F.Cu" "F.Mask" "F.Paste")
			(net "GND")
		)
		(pad "T6" smd circle
			(at -7.599934 0.40005)
			(size 0.3556 0.3556)
			(layers "F.Cu" "F.Mask" "F.Paste")
			(net "SIO_DIN_0")
		)
		(pad "T7" smd circle
			(at -6.800088 0.40005)
			(size 0.3556 0.3556)
			(layers "F.Cu" "F.Mask" "F.Paste")
			(net "GND")
		)
		(pad "T8" smd circle
			(at -5.999988 0.40005)
			(size 0.3556 0.3556)
			(layers "F.Cu" "F.Mask" "F.Paste")
			(net "GND")
		)
		(pad "T9" smd circle
			(at -5.199888 0.40005)
			(size 0.3556 0.3556)
			(layers "F.Cu" "F.Mask" "F.Paste")
			(net "SYS_PLL_VDD")
		)
		(pad "T10" smd circle
			(at -4.400042 0.40005)
			(size 0.3556 0.3556)
			(layers "F.Cu" "F.Mask" "F.Paste")
			(net "GND")
		)
		(pad "T11" smd circle
			(at -3.599942 0.40005)
			(size 0.3556 0.3556)
			(layers "F.Cu" "F.Mask" "F.Paste")
			(net "GND")
		)
		(pad "T12" smd circle
			(at -2.800096 0.40005)
			(size 0.3556 0.3556)
			(layers "F.Cu" "F.Mask" "F.Paste")
			(net "GND")
		)
		(pad "T13" smd circle
			(at -1.999996 0.40005)
			(size 0.3556 0.3556)
			(layers "F.Cu" "F.Mask" "F.Paste")
			(net "P0V975")
		)
		(pad "T14" smd circle
			(at -1.199896 0.40005)
			(size 0.3556 0.3556)
			(layers "F.Cu" "F.Mask" "F.Paste")
			(net "GND")
		)
		(pad "T15" smd circle
			(at -0.40005 0.40005)
			(size 0.3556 0.3556)
			(layers "F.Cu" "F.Mask" "F.Paste")
			(net "P0V975")
		)
		(pad "T16" smd circle
			(at 0.40005 0.40005)
			(size 0.3556 0.3556)
			(layers "F.Cu" "F.Mask" "F.Paste")
			(net "GND")
		)
		(pad "T17" smd circle
			(at 1.199896 0.40005)
			(size 0.3556 0.3556)
			(layers "F.Cu" "F.Mask" "F.Paste")
			(net "P0V975")
		)
		(pad "T18" smd circle
			(at 1.999996 0.40005)
			(size 0.3556 0.3556)
			(layers "F.Cu" "F.Mask" "F.Paste")
			(net "GND")
		)
		(pad "T19" smd circle
			(at 2.800096 0.40005)
			(size 0.3556 0.3556)
			(layers "F.Cu" "F.Mask" "F.Paste")
			(net "P0V975")
		)
		(pad "T20" smd circle
			(at 3.599942 0.40005)
			(size 0.3556 0.3556)
			(layers "F.Cu" "F.Mask" "F.Paste")
			(net "GND")
		)
		(pad "T21" smd circle
			(at 4.400042 0.40005)
			(size 0.3556 0.3556)
			(layers "F.Cu" "F.Mask" "F.Paste")
			(net "P0V975")
		)
		(pad "T22" smd circle
			(at 5.199888 0.40005)
			(size 0.3556 0.3556)
			(layers "F.Cu" "F.Mask" "F.Paste")
			(net "GND")
		)
		(pad "T23" smd circle
			(at 5.999988 0.40005)
			(size 0.3556 0.3556)
			(layers "F.Cu" "F.Mask" "F.Paste")
			(net "GND")
		)
		(pad "T24" smd circle
			(at 6.800088 0.40005)
			(size 0.3556 0.3556)
			(layers "F.Cu" "F.Mask" "F.Paste")
			(net "GND")
		)
		(pad "T25" smd circle
			(at 7.599934 0.40005)
			(size 0.3556 0.3556)
			(layers "F.Cu" "F.Mask" "F.Paste")
			(net "GND")
		)
		(pad "T26" smd circle
			(at 8.400034 0.40005)
			(size 0.3556 0.3556)
			(layers "F.Cu" "F.Mask" "F.Paste")
			(net "P1V8_C")
		)
		(pad "T27" smd circle
			(at 9.19988 0.40005)
			(size 0.3556 0.3556)
			(layers "F.Cu" "F.Mask" "F.Paste")
			(net "GND")
		)
		(pad "T28" smd circle
			(at 9.99998 0.40005)
			(size 0.3556 0.3556)
			(layers "F.Cu" "F.Mask" "F.Paste")
			(net "IOC_CLK_SEL1")
		)
		(pad "T29" smd circle
			(at 10.80008 0.40005)
			(size 0.3556 0.3556)
			(layers "F.Cu" "F.Mask" "F.Paste")
			(net "SYS_HB_LED")
		)
		(pad "T30" smd circle
			(at 11.599926 0.40005)
			(size 0.3556 0.3556)
			(layers "F.Cu" "F.Mask" "F.Paste")
			(net "SBL_SCL")
		)
		(pad "U1" smd circle
			(at -11.599926 1.199896)
			(size 0.3556 0.3556)
			(layers "F.Cu" "F.Mask" "F.Paste")
			(net "SAS0_VDDH")
		)
		(pad "U2" smd circle
			(at -10.80008 1.199896)
			(size 0.3556 0.3556)
			(layers "F.Cu" "F.Mask" "F.Paste")
			(net "GND")
		)
		(pad "U3" smd circle
			(at -9.99998 1.199896)
			(size 0.3556 0.3556)
			(layers "F.Cu" "F.Mask" "F.Paste")
			(net "GND")
		)
		(pad "U4" smd circle
			(at -9.19988 1.199896)
			(size 0.3556 0.3556)
			(layers "F.Cu" "F.Mask" "F.Paste")
			(net "GND")
		)
		(pad "U5" smd circle
			(at -8.400034 1.199896)
			(size 0.3556 0.3556)
			(layers "F.Cu" "F.Mask" "F.Paste")
			(net "GND")
		)
		(pad "U6" smd circle
			(at -7.599934 1.199896)
			(size 0.3556 0.3556)
			(layers "F.Cu" "F.Mask" "F.Paste")
			(net "GND")
		)
		(pad "U7" smd circle
			(at -6.800088 1.199896)
			(size 0.3556 0.3556)
			(layers "F.Cu" "F.Mask" "F.Paste")
			(net "GND")
		)
		(pad "U8" smd circle
			(at -5.999988 1.199896)
			(size 0.3556 0.3556)
			(layers "F.Cu" "F.Mask" "F.Paste")
			(net "GND")
		)
		(pad "U9" smd circle
			(at -5.199888 1.199896)
			(size 0.3556 0.3556)
			(layers "F.Cu" "F.Mask" "F.Paste")
			(net "GND")
		)
		(pad "U10" smd circle
			(at -4.400042 1.199896)
			(size 0.3556 0.3556)
			(layers "F.Cu" "F.Mask" "F.Paste")
			(net "SHELL_PLL_VDD")
		)
		(pad "U11" smd circle
			(at -3.599942 1.199896)
			(size 0.3556 0.3556)
			(layers "F.Cu" "F.Mask" "F.Paste")
			(net "GND")
		)
		(pad "U12" smd circle
			(at -2.800096 1.199896)
			(size 0.3556 0.3556)
			(layers "F.Cu" "F.Mask" "F.Paste")
			(net "P0V975")
		)
		(pad "U13" smd circle
			(at -1.999996 1.199896)
			(size 0.3556 0.3556)
			(layers "F.Cu" "F.Mask" "F.Paste")
			(net "GND")
		)
		(pad "U14" smd circle
			(at -1.199896 1.199896)
			(size 0.3556 0.3556)
			(layers "F.Cu" "F.Mask" "F.Paste")
			(net "P0V975")
		)
		(pad "U15" smd circle
			(at -0.40005 1.199896)
			(size 0.3556 0.3556)
			(layers "F.Cu" "F.Mask" "F.Paste")
			(net "GND")
		)
		(pad "U16" smd circle
			(at 0.40005 1.199896)
			(size 0.3556 0.3556)
			(layers "F.Cu" "F.Mask" "F.Paste")
			(net "P0V975")
		)
		(pad "U17" smd circle
			(at 1.199896 1.199896)
			(size 0.3556 0.3556)
			(layers "F.Cu" "F.Mask" "F.Paste")
			(net "GND")
		)
		(pad "U18" smd circle
			(at 1.999996 1.199896)
			(size 0.3556 0.3556)
			(layers "F.Cu" "F.Mask" "F.Paste")
			(net "P0V975")
		)
		(pad "U19" smd circle
			(at 2.800096 1.199896)
			(size 0.3556 0.3556)
			(layers "F.Cu" "F.Mask" "F.Paste")
			(net "GND")
		)
		(pad "U20" smd circle
			(at 3.599942 1.199896)
			(size 0.3556 0.3556)
			(layers "F.Cu" "F.Mask" "F.Paste")
			(net "P0V975")
		)
		(pad "U21" smd circle
			(at 4.400042 1.199896)
			(size 0.3556 0.3556)
			(layers "F.Cu" "F.Mask" "F.Paste")
			(net "GND")
		)
		(pad "U22" smd circle
			(at 5.199888 1.199896)
			(size 0.3556 0.3556)
			(layers "F.Cu" "F.Mask" "F.Paste")
			(net "GND")
		)
		(pad "U23" smd circle
			(at 5.999988 1.199896)
			(size 0.3556 0.3556)
			(layers "F.Cu" "F.Mask" "F.Paste")
			(net "GND")
		)
		(pad "U24" smd circle
			(at 6.800088 1.199896)
			(size 0.3556 0.3556)
			(layers "F.Cu" "F.Mask" "F.Paste")
			(net "GND")
		)
		(pad "U25" smd circle
			(at 7.599934 1.199896)
			(size 0.3556 0.3556)
			(layers "F.Cu" "F.Mask" "F.Paste")
			(net "GND")
		)
		(pad "U26" smd circle
			(at 8.400034 1.199896)
			(size 0.3556 0.3556)
			(layers "F.Cu" "F.Mask" "F.Paste")
			(net "GND")
		)
		(pad "U27" smd circle
			(at 9.19988 1.199896)
			(size 0.3556 0.3556)
			(layers "F.Cu" "F.Mask" "F.Paste")
			(net "P1V8_C")
		)
		(pad "U28" smd circle
			(at 9.99998 1.199896)
			(size 0.3556 0.3556)
			(layers "F.Cu" "F.Mask" "F.Paste")
			(net "IOC_RESET_N")
		)
		(pad "U29" smd circle
			(at 10.80008 1.199896)
			(size 0.3556 0.3556)
			(layers "F.Cu" "F.Mask" "F.Paste")
			(net "I2C_IOC_3_SDA")
		)
		(pad "U30" smd circle
			(at 11.599926 1.199896)
			(size 0.3556 0.3556)
			(layers "F.Cu" "F.Mask" "F.Paste")
			(net "CP_DONE")
		)
		(pad "V1" smd circle
			(at -11.599926 1.999996)
			(size 0.3556 0.3556)
			(layers "F.Cu" "F.Mask" "F.Paste")
			(net "PHY_IOC_TO_SCC_47_DP")
		)
		(pad "V2" smd circle
			(at -10.80008 1.999996)
			(size 0.3556 0.3556)
			(layers "F.Cu" "F.Mask" "F.Paste")
			(net "PHY_IOC_TO_SCC_47_DN")
		)
		(pad "V3" smd circle
			(at -9.99998 1.999996)
			(size 0.3556 0.3556)
			(layers "F.Cu" "F.Mask" "F.Paste")
			(net "GND")
		)
		(pad "V4" smd circle
			(at -9.19988 1.999996)
			(size 0.3556 0.3556)
			(layers "F.Cu" "F.Mask" "F.Paste")
			(net "PHY_SCC_TO_IOC_C_47_DP")
		)
		(pad "V5" smd circle
			(at -8.400034 1.999996)
			(size 0.3556 0.3556)
			(layers "F.Cu" "F.Mask" "F.Paste")
			(net "PHY_SCC_TO_IOC_C_47_DN")
		)
		(pad "V6" smd circle
			(at -7.599934 1.999996)
			(size 0.3556 0.3556)
			(layers "F.Cu" "F.Mask" "F.Paste")
			(net "GND")
		)
		(pad "V7" smd circle
			(at -6.800088 1.999996)
			(size 0.3556 0.3556)
			(layers "F.Cu" "F.Mask" "F.Paste")
			(net "SAS0_AVDD")
		)
		(pad "V8" smd circle
			(at -5.999988 1.999996)
			(size 0.3556 0.3556)
			(layers "F.Cu" "F.Mask" "F.Paste")
			(net "GND")
		)
		(pad "V9" smd circle
			(at -5.199888 1.999996)
			(size 0.3556 0.3556)
			(layers "F.Cu" "F.Mask" "F.Paste")
			(net "SAS0_AVDD")
		)
		(pad "V10" smd circle
			(at -4.400042 1.999996)
			(size 0.3556 0.3556)
			(layers "F.Cu" "F.Mask" "F.Paste")
			(net "GND")
		)
		(pad "V11" smd circle
			(at -3.599942 1.999996)
			(size 0.3556 0.3556)
			(layers "F.Cu" "F.Mask" "F.Paste")
			(net "VDDA_SAS_REF_CLK")
		)
		(pad "V12" smd circle
			(at -2.800096 1.999996)
			(size 0.3556 0.3556)
			(layers "F.Cu" "F.Mask" "F.Paste")
			(net "GND")
		)
		(pad "V13" smd circle
			(at -1.999996 1.999996)
			(size 0.3556 0.3556)
			(layers "F.Cu" "F.Mask" "F.Paste")
			(net "P0V975")
		)
		(pad "V14" smd circle
			(at -1.199896 1.999996)
			(size 0.3556 0.3556)
			(layers "F.Cu" "F.Mask" "F.Paste")
			(net "GND")
		)
		(pad "V15" smd circle
			(at -0.40005 1.999996)
			(size 0.3556 0.3556)
			(layers "F.Cu" "F.Mask" "F.Paste")
			(net "P0V975")
		)
		(pad "V16" smd circle
			(at 0.40005 1.999996)
			(size 0.3556 0.3556)
			(layers "F.Cu" "F.Mask" "F.Paste")
			(net "GND")
		)
		(pad "V17" smd circle
			(at 1.199896 1.999996)
			(size 0.3556 0.3556)
			(layers "F.Cu" "F.Mask" "F.Paste")
			(net "P0V975")
		)
		(pad "V18" smd circle
			(at 1.999996 1.999996)
			(size 0.3556 0.3556)
			(layers "F.Cu" "F.Mask" "F.Paste")
			(net "GND")
		)
		(pad "V19" smd circle
			(at 2.800096 1.999996)
			(size 0.3556 0.3556)
			(layers "F.Cu" "F.Mask" "F.Paste")
			(net "P0V975")
		)
		(pad "V20" smd circle
			(at 3.599942 1.999996)
			(size 0.3556 0.3556)
			(layers "F.Cu" "F.Mask" "F.Paste")
			(net "GND")
		)
		(pad "V21" smd circle
			(at 4.400042 1.999996)
			(size 0.3556 0.3556)
			(layers "F.Cu" "F.Mask" "F.Paste")
			(net "P0V975")
		)
		(pad "V22" smd circle
			(at 5.199888 1.999996)
			(size 0.3556 0.3556)
			(layers "F.Cu" "F.Mask" "F.Paste")
			(net "GND")
		)
		(pad "V23" smd circle
			(at 5.999988 1.999996)
			(size 0.3556 0.3556)
			(layers "F.Cu" "F.Mask" "F.Paste")
			(net "GND")
		)
		(pad "V24" smd circle
			(at 6.800088 1.999996)
			(size 0.3556 0.3556)
			(layers "F.Cu" "F.Mask" "F.Paste")
			(net "GND")
		)
		(pad "V25" smd circle
			(at 7.599934 1.999996)
			(size 0.3556 0.3556)
			(layers "F.Cu" "F.Mask" "F.Paste")
			(net "GND")
		)
		(pad "V26" smd circle
			(at 8.400034 1.999996)
			(size 0.3556 0.3556)
			(layers "F.Cu" "F.Mask" "F.Paste")
			(net "P1V8_C")
		)
		(pad "V27" smd circle
			(at 9.19988 1.999996)
			(size 0.3556 0.3556)
			(layers "F.Cu" "F.Mask" "F.Paste")
			(net "GND")
		)
		(pad "V28" smd circle
			(at 9.99998 1.999996)
			(size 0.3556 0.3556)
			(layers "F.Cu" "F.Mask" "F.Paste")
			(net "I2C_IOC_2_SCL")
		)
		(pad "V29" smd circle
			(at 10.80008 1.999996)
			(size 0.3556 0.3556)
			(layers "F.Cu" "F.Mask" "F.Paste")
			(net "I2C_IOC_0_SCL")
		)
		(pad "V30" smd circle
			(at 11.599926 1.999996)
			(size 0.3556 0.3556)
			(layers "F.Cu" "F.Mask" "F.Paste")
			(net "I2C_IOC_1_SDA")
		)
		(pad "W1" smd circle
			(at -11.599926 2.800096)
			(size 0.3556 0.3556)
			(layers "F.Cu" "F.Mask" "F.Paste")
			(net "PHY_IOC_TO_SCC_46_DP")
		)
		(pad "W2" smd circle
			(at -10.80008 2.800096)
			(size 0.3556 0.3556)
			(layers "F.Cu" "F.Mask" "F.Paste")
			(net "PHY_IOC_TO_SCC_46_DN")
		)
		(pad "W3" smd circle
			(at -9.99998 2.800096)
			(size 0.3556 0.3556)
			(layers "F.Cu" "F.Mask" "F.Paste")
			(net "GND")
		)
		(pad "W4" smd circle
			(at -9.19988 2.800096)
			(size 0.3556 0.3556)
			(layers "F.Cu" "F.Mask" "F.Paste")
			(net "PHY_SCC_TO_IOC_C_46_DP")
		)
		(pad "W5" smd circle
			(at -8.400034 2.800096)
			(size 0.3556 0.3556)
			(layers "F.Cu" "F.Mask" "F.Paste")
			(net "PHY_SCC_TO_IOC_C_46_DN")
		)
		(pad "W6" smd circle
			(at -7.599934 2.800096)
			(size 0.3556 0.3556)
			(layers "F.Cu" "F.Mask" "F.Paste")
			(net "GND")
		)
		(pad "W7" smd circle
			(at -6.800088 2.800096)
			(size 0.3556 0.3556)
			(layers "F.Cu" "F.Mask" "F.Paste")
			(net "GND")
		)
		(pad "W8" smd circle
			(at -5.999988 2.800096)
			(size 0.3556 0.3556)
			(layers "F.Cu" "F.Mask" "F.Paste")
			(net "GND")
		)
		(pad "W9" smd circle
			(at -5.199888 2.800096)
			(size 0.3556 0.3556)
			(layers "F.Cu" "F.Mask" "F.Paste")
			(net "GND")
		)
		(pad "W10" smd circle
			(at -4.400042 2.800096)
			(size 0.3556 0.3556)
			(layers "F.Cu" "F.Mask" "F.Paste")
			(net "GND")
		)
		(pad "W11" smd circle
			(at -3.599942 2.800096)
			(size 0.3556 0.3556)
			(layers "F.Cu" "F.Mask" "F.Paste")
			(net "GND")
		)
		(pad "W12" smd circle
			(at -2.800096 2.800096)
			(size 0.3556 0.3556)
			(layers "F.Cu" "F.Mask" "F.Paste")
			(net "GND")
		)
		(pad "W13" smd circle
			(at -1.999996 2.800096)
			(size 0.3556 0.3556)
			(layers "F.Cu" "F.Mask" "F.Paste")
			(net "GND")
		)
		(pad "W14" smd circle
			(at -1.199896 2.800096)
			(size 0.3556 0.3556)
			(layers "F.Cu" "F.Mask" "F.Paste")
			(net "P0V975")
		)
		(pad "W15" smd circle
			(at -0.40005 2.800096)
			(size 0.3556 0.3556)
			(layers "F.Cu" "F.Mask" "F.Paste")
			(net "GND")
		)
		(pad "W16" smd circle
			(at 0.40005 2.800096)
			(size 0.3556 0.3556)
			(layers "F.Cu" "F.Mask" "F.Paste")
			(net "P0V975")
		)
		(pad "W17" smd circle
			(at 1.199896 2.800096)
			(size 0.3556 0.3556)
			(layers "F.Cu" "F.Mask" "F.Paste")
			(net "GND")
		)
		(pad "W18" smd circle
			(at 1.999996 2.800096)
			(size 0.3556 0.3556)
			(layers "F.Cu" "F.Mask" "F.Paste")
			(net "P0V975")
		)
		(pad "W19" smd circle
			(at 2.800096 2.800096)
			(size 0.3556 0.3556)
			(layers "F.Cu" "F.Mask" "F.Paste")
			(net "GND")
		)
		(pad "W20" smd circle
			(at 3.599942 2.800096)
			(size 0.3556 0.3556)
			(layers "F.Cu" "F.Mask" "F.Paste")
			(net "P0V975")
		)
		(pad "W21" smd circle
			(at 4.400042 2.800096)
			(size 0.3556 0.3556)
			(layers "F.Cu" "F.Mask" "F.Paste")
			(net "GND")
		)
		(pad "W22" smd circle
			(at 5.199888 2.800096)
			(size 0.3556 0.3556)
			(layers "F.Cu" "F.Mask" "F.Paste")
			(net "GND")
		)
		(pad "W23" smd circle
			(at 5.999988 2.800096)
			(size 0.3556 0.3556)
			(layers "F.Cu" "F.Mask" "F.Paste")
			(net "GND")
		)
		(pad "W24" smd circle
			(at 6.800088 2.800096)
			(size 0.3556 0.3556)
			(layers "F.Cu" "F.Mask" "F.Paste")
			(net "GND")
		)
		(pad "W25" smd circle
			(at 7.599934 2.800096)
			(size 0.3556 0.3556)
			(layers "F.Cu" "F.Mask" "F.Paste")
			(net "GND")
		)
		(pad "W26" smd circle
			(at 8.400034 2.800096)
			(size 0.3556 0.3556)
			(layers "F.Cu" "F.Mask" "F.Paste")
			(net "GND")
		)
		(pad "W27" smd circle
			(at 9.19988 2.800096)
			(size 0.3556 0.3556)
			(layers "F.Cu" "F.Mask" "F.Paste")
			(net "P1V8_C")
		)
		(pad "W28" smd circle
			(at 9.99998 2.800096)
			(size 0.3556 0.3556)
			(layers "F.Cu" "F.Mask" "F.Paste")
			(net "IOC_GPIO_38")
		)
		(pad "W29" smd circle
			(at 10.80008 2.800096)
			(size 0.3556 0.3556)
			(layers "F.Cu" "F.Mask" "F.Paste")
			(net "I2C_IOC_4_SCL")
		)
		(pad "W30" smd circle
			(at 11.599926 2.800096)
			(size 0.3556 0.3556)
			(layers "F.Cu" "F.Mask" "F.Paste")
			(net "IOC_GPIO_24")
		)
		(pad "Y1" smd circle
			(at -11.599926 3.599942)
			(size 0.3556 0.3556)
			(layers "F.Cu" "F.Mask" "F.Paste")
			(net "SAS0_VDDH")
		)
		(pad "Y2" smd circle
			(at -10.80008 3.599942)
			(size 0.3556 0.3556)
			(layers "F.Cu" "F.Mask" "F.Paste")
			(net "GND")
		)
		(pad "Y3" smd circle
			(at -9.99998 3.599942)
			(size 0.3556 0.3556)
			(layers "F.Cu" "F.Mask" "F.Paste")
			(net "GND")
		)
		(pad "Y4" smd circle
			(at -9.19988 3.599942)
			(size 0.3556 0.3556)
			(layers "F.Cu" "F.Mask" "F.Paste")
			(net "SAS0_AVDD")
		)
		(pad "Y5" smd circle
			(at -8.400034 3.599942)
			(size 0.3556 0.3556)
			(layers "F.Cu" "F.Mask" "F.Paste")
			(net "GND")
		)
		(pad "Y6" smd circle
			(at -7.599934 3.599942)
			(size 0.3556 0.3556)
			(layers "F.Cu" "F.Mask" "F.Paste")
			(net "SAS0_VDDH")
		)
		(pad "Y7" smd circle
			(at -6.800088 3.599942)
			(size 0.3556 0.3556)
			(layers "F.Cu" "F.Mask" "F.Paste")
			(net "SAS0_AVDD")
		)
		(pad "Y8" smd circle
			(at -5.999988 3.599942)
			(size 0.3556 0.3556)
			(layers "F.Cu" "F.Mask" "F.Paste")
			(net "GND")
		)
		(pad "Y9" smd circle
			(at -5.199888 3.599942)
			(size 0.3556 0.3556)
			(layers "F.Cu" "F.Mask" "F.Paste")
			(net "GND")
		)
		(pad "Y10" smd circle
			(at -4.400042 3.599942)
			(size 0.3556 0.3556)
			(layers "F.Cu" "F.Mask" "F.Paste")
			(net "GND")
		)
		(pad "Y11" smd circle
			(at -3.599942 3.599942)
			(size 0.3556 0.3556)
			(layers "F.Cu" "F.Mask" "F.Paste")
			(net "GND")
		)
		(pad "Y12" smd circle
			(at -2.800096 3.599942)
			(size 0.3556 0.3556)
			(layers "F.Cu" "F.Mask" "F.Paste")
			(net "GND")
		)
		(pad "Y13" smd circle
			(at -1.999996 3.599942)
			(size 0.3556 0.3556)
			(layers "F.Cu" "F.Mask" "F.Paste")
			(net "GND")
		)
		(pad "Y14" smd circle
			(at -1.199896 3.599942)
			(size 0.3556 0.3556)
			(layers "F.Cu" "F.Mask" "F.Paste")
			(net "GND")
		)
		(pad "Y15" smd circle
			(at -0.40005 3.599942)
			(size 0.3556 0.3556)
			(layers "F.Cu" "F.Mask" "F.Paste")
			(net "GND")
		)
		(pad "Y16" smd circle
			(at 0.40005 3.599942)
			(size 0.3556 0.3556)
			(layers "F.Cu" "F.Mask" "F.Paste")
			(net "GND")
		)
		(pad "Y17" smd circle
			(at 1.199896 3.599942)
			(size 0.3556 0.3556)
			(layers "F.Cu" "F.Mask" "F.Paste")
			(net "P0V975")
		)
		(pad "Y18" smd circle
			(at 1.999996 3.599942)
			(size 0.3556 0.3556)
			(layers "F.Cu" "F.Mask" "F.Paste")
			(net "GND")
		)
		(pad "Y19" smd circle
			(at 2.800096 3.599942)
			(size 0.3556 0.3556)
			(layers "F.Cu" "F.Mask" "F.Paste")
			(net "P0V975")
		)
		(pad "Y20" smd circle
			(at 3.599942 3.599942)
			(size 0.3556 0.3556)
			(layers "F.Cu" "F.Mask" "F.Paste")
			(net "GND")
		)
		(pad "Y21" smd circle
			(at 4.400042 3.599942)
			(size 0.3556 0.3556)
			(layers "F.Cu" "F.Mask" "F.Paste")
			(net "P0V975")
		)
		(pad "Y22" smd circle
			(at 5.199888 3.599942)
			(size 0.3556 0.3556)
			(layers "F.Cu" "F.Mask" "F.Paste")
			(net "GND")
		)
		(pad "Y23" smd circle
			(at 5.999988 3.599942)
			(size 0.3556 0.3556)
			(layers "F.Cu" "F.Mask" "F.Paste")
			(net "GND")
		)
		(pad "Y24" smd circle
			(at 6.800088 3.599942)
			(size 0.3556 0.3556)
			(layers "F.Cu" "F.Mask" "F.Paste")
			(net "GND")
		)
		(pad "Y25" smd circle
			(at 7.599934 3.599942)
			(size 0.3556 0.3556)
			(layers "F.Cu" "F.Mask" "F.Paste")
			(net "GND")
		)
		(pad "Y26" smd circle
			(at 8.400034 3.599942)
			(size 0.3556 0.3556)
			(layers "F.Cu" "F.Mask" "F.Paste")
			(net "P1V8_C")
		)
		(pad "Y27" smd circle
			(at 9.19988 3.599942)
			(size 0.3556 0.3556)
			(layers "F.Cu" "F.Mask" "F.Paste")
			(net "GND")
		)
		(pad "Y28" smd circle
			(at 9.99998 3.599942)
			(size 0.3556 0.3556)
			(layers "F.Cu" "F.Mask" "F.Paste")
			(net "I2C_IOC_2_SDA")
		)
		(pad "Y29" smd circle
			(at 10.80008 3.599942)
			(size 0.3556 0.3556)
			(layers "F.Cu" "F.Mask" "F.Paste")
			(net "SPARE4")
		)
		(pad "Y30" smd circle
			(at 11.599926 3.599942)
			(size 0.3556 0.3556)
			(layers "F.Cu" "F.Mask" "F.Paste")
			(net "IOC_GPIO_15")
		)
	)
	(footprint ""
		(layer "F.Cu")
		(at 22.38883 -93.377004 90)
		(property "Reference" "R446"
			(at 0 0 90)
			(layer "F.SilkS")
			(hide yes)
			(effects
				(font
					(size 1.27 1.27)
				)
			)
		)
		(property "Value" "0R2J-2-GP"
			(at 0.064008 -3.993896 90)
			(unlocked yes)
			(layer "F.Fab")
			(hide yes)
			(effects
				(font
					(size 1.016 1.016)
					(thickness 0.1524)
				)
			)
		)
		(property "Device Type" "R402H16"
			(at 0.064008 -5.517896 90)
			(unlocked yes)
			(layer "F.Fab")
			(hide yes)
			(effects
				(font
					(size 1.016 1.016)
					(thickness 0.1524)
				)
			)
		)
		(duplicate_pad_numbers_are_jumpers no)
		(fp_line
			(start 0.508 -0.9398)
			(end -0.508 -0.9398)
			(stroke
				(width 0.1524)
				(type default)
			)
			(layer "F.SilkS")
		)
		(fp_line
			(start -0.508 -0.9398)
			(end -0.508 0.9398)
			(stroke
				(width 0.1524)
				(type default)
			)
			(layer "F.SilkS")
		)
		(fp_rect
			(start -0.508 0.9398)
			(end 0.508 -0.9398)
			(stroke
				(width 0)
				(type default)
			)
			(fill no)
			(layer "F.CrtYd")
		)
		(fp_rect
			(start -0.508 0.9398)
			(end 0.508 -0.9398)
			(stroke
				(width 0)
				(type default)
			)
			(fill no)
			(layer "F.Fab")
		)
		(pad "1" smd custom
			(at 0 -0.4445 90)
			(size 0.1397 0.1397)
			(layers "F.Cu" "F.Mask" "F.Paste")
			(net "LS_EN_U46")
			(options
				(clearance outline)
				(anchor circle)
			)
			(primitives
				(gr_poly
					(pts
						(arc
							(start -0.1778 -0.2794)
							(mid -0.249642 -0.249642)
							(end -0.2794 -0.1778)
						)
						(arc
							(start -0.2794 0.1778)
							(mid -0.249642 0.249642)
							(end -0.1778 0.2794)
						)
						(arc
							(start 0.1778 0.2794)
							(mid 0.249642 0.249642)
							(end 0.2794 0.1778)
						)
						(arc
							(start 0.2794 -0.1778)
							(mid 0.249642 -0.249642)
							(end 0.1778 -0.2794)
						)
					)
					(width 0)
					(fill yes)
				)
			)
		)
		(pad "2" smd custom
			(at 0 0.4445 90)
			(size 0.1397 0.1397)
			(layers "F.Cu" "F.Mask" "F.Paste")
			(net "VREF1")
			(options
				(clearance outline)
				(anchor circle)
			)
			(primitives
				(gr_poly
					(pts
						(arc
							(start -0.1778 -0.2794)
							(mid -0.249642 -0.249642)
							(end -0.2794 -0.1778)
						)
						(arc
							(start -0.2794 0.1778)
							(mid -0.249642 0.249642)
							(end -0.1778 0.2794)
						)
						(arc
							(start 0.1778 0.2794)
							(mid 0.249642 0.249642)
							(end 0.2794 0.1778)
						)
						(arc
							(start 0.2794 -0.1778)
							(mid 0.249642 -0.249642)
							(end 0.1778 -0.2794)
						)
					)
					(width 0)
					(fill yes)
				)
			)
		)
	)
	(footprint ""
		(layer "F.Cu")
		(at 148.190966 -35.15614 102)
		(property "Reference" "C330"
			(at 0 0 102)
			(layer "F.SilkS")
			(hide yes)
			(effects
				(font
					(size 1.27 1.27)
				)
			)
		)
		(property "Value" "SCD01U16V1KX-GP"
			(at -2.832296 -1.73983 102)
			(unlocked yes)
			(layer "F.Fab")
			(hide yes)
			(effects
				(font
					(size 1.016 1.016)
					(thickness 0.1524)
				)
			)
		)
		(property "Device Type" "C0201H13"
			(at -2.832174 -3.263834 102)
			(unlocked yes)
			(layer "F.Fab")
			(hide yes)
			(effects
				(font
					(size 1.016 1.016)
					(thickness 0.1524)
				)
			)
		)
		(duplicate_pad_numbers_are_jumpers no)
		(fp_poly
			(pts
				(xy -0.279454 -0.647706) (xy 0.279346 -0.647706) (xy 0.279346 0.647694) (xy -0.279454 0.647694)
			)
			(stroke
				(width 0)
				(type default)
			)
			(fill no)
			(layer "F.CrtYd")
		)
		(fp_poly
			(pts
				(xy -0.279454 -0.647706) (xy 0.279346 -0.647706) (xy 0.279346 0.647694) (xy -0.279454 0.647694)
			)
			(stroke
				(width 0)
				(type default)
			)
			(fill no)
			(layer "F.Fab")
		)
		(pad "1" smd custom
			(at -0.000001 -0.2794 102)
			(size 0.0762 0.0762)
			(layers "F.Cu" "F.Mask" "F.Paste")
			(net "PHY_SCC_TO_IOC_41_DN")
			(options
				(clearance outline)
				(anchor circle)
			)
			(primitives
				(gr_poly
					(pts
						(arc
							(start 0.1524 -0.127)
							(mid 0.137521 -0.162921)
							(end 0.1016 -0.1778)
						)
						(arc
							(start -0.1016 -0.1778)
							(mid -0.137521 -0.162921)
							(end -0.1524 -0.127)
						)
						(arc
							(start -0.1524 0.127)
							(mid -0.137521 0.162921)
							(end -0.1016 0.1778)
						)
						(arc
							(start 0.1016 0.1778)
							(mid 0.137521 0.162921)
							(end 0.1524 0.127)
						)
					)
					(width 0)
					(fill yes)
				)
			)
		)
		(pad "2" smd custom
			(at 0.000001 0.2794 102)
			(size 0.0762 0.0762)
			(layers "F.Cu" "F.Mask" "F.Paste")
			(net "PHY_SCC_TO_IOC_C_41_DN")
			(options
				(clearance outline)
				(anchor circle)
			)
			(primitives
				(gr_poly
					(pts
						(arc
							(start 0.1524 -0.127)
							(mid 0.137521 -0.162921)
							(end 0.1016 -0.1778)
						)
						(arc
							(start -0.1016 -0.1778)
							(mid -0.137521 -0.162921)
							(end -0.1524 -0.127)
						)
						(arc
							(start -0.1524 0.127)
							(mid -0.137521 0.162921)
							(end -0.1016 0.1778)
						)
						(arc
							(start 0.1016 0.1778)
							(mid 0.137521 0.162921)
							(end 0.1524 0.127)
						)
					)
					(width 0)
					(fill yes)
				)
			)
		)
	)
	(footprint ""
		(layer "F.Cu")
		(at 74.855832 -74.631804)
		(property "Reference" "R529"
			(at 0 0 0)
			(layer "F.SilkS")
			(hide yes)
			(effects
				(font
					(size 1.27 1.27)
				)
			)
		)
		(property "Value" "0R2J-2-GP"
			(at 0.064008 -3.993896 0)
			(unlocked yes)
			(layer "F.Fab")
			(hide yes)
			(effects
				(font
					(size 1.016 1.016)
					(thickness 0.1524)
				)
			)
		)
		(property "Device Type" "R402H16"
			(at 0.064008 -5.517896 0)
			(unlocked yes)
			(layer "F.Fab")
			(hide yes)
			(effects
				(font
					(size 1.016 1.016)
					(thickness 0.1524)
				)
			)
		)
		(duplicate_pad_numbers_are_jumpers no)
		(fp_line
			(start -0.508 -0.9398)
			(end -0.508 0.9398)
			(stroke
				(width 0.1524)
				(type default)
			)
			(layer "F.SilkS")
		)
		(fp_line
			(start 0.508 -0.9398)
			(end -0.508 -0.9398)
			(stroke
				(width 0.1524)
				(type default)
			)
			(layer "F.SilkS")
		)
		(fp_rect
			(start -0.508 0.9398)
			(end 0.508 -0.9398)
			(stroke
				(width 0)
				(type default)
			)
			(fill no)
			(layer "F.CrtYd")
		)
		(fp_rect
			(start -0.508 0.9398)
			(end 0.508 -0.9398)
			(stroke
				(width 0)
				(type default)
			)
			(fill no)
			(layer "F.Fab")
		)
		(pad "1" smd custom
			(at 0 -0.4445)
			(size 0.1397 0.1397)
			(layers "F.Cu" "F.Mask" "F.Paste")
			(net "I2C_EXP_IOC_SCL8")
			(options
				(clearance outline)
				(anchor circle)
			)
			(primitives
				(gr_poly
					(pts
						(arc
							(start -0.1778 -0.2794)
							(mid -0.249642 -0.249642)
							(end -0.2794 -0.1778)
						)
						(arc
							(start -0.2794 0.1778)
							(mid -0.249642 0.249642)
							(end -0.1778 0.2794)
						)
						(arc
							(start 0.1778 0.2794)
							(mid 0.249642 0.249642)
							(end 0.2794 0.1778)
						)
						(arc
							(start 0.2794 -0.1778)
							(mid 0.249642 -0.249642)
							(end 0.1778 -0.2794)
						)
					)
					(width 0)
					(fill yes)
				)
			)
		)
		(pad "2" smd custom
			(at 0 0.4445)
			(size 0.1397 0.1397)
			(layers "F.Cu" "F.Mask" "F.Paste")
			(net "I2C_IOC_4_R_SCL")
			(options
				(clearance outline)
				(anchor circle)
			)
			(primitives
				(gr_poly
					(pts
						(arc
							(start -0.1778 -0.2794)
							(mid -0.249642 -0.249642)
							(end -0.2794 -0.1778)
						)
						(arc
							(start -0.2794 0.1778)
							(mid -0.249642 0.249642)
							(end -0.1778 0.2794)
						)
						(arc
							(start 0.1778 0.2794)
							(mid 0.249642 0.249642)
							(end 0.2794 0.1778)
						)
						(arc
							(start 0.2794 -0.1778)
							(mid 0.249642 -0.249642)
							(end 0.1778 -0.2794)
						)
					)
					(width 0)
					(fill yes)
				)
			)
		)
	)
	(footprint ""
		(layer "F.Cu")
		(at 69.977 -103.505)
		(property "Reference" "C640"
			(at 0 0 0)
			(layer "F.SilkS")
			(hide yes)
			(effects
				(font
					(size 1.27 1.27)
				)
			)
		)
		(property "Value" "SC1KP50V2KX-1GP"
			(at 1.1811 -2.7051 0)
			(unlocked yes)
			(layer "F.Fab")
			(hide yes)
			(effects
				(font
					(size 1.016 1.016)
					(thickness 0.1524)
				)
			)
		)
		(property "Device Type" "C402H22"
			(at 1.1811 -4.2291 0)
			(unlocked yes)
			(layer "F.Fab")
			(hide yes)
			(effects
				(font
					(size 1.016 1.016)
					(thickness 0.1524)
				)
			)
		)
		(duplicate_pad_numbers_are_jumpers no)
		(fp_rect
			(start -0.4318 0.9525)
			(end 0.4318 -0.9525)
			(stroke
				(width 0)
				(type default)
			)
			(fill no)
			(layer "F.CrtYd")
		)
		(fp_rect
			(start -0.4318 0.9525)
			(end 0.4318 -0.9525)
			(stroke
				(width 0)
				(type default)
			)
			(fill no)
			(layer "F.Fab")
		)
		(pad "1" smd custom
			(at 0 -0.4445)
			(size 0.1524 0.1524)
			(layers "F.Cu" "F.Mask" "F.Paste")
			(net "P3V3_LL_R")
			(options
				(clearance outline)
				(anchor circle)
			)
			(primitives
				(gr_poly
					(pts
						(arc
							(start 0.3048 -0.2032)
							(mid 0.275042 -0.275042)
							(end 0.2032 -0.3048)
						)
						(arc
							(start -0.2032 -0.3048)
							(mid -0.275042 -0.275042)
							(end -0.3048 -0.2032)
						)
						(arc
							(start -0.3048 0.2032)
							(mid -0.275042 0.275042)
							(end -0.2032 0.3048)
						)
						(arc
							(start 0.2032 0.3048)
							(mid 0.275042 0.275042)
							(end 0.3048 0.2032)
						)
					)
					(width 0)
					(fill yes)
				)
			)
		)
		(pad "2" smd custom
			(at 0 0.4445)
			(size 0.1524 0.1524)
			(layers "F.Cu" "F.Mask" "F.Paste")
			(net "P3V3_VFB")
			(options
				(clearance outline)
				(anchor circle)
			)
			(primitives
				(gr_poly
					(pts
						(arc
							(start 0.3048 -0.2032)
							(mid 0.275042 -0.275042)
							(end 0.2032 -0.3048)
						)
						(arc
							(start -0.2032 -0.3048)
							(mid -0.275042 -0.275042)
							(end -0.3048 -0.2032)
						)
						(arc
							(start -0.3048 0.2032)
							(mid -0.275042 0.275042)
							(end -0.2032 0.3048)
						)
						(arc
							(start 0.2032 0.3048)
							(mid 0.275042 0.275042)
							(end 0.3048 0.2032)
						)
					)
					(width 0)
					(fill yes)
				)
			)
		)
	)
	(footprint ""
		(layer "F.Cu")
		(at 61.849 -24.13 90)
		(property "Reference" "C734"
			(at 0 0 90)
			(layer "F.SilkS")
			(hide yes)
			(effects
				(font
					(size 1.27 1.27)
				)
			)
		)
		(property "Value" "SCD1U16V2KX-3GP"
			(at 1.1811 -2.7051 90)
			(unlocked yes)
			(layer "F.Fab")
			(hide yes)
			(effects
				(font
					(size 1.016 1.016)
					(thickness 0.1524)
				)
			)
		)
		(property "Device Type" "C402H22"
			(at 1.1811 -4.2291 90)
			(unlocked yes)
			(layer "F.Fab")
			(hide yes)
			(effects
				(font
					(size 1.016 1.016)
					(thickness 0.1524)
				)
			)
		)
		(duplicate_pad_numbers_are_jumpers no)
		(fp_rect
			(start -0.4318 0.9525)
			(end 0.4318 -0.9525)
			(stroke
				(width 0)
				(type default)
			)
			(fill no)
			(layer "F.CrtYd")
		)
		(fp_rect
			(start -0.4318 0.9525)
			(end 0.4318 -0.9525)
			(stroke
				(width 0)
				(type default)
			)
			(fill no)
			(layer "F.Fab")
		)
		(pad "1" smd custom
			(at 0 -0.4445 90)
			(size 0.1524 0.1524)
			(layers "F.Cu" "F.Mask" "F.Paste")
			(net "P3V3")
			(options
				(clearance outline)
				(anchor circle)
			)
			(primitives
				(gr_poly
					(pts
						(arc
							(start 0.3048 -0.2032)
							(mid 0.275042 -0.275042)
							(end 0.2032 -0.3048)
						)
						(arc
							(start -0.2032 -0.3048)
							(mid -0.275042 -0.275042)
							(end -0.3048 -0.2032)
						)
						(arc
							(start -0.3048 0.2032)
							(mid -0.275042 0.275042)
							(end -0.2032 0.3048)
						)
						(arc
							(start 0.2032 0.3048)
							(mid 0.275042 0.275042)
							(end 0.3048 0.2032)
						)
					)
					(width 0)
					(fill yes)
				)
			)
		)
		(pad "2" smd custom
			(at 0 0.4445 90)
			(size 0.1524 0.1524)
			(layers "F.Cu" "F.Mask" "F.Paste")
			(net "GND")
			(options
				(clearance outline)
				(anchor circle)
			)
			(primitives
				(gr_poly
					(pts
						(arc
							(start 0.3048 -0.2032)
							(mid 0.275042 -0.275042)
							(end 0.2032 -0.3048)
						)
						(arc
							(start -0.2032 -0.3048)
							(mid -0.275042 -0.275042)
							(end -0.3048 -0.2032)
						)
						(arc
							(start -0.3048 0.2032)
							(mid -0.275042 0.275042)
							(end -0.2032 0.3048)
						)
						(arc
							(start 0.2032 0.3048)
							(mid 0.275042 0.275042)
							(end 0.3048 0.2032)
						)
					)
					(width 0)
					(fill yes)
				)
			)
		)
	)
	(footprint ""
		(layer "F.Cu")
		(at 187.0456 -116.6876 180)
		(property "Reference" "C691"
			(at 0 0 180)
			(layer "F.SilkS")
			(hide yes)
			(effects
				(font
					(size 1.27 1.27)
				)
			)
		)
		(property "Value" "SCD47U25V3KX-3-GP"
			(at 0 -2.8194 180)
			(unlocked yes)
			(layer "F.Fab")
			(hide yes)
			(effects
				(font
					(size 1.016 1.016)
					(thickness 0.1524)
				)
			)
		)
		(property "Device Type" "C603H36"
			(at 0 -4.3434 180)
			(unlocked yes)
			(layer "F.Fab")
			(hide yes)
			(effects
				(font
					(size 1.016 1.016)
					(thickness 0.1524)
				)
			)
		)
		(duplicate_pad_numbers_are_jumpers no)
		(fp_line
			(start 0.508 0)
			(end -0.508 0)
			(stroke
				(width 0.2032)
				(type default)
			)
			(layer "F.SilkS")
		)
		(fp_rect
			(start -0.5842 1.3335)
			(end 0.5842 -1.3335)
			(stroke
				(width 0)
				(type default)
			)
			(fill no)
			(layer "F.CrtYd")
		)
		(fp_rect
			(start -0.5842 1.3335)
			(end 0.5842 -1.3335)
			(stroke
				(width 0)
				(type default)
			)
			(fill no)
			(layer "F.Fab")
		)
		(pad "1" smd custom
			(at 0 -0.762 180)
			(size 0.2159 0.2159)
			(layers "F.Cu" "F.Mask" "F.Paste")
			(net "P1V8_C_G_PG")
			(options
				(clearance outline)
				(anchor circle)
			)
			(primitives
				(gr_poly
					(pts
						(arc
							(start -0.3302 -0.4318)
							(mid -0.402042 -0.402042)
							(end -0.4318 -0.3302)
						)
						(arc
							(start -0.4318 0.3302)
							(mid -0.402042 0.402042)
							(end -0.3302 0.4318)
						)
						(arc
							(start 0.3302 0.4318)
							(mid 0.402042 0.402042)
							(end 0.4318 0.3302)
						)
						(arc
							(start 0.4318 -0.3302)
							(mid 0.402042 -0.402042)
							(end 0.3302 -0.4318)
						)
					)
					(width 0)
					(fill yes)
				)
			)
		)
		(pad "2" smd custom
			(at 0 0.762 180)
			(size 0.2159 0.2159)
			(layers "F.Cu" "F.Mask" "F.Paste")
			(net "P1V8_C")
			(options
				(clearance outline)
				(anchor circle)
			)
			(primitives
				(gr_poly
					(pts
						(arc
							(start -0.3302 -0.4318)
							(mid -0.402042 -0.402042)
							(end -0.4318 -0.3302)
						)
						(arc
							(start -0.4318 0.3302)
							(mid -0.402042 0.402042)
							(end -0.3302 0.4318)
						)
						(arc
							(start 0.3302 0.4318)
							(mid 0.402042 0.402042)
							(end 0.4318 0.3302)
						)
						(arc
							(start 0.4318 -0.3302)
							(mid 0.402042 -0.402042)
							(end 0.3302 -0.4318)
						)
					)
					(width 0)
					(fill yes)
				)
			)
		)
	)
	(footprint ""
		(layer "F.Cu")
		(at 128.58623 -44.732448 180)
		(property "Reference" "C46"
			(at 0 0 180)
			(layer "F.SilkS")
			(hide yes)
			(effects
				(font
					(size 1.27 1.27)
				)
			)
		)
		(property "Value" "SCD01U16V1KX-GP"
			(at -2.8321 -1.7399 180)
			(unlocked yes)
			(layer "F.Fab")
			(hide yes)
			(effects
				(font
					(size 1.016 1.016)
					(thickness 0.1524)
				)
			)
		)
		(property "Device Type" "C0201H13"
			(at -2.8321 -3.2639 180)
			(unlocked yes)
			(layer "F.Fab")
			(hide yes)
			(effects
				(font
					(size 1.016 1.016)
					(thickness 0.1524)
				)
			)
		)
		(duplicate_pad_numbers_are_jumpers no)
		(fp_rect
			(start -0.2794 0.6477)
			(end 0.2794 -0.6477)
			(stroke
				(width 0)
				(type default)
			)
			(fill no)
			(layer "F.CrtYd")
		)
		(fp_rect
			(start -0.2794 0.6477)
			(end 0.2794 -0.6477)
			(stroke
				(width 0)
				(type default)
			)
			(fill no)
			(layer "F.Fab")
		)
		(pad "1" smd custom
			(at 0 -0.2794 180)
			(size 0.0762 0.0762)
			(layers "F.Cu" "F.Mask" "F.Paste")
			(net "PHY_IOC_TO_SCC_41_DN")
			(options
				(clearance outline)
				(anchor circle)
			)
			(primitives
				(gr_poly
					(pts
						(arc
							(start 0.1524 -0.127)
							(mid 0.137521 -0.162921)
							(end 0.1016 -0.1778)
						)
						(arc
							(start -0.1016 -0.1778)
							(mid -0.137521 -0.162921)
							(end -0.1524 -0.127)
						)
						(arc
							(start -0.1524 0.127)
							(mid -0.137521 0.162921)
							(end -0.1016 0.1778)
						)
						(arc
							(start 0.1016 0.1778)
							(mid 0.137521 0.162921)
							(end 0.1524 0.127)
						)
					)
					(width 0)
					(fill yes)
				)
			)
		)
		(pad "2" smd custom
			(at 0 0.2794 180)
			(size 0.0762 0.0762)
			(layers "F.Cu" "F.Mask" "F.Paste")
			(net "PHY_IOC_TO_SCC_C_41_DN")
			(options
				(clearance outline)
				(anchor circle)
			)
			(primitives
				(gr_poly
					(pts
						(arc
							(start 0.1524 -0.127)
							(mid 0.137521 -0.162921)
							(end 0.1016 -0.1778)
						)
						(arc
							(start -0.1016 -0.1778)
							(mid -0.137521 -0.162921)
							(end -0.1524 -0.127)
						)
						(arc
							(start -0.1524 0.127)
							(mid -0.137521 0.162921)
							(end -0.1016 0.1778)
						)
						(arc
							(start 0.1016 0.1778)
							(mid 0.137521 0.162921)
							(end 0.1524 0.127)
						)
					)
					(width 0)
					(fill yes)
				)
			)
		)
	)
	(footprint ""
		(layer "F.Cu")
		(at 87.660734 -83.7565 180)
		(property "Reference" "R129"
			(at 0 0 180)
			(layer "F.SilkS")
			(hide yes)
			(effects
				(font
					(size 1.27 1.27)
				)
			)
		)
		(property "Value" "10KR2F-2-GP"
			(at 0.064008 -3.993896 180)
			(unlocked yes)
			(layer "F.Fab")
			(hide yes)
			(effects
				(font
					(size 1.016 1.016)
					(thickness 0.1524)
				)
			)
		)
		(property "Device Type" "R402H16"
			(at 0.064008 -5.517896 180)
			(unlocked yes)
			(layer "F.Fab")
			(hide yes)
			(effects
				(font
					(size 1.016 1.016)
					(thickness 0.1524)
				)
			)
		)
		(duplicate_pad_numbers_are_jumpers no)
		(fp_line
			(start 0.508 -0.9398)
			(end -0.508 -0.9398)
			(stroke
				(width 0.1524)
				(type default)
			)
			(layer "F.SilkS")
		)
		(fp_line
			(start -0.508 -0.9398)
			(end -0.508 0.9398)
			(stroke
				(width 0.1524)
				(type default)
			)
			(layer "F.SilkS")
		)
		(fp_rect
			(start -0.508 0.9398)
			(end 0.508 -0.9398)
			(stroke
				(width 0)
				(type default)
			)
			(fill no)
			(layer "F.CrtYd")
		)
		(fp_rect
			(start -0.508 0.9398)
			(end 0.508 -0.9398)
			(stroke
				(width 0)
				(type default)
			)
			(fill no)
			(layer "F.Fab")
		)
		(pad "1" smd custom
			(at 0 -0.4445 180)
			(size 0.1397 0.1397)
			(layers "F.Cu" "F.Mask" "F.Paste")
			(net "P3V3")
			(options
				(clearance outline)
				(anchor circle)
			)
			(primitives
				(gr_poly
					(pts
						(arc
							(start -0.1778 -0.2794)
							(mid -0.249642 -0.249642)
							(end -0.2794 -0.1778)
						)
						(arc
							(start -0.2794 0.1778)
							(mid -0.249642 0.249642)
							(end -0.1778 0.2794)
						)
						(arc
							(start 0.1778 0.2794)
							(mid 0.249642 0.249642)
							(end 0.2794 0.1778)
						)
						(arc
							(start 0.2794 -0.1778)
							(mid 0.249642 -0.249642)
							(end 0.1778 -0.2794)
						)
					)
					(width 0)
					(fill yes)
				)
			)
		)
		(pad "2" smd custom
			(at 0 0.4445 180)
			(size 0.1397 0.1397)
			(layers "F.Cu" "F.Mask" "F.Paste")
			(net "RESET_SENSE")
			(options
				(clearance outline)
				(anchor circle)
			)
			(primitives
				(gr_poly
					(pts
						(arc
							(start -0.1778 -0.2794)
							(mid -0.249642 -0.249642)
							(end -0.2794 -0.1778)
						)
						(arc
							(start -0.2794 0.1778)
							(mid -0.249642 0.249642)
							(end -0.1778 0.2794)
						)
						(arc
							(start 0.1778 0.2794)
							(mid 0.249642 0.249642)
							(end 0.2794 0.1778)
						)
						(arc
							(start 0.2794 -0.1778)
							(mid 0.249642 -0.249642)
							(end 0.1778 -0.2794)
						)
					)
					(width 0)
					(fill yes)
				)
			)
		)
	)
	(footprint ""
		(layer "F.Cu")
		(at 124.6632 -112.62868)
		(property "Reference" "TP21"
			(at 0 0 0)
			(layer "F.SilkS")
			(hide yes)
			(effects
				(font
					(size 1.27 1.27)
				)
			)
		)
		(property "Value" "TPAD28-2-GP"
			(at -0.0127 -1.6637 0)
			(unlocked yes)
			(layer "F.Fab")
			(hide yes)
			(effects
				(font
					(size 1.016 1.016)
					(thickness 0.1524)
				)
			)
		)
		(property "Device Type" "TPAD28"
			(at -0.0127 -3.1877 0)
			(unlocked yes)
			(layer "F.Fab")
			(hide yes)
			(effects
				(font
					(size 1.016 1.016)
					(thickness 0.1524)
				)
			)
		)
		(duplicate_pad_numbers_are_jumpers no)
		(fp_poly
			(pts
				(arc
					(start 0.3556 0)
					(mid -0.3556 0)
					(end 0.3556 0)
				)
			)
			(stroke
				(width 0)
				(type default)
			)
			(fill no)
			(layer "F.CrtYd")
		)
		(fp_poly
			(pts
				(arc
					(start 0.6096 0)
					(mid -0.6096 0)
					(end 0.6096 0)
				)
			)
			(stroke
				(width 0)
				(type default)
			)
			(fill no)
			(layer "F.Fab")
		)
		(pad "1" smd circle
			(at 0 0)
			(size 0.7112 0.7112)
			(layers "F.Cu" "F.Mask" "F.Paste")
			(net "INT_A1_CONN1")
		)
	)
	(footprint ""
		(layer "F.Cu")
		(at 181.8132 -97.6884 180)
		(property "Reference" "R285"
			(at 0 0 180)
			(layer "F.SilkS")
			(hide yes)
			(effects
				(font
					(size 1.27 1.27)
				)
			)
		)
		(property "Value" "D51R3F-2-GP"
			(at -0.0254 -2.5146 180)
			(unlocked yes)
			(layer "F.Fab")
			(hide yes)
			(effects
				(font
					(size 1.016 1.016)
					(thickness 0.1524)
				)
			)
		)
		(property "Device Type" "R603H22"
			(at -0.0254 -4.0386 180)
			(unlocked yes)
			(layer "F.Fab")
			(hide yes)
			(effects
				(font
					(size 1.016 1.016)
					(thickness 0.1524)
				)
			)
		)
		(duplicate_pad_numbers_are_jumpers no)
		(fp_line
			(start 0.2032 0)
			(end 0.4826 0)
			(stroke
				(width 0.2032)
				(type default)
			)
			(layer "F.SilkS")
		)
		(fp_line
			(start -0.4826 0)
			(end -0.2032 0)
			(stroke
				(width 0.2032)
				(type default)
			)
			(layer "F.SilkS")
		)
		(fp_rect
			(start -0.5842 1.3335)
			(end 0.5842 -1.3335)
			(stroke
				(width 0)
				(type default)
			)
			(fill no)
			(layer "F.CrtYd")
		)
		(fp_rect
			(start -0.5842 1.3335)
			(end 0.5842 -1.3335)
			(stroke
				(width 0)
				(type default)
			)
			(fill no)
			(layer "F.Fab")
		)
		(pad "1" smd custom
			(at 0 -0.762 180)
			(size 0.2159 0.2159)
			(layers "F.Cu" "F.Mask" "F.Paste")
			(net "P0V975")
			(options
				(clearance outline)
				(anchor circle)
			)
			(primitives
				(gr_poly
					(pts
						(arc
							(start -0.3302 -0.4318)
							(mid -0.402042 -0.402042)
							(end -0.4318 -0.3302)
						)
						(arc
							(start -0.4318 0.3302)
							(mid -0.402042 0.402042)
							(end -0.3302 0.4318)
						)
						(arc
							(start 0.3302 0.4318)
							(mid 0.402042 0.402042)
							(end 0.4318 0.3302)
						)
						(arc
							(start 0.4318 -0.3302)
							(mid 0.402042 -0.402042)
							(end 0.3302 -0.4318)
						)
					)
					(width 0)
					(fill yes)
				)
			)
		)
		(pad "2" smd custom
			(at 0 0.762 180)
			(size 0.2159 0.2159)
			(layers "F.Cu" "F.Mask" "F.Paste")
			(net "SAS0_AVDD")
			(options
				(clearance outline)
				(anchor circle)
			)
			(primitives
				(gr_poly
					(pts
						(arc
							(start -0.3302 -0.4318)
							(mid -0.402042 -0.402042)
							(end -0.4318 -0.3302)
						)
						(arc
							(start -0.4318 0.3302)
							(mid -0.402042 0.402042)
							(end -0.3302 0.4318)
						)
						(arc
							(start 0.3302 0.4318)
							(mid 0.402042 0.402042)
							(end 0.4318 0.3302)
						)
						(arc
							(start 0.4318 -0.3302)
							(mid 0.402042 -0.402042)
							(end 0.3302 -0.4318)
						)
					)
					(width 0)
					(fill yes)
				)
			)
		)
	)
	(footprint ""
		(layer "F.Cu")
		(at 173.7614 -112.0013 90)
		(property "Reference" "R93"
			(at 0 0 90)
			(layer "F.SilkS")
			(hide yes)
			(effects
				(font
					(size 1.27 1.27)
				)
			)
		)
		(property "Value" "4K75R2F-1-GP"
			(at 0.064008 -3.993896 90)
			(unlocked yes)
			(layer "F.Fab")
			(hide yes)
			(effects
				(font
					(size 1.016 1.016)
					(thickness 0.1524)
				)
			)
		)
		(property "Device Type" "R402H16"
			(at 0.064008 -5.517896 90)
			(unlocked yes)
			(layer "F.Fab")
			(hide yes)
			(effects
				(font
					(size 1.016 1.016)
					(thickness 0.1524)
				)
			)
		)
		(duplicate_pad_numbers_are_jumpers no)
		(fp_line
			(start 0.508 -0.9398)
			(end -0.508 -0.9398)
			(stroke
				(width 0.1524)
				(type default)
			)
			(layer "F.SilkS")
		)
		(fp_line
			(start -0.508 -0.9398)
			(end -0.508 0.9398)
			(stroke
				(width 0.1524)
				(type default)
			)
			(layer "F.SilkS")
		)
		(fp_rect
			(start -0.508 0.9398)
			(end 0.508 -0.9398)
			(stroke
				(width 0)
				(type default)
			)
			(fill no)
			(layer "F.CrtYd")
		)
		(fp_rect
			(start -0.508 0.9398)
			(end 0.508 -0.9398)
			(stroke
				(width 0)
				(type default)
			)
			(fill no)
			(layer "F.Fab")
		)
		(pad "1" smd custom
			(at 0 -0.4445 90)
			(size 0.1397 0.1397)
			(layers "F.Cu" "F.Mask" "F.Paste")
			(net "P3V3")
			(options
				(clearance outline)
				(anchor circle)
			)
			(primitives
				(gr_poly
					(pts
						(arc
							(start -0.1778 -0.2794)
							(mid -0.249642 -0.249642)
							(end -0.2794 -0.1778)
						)
						(arc
							(start -0.2794 0.1778)
							(mid -0.249642 0.249642)
							(end -0.1778 0.2794)
						)
						(arc
							(start 0.1778 0.2794)
							(mid 0.249642 0.249642)
							(end 0.2794 0.1778)
						)
						(arc
							(start 0.2794 -0.1778)
							(mid 0.249642 -0.249642)
							(end 0.1778 -0.2794)
						)
					)
					(width 0)
					(fill yes)
				)
			)
		)
		(pad "2" smd custom
			(at 0 0.4445 90)
			(size 0.1397 0.1397)
			(layers "F.Cu" "F.Mask" "F.Paste")
			(net "P1V8_E_EN")
			(options
				(clearance outline)
				(anchor circle)
			)
			(primitives
				(gr_poly
					(pts
						(arc
							(start -0.1778 -0.2794)
							(mid -0.249642 -0.249642)
							(end -0.2794 -0.1778)
						)
						(arc
							(start -0.2794 0.1778)
							(mid -0.249642 0.249642)
							(end -0.1778 0.2794)
						)
						(arc
							(start 0.1778 0.2794)
							(mid 0.249642 0.249642)
							(end 0.2794 0.1778)
						)
						(arc
							(start 0.2794 -0.1778)
							(mid 0.249642 -0.249642)
							(end 0.1778 -0.2794)
						)
					)
					(width 0)
					(fill yes)
				)
			)
		)
	)
	(footprint ""
		(layer "F.Cu")
		(at 139.310618 -64.972184)
		(property "Reference" "VIA16"
			(at 0 0 0)
			(layer "F.SilkS")
			(hide yes)
			(effects
				(font
					(size 1.27 1.27)
				)
			)
		)
		(property "Value" "100OHM-8L-1D6MM-L13-GP"
			(at 3.2893 0.0508 0)
			(unlocked yes)
			(layer "F.Fab")
			(hide yes)
			(effects
				(font
					(size 1.016 1.016)
					(thickness 0.1524)
				)
			)
		)
		(property "Device Type" "VIA-PCIE-4P-409091"
			(at 3.2893 -1.4732 0)
			(unlocked yes)
			(layer "F.Fab")
			(hide yes)
			(effects
				(font
					(size 1.016 1.016)
					(thickness 0.1524)
				)
			)
		)
		(duplicate_pad_numbers_are_jumpers no)
		(fp_rect
			(start -2.0447 0.4572)
			(end 2.0447 -0.4572)
			(stroke
				(width 0)
				(type default)
			)
			(fill no)
			(layer "F.CrtYd")
		)
		(fp_rect
			(start -2.0447 0.4572)
			(end 2.0447 -0.4572)
			(stroke
				(width 0)
				(type default)
			)
			(fill no)
			(layer "F.Fab")
		)
		(pad "1" thru_hole circle
			(at -1.5875 0)
			(size 0.508 0.508)
			(drill 0.254)
			(layers "*.Cu" "*.Mask")
			(remove_unused_layers no)
			(net "GND")
			(clearance 0.2032)
			(thermal_gap 0.2032)
		)
		(pad "2" thru_hole circle
			(at -0.5715 0)
			(size 0.508 0.508)
			(drill 0.254)
			(layers "*.Cu" "*.Mask")
			(remove_unused_layers no)
			(net "PHY_IOC_TO_SCC_C_47_DP")
			(clearance 0.2032)
			(thermal_gap 0.2032)
		)
		(pad "3" thru_hole circle
			(at 0.5715 0)
			(size 0.508 0.508)
			(drill 0.254)
			(layers "*.Cu" "*.Mask")
			(remove_unused_layers no)
			(net "PHY_IOC_TO_SCC_C_47_DN")
			(clearance 0.2032)
			(thermal_gap 0.2032)
		)
		(pad "4" thru_hole circle
			(at 1.5875 0)
			(size 0.508 0.508)
			(drill 0.254)
			(layers "*.Cu" "*.Mask")
			(remove_unused_layers no)
			(net "GND")
			(clearance 0.2032)
			(thermal_gap 0.2032)
		)
	)
	(footprint ""
		(layer "F.Cu")
		(at 41.86174 -36.939474 180)
		(property "Reference" "C604"
			(at 0 0 180)
			(layer "F.SilkS")
			(hide yes)
			(effects
				(font
					(size 1.27 1.27)
				)
			)
		)
		(property "Value" "SCD1U16V2KX-3GP"
			(at 1.1811 -2.7051 180)
			(unlocked yes)
			(layer "F.Fab")
			(hide yes)
			(effects
				(font
					(size 1.016 1.016)
					(thickness 0.1524)
				)
			)
		)
		(property "Device Type" "C402H22"
			(at 1.1811 -4.2291 180)
			(unlocked yes)
			(layer "F.Fab")
			(hide yes)
			(effects
				(font
					(size 1.016 1.016)
					(thickness 0.1524)
				)
			)
		)
		(duplicate_pad_numbers_are_jumpers no)
		(fp_rect
			(start -0.4318 0.9525)
			(end 0.4318 -0.9525)
			(stroke
				(width 0)
				(type default)
			)
			(fill no)
			(layer "F.CrtYd")
		)
		(fp_rect
			(start -0.4318 0.9525)
			(end 0.4318 -0.9525)
			(stroke
				(width 0)
				(type default)
			)
			(fill no)
			(layer "F.Fab")
		)
		(pad "1" smd custom
			(at 0 -0.4445 180)
			(size 0.1524 0.1524)
			(layers "F.Cu" "F.Mask" "F.Paste")
			(net "P0V9_BST")
			(options
				(clearance outline)
				(anchor circle)
			)
			(primitives
				(gr_poly
					(pts
						(arc
							(start 0.3048 -0.2032)
							(mid 0.275042 -0.275042)
							(end 0.2032 -0.3048)
						)
						(arc
							(start -0.2032 -0.3048)
							(mid -0.275042 -0.275042)
							(end -0.3048 -0.2032)
						)
						(arc
							(start -0.3048 0.2032)
							(mid -0.275042 0.275042)
							(end -0.2032 0.3048)
						)
						(arc
							(start 0.2032 0.3048)
							(mid 0.275042 0.275042)
							(end 0.3048 0.2032)
						)
					)
					(width 0)
					(fill yes)
				)
			)
		)
		(pad "2" smd custom
			(at 0 0.4445 180)
			(size 0.1524 0.1524)
			(layers "F.Cu" "F.Mask" "F.Paste")
			(net "P0V9_BST_R")
			(options
				(clearance outline)
				(anchor circle)
			)
			(primitives
				(gr_poly
					(pts
						(arc
							(start 0.3048 -0.2032)
							(mid 0.275042 -0.275042)
							(end 0.2032 -0.3048)
						)
						(arc
							(start -0.2032 -0.3048)
							(mid -0.275042 -0.275042)
							(end -0.3048 -0.2032)
						)
						(arc
							(start -0.3048 0.2032)
							(mid -0.275042 0.275042)
							(end -0.2032 0.3048)
						)
						(arc
							(start 0.2032 0.3048)
							(mid 0.275042 0.275042)
							(end 0.3048 0.2032)
						)
					)
					(width 0)
					(fill yes)
				)
			)
		)
	)
	(footprint ""
		(layer "F.Cu")
		(at 105.000044 -117.00002 180)
		(property "Reference" "MSAS1"
			(at 0 0 180)
			(layer "F.SilkS")
			(hide yes)
			(effects
				(font
					(size 1.27 1.27)
				)
			)
		)
		(property "Value" "MLX-CONN36-12R-1-GP-U"
			(at 19.4564 -15.1257 180)
			(unlocked yes)
			(layer "F.Fab")
			(hide yes)
			(effects
				(font
					(size 1.016 1.016)
					(thickness 0.1524)
				)
			)
		)
		(property "Device Type" "PREFIT-36P-152240-UH561"
			(at 19.4564 -16.6497 180)
			(unlocked yes)
			(layer "F.Fab")
			(hide yes)
			(effects
				(font
					(size 1.016 1.016)
					(thickness 0.1524)
				)
			)
		)
		(duplicate_pad_numbers_are_jumpers no)
		(fp_line
			(start 7.8359 2.5908)
			(end 7.3406 2.5908)
			(stroke
				(width 0.1524)
				(type default)
			)
			(layer "F.SilkS")
		)
		(fp_line
			(start 7.8359 -2.7432)
			(end 7.8359 2.5908)
			(stroke
				(width 0.1524)
				(type default)
			)
			(layer "F.SilkS")
		)
		(fp_line
			(start 7.3406 9.2456)
			(end -7.3406 9.2456)
			(stroke
				(width 0.1524)
				(type default)
			)
			(layer "F.SilkS")
		)
		(fp_line
			(start 7.3406 2.5908)
			(end 7.3406 9.2456)
			(stroke
				(width 0.1524)
				(type default)
			)
			(layer "F.SilkS")
		)
		(fp_line
			(start 5.4991 -2.7432)
			(end 7.8359 -2.7432)
			(stroke
				(width 0.1524)
				(type default)
			)
			(layer "F.SilkS")
		)
		(fp_line
			(start 5.4991 -15.2654)
			(end 5.4991 -2.7432)
			(stroke
				(width 0.1524)
				(type default)
			)
			(layer "F.SilkS")
		)
		(fp_line
			(start -5.4991 -2.7432)
			(end -5.4991 -15.2654)
			(stroke
				(width 0.1524)
				(type default)
			)
			(layer "F.SilkS")
		)
		(fp_line
			(start -5.4991 -15.2654)
			(end 5.4991 -15.2654)
			(stroke
				(width 0.1524)
				(type default)
			)
			(layer "F.SilkS")
		)
		(fp_line
			(start -7.3406 9.2456)
			(end -7.3406 2.5908)
			(stroke
				(width 0.1524)
				(type default)
			)
			(layer "F.SilkS")
		)
		(fp_line
			(start -7.3406 2.5908)
			(end -7.8359 2.5908)
			(stroke
				(width 0.1524)
				(type default)
			)
			(layer "F.SilkS")
		)
		(fp_line
			(start -7.8359 2.5908)
			(end -7.8359 -2.7432)
			(stroke
				(width 0.1524)
				(type default)
			)
			(layer "F.SilkS")
		)
		(fp_line
			(start -7.8359 -2.7432)
			(end -5.4991 -2.7432)
			(stroke
				(width 0.1524)
				(type default)
			)
			(layer "F.SilkS")
		)
		(fp_poly
			(pts
				(xy -7.3406 9.2456) (xy -7.3406 2.5908) (xy -7.8359 2.5908) (xy -7.8359 -2.7432) (xy -5.4991 -2.7432)
				(xy -5.4991 -15.2654) (xy 5.4991 -15.2654) (xy 5.4991 -2.7432) (xy 7.8359 -2.7432) (xy 7.8359 2.5908)
				(xy 7.3406 2.5908) (xy 7.3406 9.2456)
			)
			(stroke
				(width 0)
				(type default)
			)
			(fill yes)
			(layer "F.SilkS")
		)
		(fp_poly
			(pts
				(arc
					(start -3.7084 -0.855218)
					(mid -4.0894 -0.474218)
					(end -4.4704 -0.855218)
				)
				(arc
					(start -4.4704 -1.998218)
					(mid -4.0894 -2.379218)
					(end -3.7084 -1.998218)
				)
			)
			(stroke
				(width 0)
				(type default)
			)
			(fill yes)
			(layer "F.SilkS")
		)
		(fp_poly
			(pts
				(arc
					(start -3.7084 -4.655312)
					(mid -4.0894 -4.274312)
					(end -4.4704 -4.655312)
				)
				(arc
					(start -4.4704 -5.798312)
					(mid -4.0894 -6.179312)
					(end -3.7084 -5.798312)
				)
			)
			(stroke
				(width 0)
				(type default)
			)
			(fill yes)
			(layer "F.SilkS")
		)
		(fp_poly
			(pts
				(arc
					(start -3.7084 -8.455406)
					(mid -4.0894 -8.074406)
					(end -4.4704 -8.455406)
				)
				(arc
					(start -4.4704 -9.598406)
					(mid -4.0894 -9.979406)
					(end -3.7084 -9.598406)
				)
			)
			(stroke
				(width 0)
				(type default)
			)
			(fill yes)
			(layer "F.SilkS")
		)
		(fp_poly
			(pts
				(arc
					(start -3.7084 -12.2555)
					(mid -4.0894 -11.8745)
					(end -4.4704 -12.2555)
				)
				(arc
					(start -4.4704 -13.3985)
					(mid -4.0894 -13.7795)
					(end -3.7084 -13.3985)
				)
			)
			(stroke
				(width 0)
				(type default)
			)
			(fill yes)
			(layer "F.SilkS")
		)
		(fp_poly
			(pts
				(xy -12.1158 6.1214) (xy 12.1158 6.1214) (xy 12.1158 -6.1087) (xy 8.3693 -6.1087) (xy 8.3693 -18.923)
				(xy -8.3693 -18.923) (xy -8.3693 -6.1087) (xy -12.1158 -6.1087)
			)
			(stroke
				(width 0)
				(type default)
			)
			(fill no)
			(layer "B.CrtYd")
		)
		(fp_poly
			(pts
				(xy -7.0866 8.9916) (xy -7.0866 2.3368) (xy -7.5819 2.3368) (xy -7.5819 -2.4892) (xy -5.2451 -2.4892)
				(xy -5.2451 -15.0114) (xy 5.2451 -15.0114) (xy 5.2451 -2.4892) (xy 7.5819 -2.4892) (xy 7.5819 2.3368)
				(xy 7.0866 2.3368) (xy 7.0866 8.9916)
			)
			(stroke
				(width 0)
				(type default)
			)
			(fill no)
			(layer "F.CrtYd")
		)
		(fp_poly
			(pts
				(xy 12.0904 13.9954) (xy 12.0904 7.3406) (xy 12.5857 7.3406) (xy 12.5857 -7.493) (xy 10.2489 -7.493)
				(xy 10.2489 -10.3632) (xy 5.7531 -10.3632) (xy 5.7531 -2.9972) (xy 8.0899 -2.9972) (xy 8.0899 2.8448)
				(xy 7.5946 2.8448) (xy 7.5946 9.4996) (xy -7.5946 9.4996) (xy -7.5946 2.8448) (xy -8.0899 2.8448)
				(xy -8.0899 -2.9972) (xy -5.7531 -2.9972) (xy -5.7531 -15.5194) (xy 5.7531 -15.5194) (xy 5.7531 -10.3759)
				(xy 10.2489 -10.3759) (xy 10.2489 -20.0152) (xy -10.2489 -20.0152) (xy -10.2489 -7.493) (xy -12.5857 -7.493)
				(xy -12.5857 7.3406) (xy -12.0904 7.3406) (xy -12.0904 13.9954)
			)
			(stroke
				(width 0)
				(type default)
			)
			(fill no)
			(layer "F.CrtYd")
		)
		(fp_poly
			(pts
				(xy -7.5946 9.4996) (xy -7.5946 2.8448) (xy -8.0899 2.8448) (xy -8.0899 -2.9972) (xy -5.7531 -2.9972)
				(xy -5.7531 -15.5194) (xy 5.7531 -15.5194) (xy 5.7531 -2.9972) (xy 8.0899 -2.9972) (xy 8.0899 -0.00635)
				(xy 7.5819 -0.00635) (xy 7.5819 -2.4892) (xy 5.2451 -2.4892) (xy 5.2451 -15.0114) (xy -5.2451 -15.0114)
				(xy -5.2451 -2.4892) (xy -7.5819 -2.4892) (xy -7.5819 2.3368) (xy -7.0866 2.3368) (xy -7.0866 8.9916)
				(xy 7.0866 8.9916) (xy 7.0866 2.3368) (xy 7.5819 2.3368) (xy 7.5819 0.00635) (xy 8.0899 0.00635)
				(xy 8.0899 2.8448) (xy 7.5946 2.8448) (xy 7.5946 9.4996)
			)
			(stroke
				(width 0)
				(type default)
			)
			(fill no)
			(layer "F.CrtYd")
		)
		(fp_poly
			(pts
				(xy -12.1158 6.1214) (xy -12.1158 -6.1087) (xy -8.3693 -6.1087) (xy -8.3693 -18.923) (xy 8.3693 -18.923)
				(xy 8.3693 -6.1087) (xy 12.1158 -6.1087) (xy 12.1158 6.1214)
			)
			(stroke
				(width 0)
				(type default)
			)
			(fill no)
			(layer "B.Fab")
		)
		(fp_poly
			(pts
				(xy -17.1196 11.1252) (xy -17.1196 -11.1125) (xy -13.3731 -11.1125) (xy -13.3731 -23.9268) (xy 13.3731 -23.9268)
				(xy 13.3731 -11.1125) (xy 17.1196 -11.1125) (xy 17.1196 11.1252)
			)
			(stroke
				(width 0)
				(type default)
			)
			(fill no)
			(layer "B.Fab")
		)
		(fp_poly
			(pts
				(xy -7.5946 9.4996) (xy -7.5946 2.8448) (xy -8.0899 2.8448) (xy -8.0899 -2.9972) (xy -5.7531 -2.9972)
				(xy -5.7531 -15.5194) (xy 5.7531 -15.5194) (xy 5.7531 -2.9972) (xy 8.0899 -2.9972) (xy 8.0899 2.8448)
				(xy 7.5946 2.8448) (xy 7.5946 9.4996)
			)
			(stroke
				(width 0)
				(type default)
			)
			(fill no)
			(layer "F.Fab")
		)
		(fp_poly
			(pts
				(xy -12.0904 13.9954) (xy -12.0904 7.3406) (xy -12.5857 7.3406) (xy -12.5857 -7.493) (xy -10.2489 -7.493)
				(xy -10.2489 -20.0152) (xy 10.2489 -20.0152) (xy 10.2489 -7.493) (xy 12.5857 -7.493) (xy 12.5857 7.3406)
				(xy 12.0904 7.3406) (xy 12.0904 13.9954)
			)
			(stroke
				(width 0)
				(type default)
			)
			(fill no)
			(layer "F.Fab")
		)
		(fp_poly
			(pts
				(xy -17.0942 18.9992) (xy -17.0942 12.3444) (xy -17.5895 12.3444) (xy -17.5895 -12.4968) (xy -15.2527 -12.4968)
				(xy -15.2527 -25.019) (xy 15.2527 -25.019) (xy 15.2527 -12.4968) (xy 17.5895 -12.4968) (xy 17.5895 12.3444)
				(xy 17.0942 12.3444) (xy 17.0942 18.9992)
			)
			(stroke
				(width 0)
				(type default)
			)
			(fill no)
			(layer "F.Fab")
		)
		(fp_text user "Press Fit"
			(at -4.9022 2.5908 180)
			(unlocked yes)
			(layer "F.SilkS")
			(effects
				(font
					(size 1.016 1.016)
					(thickness 0.1524)
				)
				(justify left)
			)
		)
		(fp_text user "Can not place BGA,CSP,Wave Solder Component."
			(at -21.4249 10.2108 180)
			(unlocked yes)
			(layer "B.Fab")
			(effects
				(font
					(size 1.016 1.016)
					(thickness 0.1524)
				)
				(justify left)
			)
		)
		(fp_text user "High Limit 2mm"
			(at -8.128 12.7508 180)
			(unlocked yes)
			(layer "F.Fab")
			(effects
				(font
					(size 1.016 1.016)
					(thickness 0.1524)
				)
				(justify left)
			)
		)
		(fp_text user "Can not place BGA,CSP,Wave Solder Component."
			(at -21.4884 16.5227 180)
			(unlocked yes)
			(layer "F.Fab")
			(effects
				(font
					(size 1.016 1.016)
					(thickness 0.1524)
				)
				(justify left)
			)
		)
		(pad "" np_thru_hole circle
			(at -5.999988 0 180)
			(size 0.254 0.254)
			(drill 2.2098)
			(layers "*.Cu" "*.Mask")
			(clearance 1.3335)
			(thermal_gap 1.3335)
		)
		(pad "" np_thru_hole circle
			(at 5.999988 0 180)
			(size 0.254 0.254)
			(drill 2.2098)
			(layers "*.Cu" "*.Mask")
			(clearance 1.3335)
			(thermal_gap 1.3335)
		)
		(pad "A1" thru_hole circle
			(at -2.999994 -2.15011 180)
			(size 0.7366 0.7366)
			(drill 0.369824)
			(layers "*.Cu" "*.Mask")
			(remove_unused_layers no)
			(net "INT_A1_CONN1")
			(clearance 0.1778)
			(thermal_gap 0.1778)
		)
		(pad "A2" thru_hole circle
			(at -2.249932 -0.750062 180)
			(size 0.7366 0.7366)
			(drill 0.369824)
			(layers "*.Cu" "*.Mask")
			(remove_unused_layers no)
			(net "INT_A2_CONN1")
			(clearance 0.1778)
			(thermal_gap 0.1778)
		)
		(pad "A3" thru_hole circle
			(at -1.500124 -1.450086 180)
			(size 0.7366 0.7366)
			(drill 0.369824)
			(layers "*.Cu" "*.Mask")
			(remove_unused_layers no)
			(net "GND")
			(clearance 0.1778)
			(thermal_gap 0.1778)
		)
		(pad "A4" thru_hole circle
			(at -0.750062 -2.15011 180)
			(size 0.7366 0.7366)
			(drill 0.369824)
			(layers "*.Cu" "*.Mask")
			(remove_unused_layers no)
			(net "PHY_CONN_TO_EXP_8_DP")
			(clearance 0.1778)
			(thermal_gap 0.1778)
		)
		(pad "A5" thru_hole circle
			(at 0 -0.750062 180)
			(size 0.7366 0.7366)
			(drill 0.369824)
			(layers "*.Cu" "*.Mask")
			(remove_unused_layers no)
			(net "PHY_CONN_TO_EXP_8_DN")
			(clearance 0.1778)
			(thermal_gap 0.1778)
		)
		(pad "A6" thru_hole circle
			(at 0.750062 -1.450086 180)
			(size 0.7366 0.7366)
			(drill 0.369824)
			(layers "*.Cu" "*.Mask")
			(remove_unused_layers no)
			(net "GND")
			(clearance 0.1778)
			(thermal_gap 0.1778)
		)
		(pad "A7" thru_hole circle
			(at 1.500124 -2.15011 180)
			(size 0.7366 0.7366)
			(drill 0.369824)
			(layers "*.Cu" "*.Mask")
			(remove_unused_layers no)
			(net "PHY_CONN_TO_EXP_9_DP")
			(clearance 0.1778)
			(thermal_gap 0.1778)
		)
		(pad "A8" thru_hole circle
			(at 2.249932 -0.750062 180)
			(size 0.7366 0.7366)
			(drill 0.369824)
			(layers "*.Cu" "*.Mask")
			(remove_unused_layers no)
			(net "PHY_CONN_TO_EXP_9_DN")
			(clearance 0.1778)
			(thermal_gap 0.1778)
		)
		(pad "A9" thru_hole circle
			(at 2.999994 -1.450086 180)
			(size 0.7366 0.7366)
			(drill 0.369824)
			(layers "*.Cu" "*.Mask")
			(remove_unused_layers no)
			(net "GND")
			(clearance 0.1778)
			(thermal_gap 0.1778)
		)
		(pad "B1" thru_hole circle
			(at -2.999994 -5.94995 180)
			(size 0.7366 0.7366)
			(drill 0.369824)
			(layers "*.Cu" "*.Mask")
			(remove_unused_layers no)
			(net "INT_B1_CONN1")
			(clearance 0.1778)
			(thermal_gap 0.1778)
		)
		(pad "B2" thru_hole circle
			(at -2.249932 -4.549902 180)
			(size 0.7366 0.7366)
			(drill 0.369824)
			(layers "*.Cu" "*.Mask")
			(remove_unused_layers no)
			(net "INT_B2_CONN1")
			(clearance 0.1778)
			(thermal_gap 0.1778)
		)
		(pad "B3" thru_hole circle
			(at -1.500124 -5.249926 180)
			(size 0.7366 0.7366)
			(drill 0.369824)
			(layers "*.Cu" "*.Mask")
			(remove_unused_layers no)
			(net "GND")
			(clearance 0.1778)
			(thermal_gap 0.1778)
		)
		(pad "B4" thru_hole circle
			(at -0.750062 -5.94995 180)
			(size 0.7366 0.7366)
			(drill 0.369824)
			(layers "*.Cu" "*.Mask")
			(remove_unused_layers no)
			(net "PHY_CONN_TO_EXP_10_DP")
			(clearance 0.1778)
			(thermal_gap 0.1778)
		)
		(pad "B5" thru_hole circle
			(at 0 -4.549902 180)
			(size 0.7366 0.7366)
			(drill 0.369824)
			(layers "*.Cu" "*.Mask")
			(remove_unused_layers no)
			(net "PHY_CONN_TO_EXP_10_DN")
			(clearance 0.1778)
			(thermal_gap 0.1778)
		)
		(pad "B6" thru_hole circle
			(at 0.750062 -5.249926 180)
			(size 0.7366 0.7366)
			(drill 0.369824)
			(layers "*.Cu" "*.Mask")
			(remove_unused_layers no)
			(net "GND")
			(clearance 0.1778)
			(thermal_gap 0.1778)
		)
		(pad "B7" thru_hole circle
			(at 1.500124 -5.94995 180)
			(size 0.7366 0.7366)
			(drill 0.369824)
			(layers "*.Cu" "*.Mask")
			(remove_unused_layers no)
			(net "PHY_CONN_TO_EXP_11_DP")
			(clearance 0.1778)
			(thermal_gap 0.1778)
		)
		(pad "B8" thru_hole circle
			(at 2.249932 -4.549902 180)
			(size 0.7366 0.7366)
			(drill 0.369824)
			(layers "*.Cu" "*.Mask")
			(remove_unused_layers no)
			(net "PHY_CONN_TO_EXP_11_DN")
			(clearance 0.1778)
			(thermal_gap 0.1778)
		)
		(pad "B9" thru_hole circle
			(at 2.999994 -5.249926 180)
			(size 0.7366 0.7366)
			(drill 0.369824)
			(layers "*.Cu" "*.Mask")
			(remove_unused_layers no)
			(net "GND")
			(clearance 0.1778)
			(thermal_gap 0.1778)
		)
		(pad "C1" thru_hole circle
			(at -2.999994 -9.750044 180)
			(size 0.7366 0.7366)
			(drill 0.369824)
			(layers "*.Cu" "*.Mask")
			(remove_unused_layers no)
			(net "INT_C1_CONN1")
			(clearance 0.1778)
			(thermal_gap 0.1778)
		)
		(pad "C2" thru_hole circle
			(at -2.249932 -8.349996 180)
			(size 0.7366 0.7366)
			(drill 0.369824)
			(layers "*.Cu" "*.Mask")
			(remove_unused_layers no)
			(net "INT_C2_CONN1")
			(clearance 0.1778)
			(thermal_gap 0.1778)
		)
		(pad "C3" thru_hole circle
			(at -1.500124 -9.05002 180)
			(size 0.7366 0.7366)
			(drill 0.369824)
			(layers "*.Cu" "*.Mask")
			(remove_unused_layers no)
			(net "GND")
			(clearance 0.1778)
			(thermal_gap 0.1778)
		)
		(pad "C4" thru_hole circle
			(at -0.750062 -9.750044 180)
			(size 0.7366 0.7366)
			(drill 0.369824)
			(layers "*.Cu" "*.Mask")
			(remove_unused_layers no)
			(net "PHY_EXP_TO_CONN_8_DP")
			(clearance 0.1778)
			(thermal_gap 0.1778)
		)
		(pad "C5" thru_hole circle
			(at 0 -8.349996 180)
			(size 0.7366 0.7366)
			(drill 0.369824)
			(layers "*.Cu" "*.Mask")
			(remove_unused_layers no)
			(net "PHY_EXP_TO_CONN_8_DN")
			(clearance 0.1778)
			(thermal_gap 0.1778)
		)
		(pad "C6" thru_hole circle
			(at 0.750062 -9.05002 180)
			(size 0.7366 0.7366)
			(drill 0.369824)
			(layers "*.Cu" "*.Mask")
			(remove_unused_layers no)
			(net "GND")
			(clearance 0.1778)
			(thermal_gap 0.1778)
		)
		(pad "C7" thru_hole circle
			(at 1.500124 -9.750044 180)
			(size 0.7366 0.7366)
			(drill 0.369824)
			(layers "*.Cu" "*.Mask")
			(remove_unused_layers no)
			(net "PHY_EXP_TO_CONN_9_DP")
			(clearance 0.1778)
			(thermal_gap 0.1778)
		)
		(pad "C8" thru_hole circle
			(at 2.249932 -8.349996 180)
			(size 0.7366 0.7366)
			(drill 0.369824)
			(layers "*.Cu" "*.Mask")
			(remove_unused_layers no)
			(net "PHY_EXP_TO_CONN_9_DN")
			(clearance 0.1778)
			(thermal_gap 0.1778)
		)
		(pad "C9" thru_hole circle
			(at 2.999994 -9.05002 180)
			(size 0.7366 0.7366)
			(drill 0.369824)
			(layers "*.Cu" "*.Mask")
			(remove_unused_layers no)
			(net "GND")
			(clearance 0.1778)
			(thermal_gap 0.1778)
		)
		(pad "D1" thru_hole circle
			(at -2.999994 -13.549884 180)
			(size 0.7366 0.7366)
			(drill 0.369824)
			(layers "*.Cu" "*.Mask")
			(remove_unused_layers no)
			(net "INT_D1_CONN1")
			(clearance 0.1778)
			(thermal_gap 0.1778)
		)
		(pad "D2" thru_hole circle
			(at -2.249932 -12.15009 180)
			(size 0.7366 0.7366)
			(drill 0.369824)
			(layers "*.Cu" "*.Mask")
			(remove_unused_layers no)
			(net "INT_D2_CONN1")
			(clearance 0.1778)
			(thermal_gap 0.1778)
		)
		(pad "D3" thru_hole circle
			(at -1.500124 -12.850114 180)
			(size 0.7366 0.7366)
			(drill 0.369824)
			(layers "*.Cu" "*.Mask")
			(remove_unused_layers no)
			(net "GND")
			(clearance 0.1778)
			(thermal_gap 0.1778)
		)
		(pad "D4" thru_hole circle
			(at -0.750062 -13.549884 180)
			(size 0.7366 0.7366)
			(drill 0.369824)
			(layers "*.Cu" "*.Mask")
			(remove_unused_layers no)
			(net "PHY_EXP_TO_CONN_10_DP")
			(clearance 0.1778)
			(thermal_gap 0.1778)
		)
		(pad "D5" thru_hole circle
			(at 0 -12.15009 180)
			(size 0.7366 0.7366)
			(drill 0.369824)
			(layers "*.Cu" "*.Mask")
			(remove_unused_layers no)
			(net "PHY_EXP_TO_CONN_10_DN")
			(clearance 0.1778)
			(thermal_gap 0.1778)
		)
		(pad "D6" thru_hole circle
			(at 0.750062 -12.850114 180)
			(size 0.7366 0.7366)
			(drill 0.369824)
			(layers "*.Cu" "*.Mask")
			(remove_unused_layers no)
			(net "GND")
			(clearance 0.1778)
			(thermal_gap 0.1778)
		)
		(pad "D7" thru_hole circle
			(at 1.500124 -13.549884 180)
			(size 0.7366 0.7366)
			(drill 0.369824)
			(layers "*.Cu" "*.Mask")
			(remove_unused_layers no)
			(net "PHY_EXP_TO_CONN_11_DP")
			(clearance 0.1778)
			(thermal_gap 0.1778)
		)
		(pad "D8" thru_hole circle
			(at 2.249932 -12.15009 180)
			(size 0.7366 0.7366)
			(drill 0.369824)
			(layers "*.Cu" "*.Mask")
			(remove_unused_layers no)
			(net "PHY_EXP_TO_CONN_11_DN")
			(clearance 0.1778)
			(thermal_gap 0.1778)
		)
		(pad "D9" thru_hole circle
			(at 2.999994 -12.850114 180)
			(size 0.7366 0.7366)
			(drill 0.369824)
			(layers "*.Cu" "*.Mask")
			(remove_unused_layers no)
			(net "GND")
			(clearance 0.1778)
			(thermal_gap 0.1778)
		)
		(zone
			(layers "F.Cu" "B.Cu" "In1.Cu" "In2.Cu" "In3.Cu" "In4.Cu" "In5.Cu" "In6.Cu")
			(hatch none 0.5)
			(connect_pads
				(clearance 0)
			)
			(min_thickness 0.25)
			(keepout
				(tracks not_allowed)
				(vias allowed)
				(pads allowed)
				(copperpour not_allowed)
				(footprints allowed)
			)
			(placement
				(enabled no)
				(sheetname "")
			)
			(fill
				(thermal_gap 0.5)
				(thermal_bridge_width 0.5)
				(island_removal_mode 0)
			)
			(polygon
				(pts
					(arc
						(start 100.409756 -117.00002)
						(mid 97.590356 -117.00002)
						(end 100.409756 -117.00002)
					)
				)
			)
		)
		(zone
			(layers "F.Cu" "B.Cu" "In1.Cu" "In2.Cu" "In3.Cu" "In4.Cu" "In5.Cu" "In6.Cu")
			(hatch none 0.5)
			(connect_pads
				(clearance 0)
			)
			(min_thickness 0.25)
			(keepout
				(tracks not_allowed)
				(vias allowed)
				(pads allowed)
				(copperpour not_allowed)
				(footprints allowed)
			)
			(placement
				(enabled no)
				(sheetname "")
			)
			(fill
				(thermal_gap 0.5)
				(thermal_bridge_width 0.5)
				(island_removal_mode 0)
			)
			(polygon
				(pts
					(arc
						(start 112.409732 -117.00002)
						(mid 109.590332 -117.00002)
						(end 112.409732 -117.00002)
					)
				)
			)
		)
	)
	(footprint ""
		(layer "F.Cu")
		(at 21.79193 -94.850204 180)
		(property "Reference" "R416"
			(at 0 0 180)
			(layer "F.SilkS")
			(hide yes)
			(effects
				(font
					(size 1.27 1.27)
				)
			)
		)
		(property "Value" "200KR2F-L-GP"
			(at 0.064008 -3.993896 180)
			(unlocked yes)
			(layer "F.Fab")
			(hide yes)
			(effects
				(font
					(size 1.016 1.016)
					(thickness 0.1524)
				)
			)
		)
		(property "Device Type" "R402H16"
			(at 0.064008 -5.517896 180)
			(unlocked yes)
			(layer "F.Fab")
			(hide yes)
			(effects
				(font
					(size 1.016 1.016)
					(thickness 0.1524)
				)
			)
		)
		(duplicate_pad_numbers_are_jumpers no)
		(fp_line
			(start 0.508 -0.9398)
			(end -0.508 -0.9398)
			(stroke
				(width 0.1524)
				(type default)
			)
			(layer "F.SilkS")
		)
		(fp_line
			(start -0.508 -0.9398)
			(end -0.508 0.9398)
			(stroke
				(width 0.1524)
				(type default)
			)
			(layer "F.SilkS")
		)
		(fp_rect
			(start -0.508 0.9398)
			(end 0.508 -0.9398)
			(stroke
				(width 0)
				(type default)
			)
			(fill no)
			(layer "F.CrtYd")
		)
		(fp_rect
			(start -0.508 0.9398)
			(end 0.508 -0.9398)
			(stroke
				(width 0)
				(type default)
			)
			(fill no)
			(layer "F.Fab")
		)
		(pad "1" smd custom
			(at 0 -0.4445 180)
			(size 0.1397 0.1397)
			(layers "F.Cu" "F.Mask" "F.Paste")
			(net "LS_EN_U46")
			(options
				(clearance outline)
				(anchor circle)
			)
			(primitives
				(gr_poly
					(pts
						(arc
							(start -0.1778 -0.2794)
							(mid -0.249642 -0.249642)
							(end -0.2794 -0.1778)
						)
						(arc
							(start -0.2794 0.1778)
							(mid -0.249642 0.249642)
							(end -0.1778 0.2794)
						)
						(arc
							(start 0.1778 0.2794)
							(mid 0.249642 0.249642)
							(end 0.2794 0.1778)
						)
						(arc
							(start 0.2794 -0.1778)
							(mid 0.249642 -0.249642)
							(end 0.1778 -0.2794)
						)
					)
					(width 0)
					(fill yes)
				)
			)
		)
		(pad "2" smd custom
			(at 0 0.4445 180)
			(size 0.1397 0.1397)
			(layers "F.Cu" "F.Mask" "F.Paste")
			(net "P0V9_PG")
			(options
				(clearance outline)
				(anchor circle)
			)
			(primitives
				(gr_poly
					(pts
						(arc
							(start -0.1778 -0.2794)
							(mid -0.249642 -0.249642)
							(end -0.2794 -0.1778)
						)
						(arc
							(start -0.2794 0.1778)
							(mid -0.249642 0.249642)
							(end -0.1778 0.2794)
						)
						(arc
							(start 0.1778 0.2794)
							(mid 0.249642 0.249642)
							(end 0.2794 0.1778)
						)
						(arc
							(start 0.2794 -0.1778)
							(mid 0.249642 -0.249642)
							(end 0.1778 -0.2794)
						)
					)
					(width 0)
					(fill yes)
				)
			)
		)
	)
	(footprint ""
		(layer "F.Cu")
		(at 6.5786 -52.1462 180)
		(property "Reference" "R532"
			(at 0 0 180)
			(layer "F.SilkS")
			(hide yes)
			(effects
				(font
					(size 1.27 1.27)
				)
			)
		)
		(property "Value" "100KR2F-L1-GP"
			(at 0.064008 -3.993896 180)
			(unlocked yes)
			(layer "F.Fab")
			(hide yes)
			(effects
				(font
					(size 1.016 1.016)
					(thickness 0.1524)
				)
			)
		)
		(property "Device Type" "R402H16"
			(at 0.064008 -5.517896 180)
			(unlocked yes)
			(layer "F.Fab")
			(hide yes)
			(effects
				(font
					(size 1.016 1.016)
					(thickness 0.1524)
				)
			)
		)
		(duplicate_pad_numbers_are_jumpers no)
		(fp_line
			(start 0.508 -0.9398)
			(end -0.508 -0.9398)
			(stroke
				(width 0.1524)
				(type default)
			)
			(layer "F.SilkS")
		)
		(fp_line
			(start -0.508 -0.9398)
			(end -0.508 0.9398)
			(stroke
				(width 0.1524)
				(type default)
			)
			(layer "F.SilkS")
		)
		(fp_rect
			(start -0.508 0.9398)
			(end 0.508 -0.9398)
			(stroke
				(width 0)
				(type default)
			)
			(fill no)
			(layer "F.CrtYd")
		)
		(fp_rect
			(start -0.508 0.9398)
			(end 0.508 -0.9398)
			(stroke
				(width 0)
				(type default)
			)
			(fill no)
			(layer "F.Fab")
		)
		(pad "1" smd custom
			(at 0 -0.4445 180)
			(size 0.1397 0.1397)
			(layers "F.Cu" "F.Mask" "F.Paste")
			(net "P12V_STBY_SCC")
			(options
				(clearance outline)
				(anchor circle)
			)
			(primitives
				(gr_poly
					(pts
						(arc
							(start -0.1778 -0.2794)
							(mid -0.249642 -0.249642)
							(end -0.2794 -0.1778)
						)
						(arc
							(start -0.2794 0.1778)
							(mid -0.249642 0.249642)
							(end -0.1778 0.2794)
						)
						(arc
							(start 0.1778 0.2794)
							(mid 0.249642 0.249642)
							(end 0.2794 0.1778)
						)
						(arc
							(start 0.2794 -0.1778)
							(mid 0.249642 -0.249642)
							(end 0.1778 -0.2794)
						)
					)
					(width 0)
					(fill yes)
				)
			)
		)
		(pad "2" smd custom
			(at 0 0.4445 180)
			(size 0.1397 0.1397)
			(layers "F.Cu" "F.Mask" "F.Paste")
			(net "MB0_P12V_PWGIN_R")
			(options
				(clearance outline)
				(anchor circle)
			)
			(primitives
				(gr_poly
					(pts
						(arc
							(start -0.1778 -0.2794)
							(mid -0.249642 -0.249642)
							(end -0.2794 -0.1778)
						)
						(arc
							(start -0.2794 0.1778)
							(mid -0.249642 0.249642)
							(end -0.1778 0.2794)
						)
						(arc
							(start 0.1778 0.2794)
							(mid 0.249642 0.249642)
							(end 0.2794 0.1778)
						)
						(arc
							(start 0.2794 -0.1778)
							(mid 0.249642 -0.249642)
							(end 0.1778 -0.2794)
						)
					)
					(width 0)
					(fill yes)
				)
			)
		)
	)
	(footprint ""
		(layer "F.Cu")
		(at 200.49998 -131.430014)
		(property "Reference" "RHOLE1"
			(at 0 0 0)
			(layer "F.SilkS")
			(hide yes)
			(effects
				(font
					(size 1.27 1.27)
				)
			)
		)
		(property "Value" "HOLE709R146-3P-S2-GP"
			(at -10.312908 -1.750314 0)
			(unlocked yes)
			(layer "F.Fab")
			(hide yes)
			(effects
				(font
					(size 1.016 1.016)
					(thickness 0.1524)
				)
			)
		)
		(property "Device Type" "HOLE709R146-3P-S2"
			(at -10.312908 -3.274314 0)
			(unlocked yes)
			(layer "F.Fab")
			(hide yes)
			(effects
				(font
					(size 1.016 1.016)
					(thickness 0.1524)
				)
			)
		)
		(duplicate_pad_numbers_are_jumpers no)
		(fp_poly
			(pts
				(arc
					(start 4.8006 -7.975854)
					(mid -9.309136 0)
					(end 4.8006 7.975854)
				)
			)
			(stroke
				(width 0)
				(type default)
			)
			(fill no)
			(layer "B.CrtYd")
		)
		(fp_poly
			(pts
				(arc
					(start 4.8006 -7.975854)
					(mid -9.309136 0)
					(end 4.8006 7.975854)
				)
			)
			(stroke
				(width 0)
				(type default)
			)
			(fill no)
			(layer "F.CrtYd")
		)
		(fp_poly
			(pts
				(arc
					(start 4.8006 -7.975854)
					(mid -9.309136 0)
					(end 4.8006 7.975854)
				)
			)
			(stroke
				(width 0)
				(type default)
			)
			(fill no)
			(layer "B.Fab")
		)
		(fp_poly
			(pts
				(arc
					(start 4.8006 -7.975854)
					(mid -9.309136 0)
					(end 4.8006 7.975854)
				)
			)
			(stroke
				(width 0)
				(type default)
			)
			(fill no)
			(layer "F.Fab")
		)
		(pad "1" thru_hole circle
			(at 0 -4.500118)
			(size 2.5146 2.5146)
			(drill 2.1082)
			(layers "*.Cu" "*.Mask")
			(remove_unused_layers no)
			(net "GND")
			(clearance 0.1524)
			(thermal_gap 0.1524)
		)
		(pad "2" thru_hole custom
			(at 0 0)
			(size 3.374898 3.374898)
			(drill 3.7084)
			(layers "*.Cu" "*.Mask")
			(remove_unused_layers no)
			(net "GND")
			(clearance -4.38785)
			(thermal_gap 0.3048)
			(options
				(clearance outline)
				(anchor circle)
			)
			(primitives
				(gr_poly
					(pts
						(arc
							(start 6.75005 -7.80161)
							(mid -6.750045 0)
							(end 6.75005 7.80161)
						)
					)
					(width 0)
					(fill yes)
				)
			)
			(padstack
				(mode front_inner_back)
				(layer "Inner"
					(shape circle)
					(size 4.1148 4.1148)
					(clearance 0.3048)
				)
				(layer "B.Cu"
					(shape custom)
					(size 3.374898 3.374898)
					(options
						(anchor circle)
					)
					(primitives
						(gr_poly
							(pts
								(arc
									(start 6.75005 -7.80161)
									(mid -6.750045 0)
									(end 6.75005 7.80161)
								)
							)
							(width 0)
							(fill yes)
						)
					)
					(clearance -4.38785)
				)
			)
		)
		(pad "3" thru_hole circle
			(at 0 4.500118)
			(size 1.9812 1.9812)
			(drill 1.5748)
			(layers "*.Cu" "*.Mask")
			(remove_unused_layers no)
			(net "GND")
			(clearance 0.1524)
			(thermal_gap 0.1524)
		)
	)
	(footprint ""
		(layer "F.Cu")
		(at 23.79853 -94.850204 180)
		(property "Reference" "R449"
			(at 0 0 180)
			(layer "F.SilkS")
			(hide yes)
			(effects
				(font
					(size 1.27 1.27)
				)
			)
		)
		(property "Value" "200KR2F-L-GP"
			(at 0.064008 -3.993896 180)
			(unlocked yes)
			(layer "F.Fab")
			(hide yes)
			(effects
				(font
					(size 1.016 1.016)
					(thickness 0.1524)
				)
			)
		)
		(property "Device Type" "R402H16"
			(at 0.064008 -5.517896 180)
			(unlocked yes)
			(layer "F.Fab")
			(hide yes)
			(effects
				(font
					(size 1.016 1.016)
					(thickness 0.1524)
				)
			)
		)
		(duplicate_pad_numbers_are_jumpers no)
		(fp_line
			(start 0.508 -0.9398)
			(end -0.508 -0.9398)
			(stroke
				(width 0.1524)
				(type default)
			)
			(layer "F.SilkS")
		)
		(fp_line
			(start -0.508 -0.9398)
			(end -0.508 0.9398)
			(stroke
				(width 0.1524)
				(type default)
			)
			(layer "F.SilkS")
		)
		(fp_rect
			(start -0.508 0.9398)
			(end 0.508 -0.9398)
			(stroke
				(width 0)
				(type default)
			)
			(fill no)
			(layer "F.CrtYd")
		)
		(fp_rect
			(start -0.508 0.9398)
			(end 0.508 -0.9398)
			(stroke
				(width 0)
				(type default)
			)
			(fill no)
			(layer "F.Fab")
		)
		(pad "1" smd custom
			(at 0 -0.4445 180)
			(size 0.1397 0.1397)
			(layers "F.Cu" "F.Mask" "F.Paste")
			(net "VREF1")
			(options
				(clearance outline)
				(anchor circle)
			)
			(primitives
				(gr_poly
					(pts
						(arc
							(start -0.1778 -0.2794)
							(mid -0.249642 -0.249642)
							(end -0.2794 -0.1778)
						)
						(arc
							(start -0.2794 0.1778)
							(mid -0.249642 0.249642)
							(end -0.1778 0.2794)
						)
						(arc
							(start 0.1778 0.2794)
							(mid 0.249642 0.249642)
							(end 0.2794 0.1778)
						)
						(arc
							(start 0.2794 -0.1778)
							(mid 0.249642 -0.249642)
							(end 0.1778 -0.2794)
						)
					)
					(width 0)
					(fill yes)
				)
			)
		)
		(pad "2" smd custom
			(at 0 0.4445 180)
			(size 0.1397 0.1397)
			(layers "F.Cu" "F.Mask" "F.Paste")
			(net "P3V3")
			(options
				(clearance outline)
				(anchor circle)
			)
			(primitives
				(gr_poly
					(pts
						(arc
							(start -0.1778 -0.2794)
							(mid -0.249642 -0.249642)
							(end -0.2794 -0.1778)
						)
						(arc
							(start -0.2794 0.1778)
							(mid -0.249642 0.249642)
							(end -0.1778 0.2794)
						)
						(arc
							(start 0.1778 0.2794)
							(mid 0.249642 0.249642)
							(end 0.2794 0.1778)
						)
						(arc
							(start 0.2794 -0.1778)
							(mid 0.249642 -0.249642)
							(end 0.1778 -0.2794)
						)
					)
					(width 0)
					(fill yes)
				)
			)
		)
	)
	(footprint ""
		(layer "F.Cu")
		(at 71.172324 -75.548236 90)
		(property "Reference" "R541"
			(at 0 0 90)
			(layer "F.SilkS")
			(hide yes)
			(effects
				(font
					(size 1.27 1.27)
				)
			)
		)
		(property "Value" "0R2J-2-GP"
			(at 0.064008 -3.993896 90)
			(unlocked yes)
			(layer "F.Fab")
			(hide yes)
			(effects
				(font
					(size 1.016 1.016)
					(thickness 0.1524)
				)
			)
		)
		(property "Device Type" "R402H16"
			(at 0.064008 -5.517896 90)
			(unlocked yes)
			(layer "F.Fab")
			(hide yes)
			(effects
				(font
					(size 1.016 1.016)
					(thickness 0.1524)
				)
			)
		)
		(duplicate_pad_numbers_are_jumpers no)
		(fp_line
			(start 0.508 -0.9398)
			(end -0.508 -0.9398)
			(stroke
				(width 0.1524)
				(type default)
			)
			(layer "F.SilkS")
		)
		(fp_line
			(start -0.508 -0.9398)
			(end -0.508 0.9398)
			(stroke
				(width 0.1524)
				(type default)
			)
			(layer "F.SilkS")
		)
		(fp_rect
			(start -0.508 0.9398)
			(end 0.508 -0.9398)
			(stroke
				(width 0)
				(type default)
			)
			(fill no)
			(layer "F.CrtYd")
		)
		(fp_rect
			(start -0.508 0.9398)
			(end 0.508 -0.9398)
			(stroke
				(width 0)
				(type default)
			)
			(fill no)
			(layer "F.Fab")
		)
		(pad "1" smd custom
			(at 0 -0.4445 90)
			(size 0.1397 0.1397)
			(layers "F.Cu" "F.Mask" "F.Paste")
			(net "I2C_EXP_IOC_SDA8")
			(options
				(clearance outline)
				(anchor circle)
			)
			(primitives
				(gr_poly
					(pts
						(arc
							(start -0.1778 -0.2794)
							(mid -0.249642 -0.249642)
							(end -0.2794 -0.1778)
						)
						(arc
							(start -0.2794 0.1778)
							(mid -0.249642 0.249642)
							(end -0.1778 0.2794)
						)
						(arc
							(start 0.1778 0.2794)
							(mid 0.249642 0.249642)
							(end 0.2794 0.1778)
						)
						(arc
							(start 0.2794 -0.1778)
							(mid 0.249642 -0.249642)
							(end 0.1778 -0.2794)
						)
					)
					(width 0)
					(fill yes)
				)
			)
		)
		(pad "2" smd custom
			(at 0 0.4445 90)
			(size 0.1397 0.1397)
			(layers "F.Cu" "F.Mask" "F.Paste")
			(net "I2C_IOC_4_R_SDA")
			(options
				(clearance outline)
				(anchor circle)
			)
			(primitives
				(gr_poly
					(pts
						(arc
							(start -0.1778 -0.2794)
							(mid -0.249642 -0.249642)
							(end -0.2794 -0.1778)
						)
						(arc
							(start -0.2794 0.1778)
							(mid -0.249642 0.249642)
							(end -0.1778 0.2794)
						)
						(arc
							(start 0.1778 0.2794)
							(mid 0.249642 0.249642)
							(end 0.2794 0.1778)
						)
						(arc
							(start 0.2794 -0.1778)
							(mid 0.249642 -0.249642)
							(end 0.1778 -0.2794)
						)
					)
					(width 0)
					(fill yes)
				)
			)
		)
	)
	(footprint ""
		(layer "F.Cu")
		(at 142.673324 -104.872028 180)
		(property "Reference" "R26"
			(at 0 0 180)
			(layer "F.SilkS")
			(hide yes)
			(effects
				(font
					(size 1.27 1.27)
				)
			)
		)
		(property "Value" "0R5J-5-GP"
			(at 0 -8.9535 180)
			(unlocked yes)
			(layer "F.Fab")
			(hide yes)
			(effects
				(font
					(size 1.27 1.016)
					(thickness 0.1524)
				)
			)
		)
		(property "Device Type" "R805H24"
			(at 0 -10.6299 180)
			(unlocked yes)
			(layer "F.Fab")
			(hide yes)
			(effects
				(font
					(size 1.27 1.016)
					(thickness 0.1524)
				)
			)
		)
		(duplicate_pad_numbers_are_jumpers no)
		(fp_line
			(start 0.889 1.7018)
			(end 0.889 -0.508)
			(stroke
				(width 0.1524)
				(type default)
			)
			(layer "F.SilkS")
		)
		(fp_line
			(start 0.889 -1.7018)
			(end 0.889 -0.381)
			(stroke
				(width 0.1524)
				(type default)
			)
			(layer "F.SilkS")
		)
		(fp_line
			(start 0.889 -1.7018)
			(end -0.889 -1.7018)
			(stroke
				(width 0.1524)
				(type default)
			)
			(layer "F.SilkS")
		)
		(fp_line
			(start -0.889 1.7018)
			(end 0.889 1.7018)
			(stroke
				(width 0.1524)
				(type default)
			)
			(layer "F.SilkS")
		)
		(fp_line
			(start -0.889 0.0762)
			(end -0.889 1.7018)
			(stroke
				(width 0.1524)
				(type default)
			)
			(layer "F.SilkS")
		)
		(fp_line
			(start -0.889 -1.7018)
			(end -0.889 0.2794)
			(stroke
				(width 0.1524)
				(type default)
			)
			(layer "F.SilkS")
		)
		(fp_poly
			(pts
				(xy 0.9652 -1.778) (xy 0.9652 1.778) (xy -0.9652 1.778) (xy -0.9652 -1.778)
			)
			(stroke
				(width 0)
				(type default)
			)
			(fill no)
			(layer "F.CrtYd")
		)
		(fp_rect
			(start -0.9652 1.778)
			(end 0.9652 -1.778)
			(stroke
				(width 0)
				(type default)
			)
			(fill no)
			(layer "F.Fab")
		)
		(pad "1" smd rect
			(at 0 -0.9652 180)
			(size 1.397 1.143)
			(layers "F.Cu" "F.Mask" "F.Paste")
			(net "P1V5_E")
		)
		(pad "2" smd rect
			(at 0 0.9652 180)
			(size 1.397 1.143)
			(layers "F.Cu" "F.Mask" "F.Paste")
			(net "P1V5_E_OUT")
		)
	)
	(footprint ""
		(layer "F.Cu")
		(at 74.99985 -134.999984)
		(property "Reference" ""
			(at 0 0 0)
			(layer "F.SilkS")
			(hide yes)
			(effects
				(font
					(size 1.27 1.27)
				)
			)
		)
		(property "Value" "*"
			(at -6.38175 0.19685 0)
			(unlocked yes)
			(layer "F.Fab")
			(hide yes)
			(effects
				(font
					(size 1.016 1.016)
					(thickness 0.1524)
				)
			)
		)
		(duplicate_pad_numbers_are_jumpers no)
		(fp_poly
			(pts
				(arc
					(start 5.0673 0)
					(mid -5.0673 0)
					(end 5.0673 0)
				)
			)
			(stroke
				(width 0)
				(type default)
			)
			(fill no)
			(layer "B.CrtYd")
		)
		(fp_poly
			(pts
				(arc
					(start 5.0673 0)
					(mid -5.0673 0)
					(end 5.0673 0)
				)
			)
			(stroke
				(width 0)
				(type default)
			)
			(fill no)
			(layer "F.CrtYd")
		)
		(fp_poly
			(pts
				(arc
					(start 5.0673 0)
					(mid -5.0673 0)
					(end 5.0673 0)
				)
			)
			(stroke
				(width 0)
				(type default)
			)
			(fill no)
			(layer "B.Fab")
		)
		(fp_poly
			(pts
				(arc
					(start 5.0673 0)
					(mid -5.0673 0)
					(end 5.0673 0)
				)
			)
			(stroke
				(width 0)
				(type default)
			)
			(fill no)
			(layer "F.Fab")
		)
		(pad "1" thru_hole circle
			(at 0 0)
			(size 9.525 9.525)
			(drill 3.5052)
			(layers "*.Cu" "*.Mask")
			(remove_unused_layers no)
			(net "Net_7")
			(clearance -2.5019)
			(thermal_gap 0.3048)
			(padstack
				(mode front_inner_back)
				(layer "Inner"
					(shape circle)
					(size 3.9116 3.9116)
					(clearance 0.3048)
				)
				(layer "B.Cu"
					(shape circle)
					(size 9.525 9.525)
					(clearance -2.5019)
				)
			)
		)
	)
	(footprint ""
		(layer "F.Cu")
		(at 191.8462 -43.0657 -90)
		(property "Reference" "R183"
			(at 0 0 270)
			(layer "F.SilkS")
			(hide yes)
			(effects
				(font
					(size 1.27 1.27)
				)
			)
		)
		(property "Value" "2K2R2F-GP"
			(at 0.064008 -3.993896 270)
			(unlocked yes)
			(layer "F.Fab")
			(hide yes)
			(effects
				(font
					(size 1.016 1.016)
					(thickness 0.1524)
				)
			)
		)
		(property "Device Type" "R402H16"
			(at 0.064008 -5.517896 270)
			(unlocked yes)
			(layer "F.Fab")
			(hide yes)
			(effects
				(font
					(size 1.016 1.016)
					(thickness 0.1524)
				)
			)
		)
		(duplicate_pad_numbers_are_jumpers no)
		(fp_line
			(start -0.508 -0.9398)
			(end -0.508 0.9398)
			(stroke
				(width 0.1524)
				(type default)
			)
			(layer "F.SilkS")
		)
		(fp_line
			(start 0.508 -0.9398)
			(end -0.508 -0.9398)
			(stroke
				(width 0.1524)
				(type default)
			)
			(layer "F.SilkS")
		)
		(fp_rect
			(start -0.508 0.9398)
			(end 0.508 -0.9398)
			(stroke
				(width 0)
				(type default)
			)
			(fill no)
			(layer "F.CrtYd")
		)
		(fp_rect
			(start -0.508 0.9398)
			(end 0.508 -0.9398)
			(stroke
				(width 0)
				(type default)
			)
			(fill no)
			(layer "F.Fab")
		)
		(pad "1" smd custom
			(at 0 -0.4445 270)
			(size 0.1397 0.1397)
			(layers "F.Cu" "F.Mask" "F.Paste")
			(net "P1V8_C")
			(options
				(clearance outline)
				(anchor circle)
			)
			(primitives
				(gr_poly
					(pts
						(arc
							(start -0.1778 -0.2794)
							(mid -0.249642 -0.249642)
							(end -0.2794 -0.1778)
						)
						(arc
							(start -0.2794 0.1778)
							(mid -0.249642 0.249642)
							(end -0.1778 0.2794)
						)
						(arc
							(start 0.1778 0.2794)
							(mid 0.249642 0.249642)
							(end 0.2794 0.1778)
						)
						(arc
							(start 0.2794 -0.1778)
							(mid 0.249642 -0.249642)
							(end 0.1778 -0.2794)
						)
					)
					(width 0)
					(fill yes)
				)
			)
		)
		(pad "2" smd custom
			(at 0 0.4445 270)
			(size 0.1397 0.1397)
			(layers "F.Cu" "F.Mask" "F.Paste")
			(net "I2C_IOC_1_SCL")
			(options
				(clearance outline)
				(anchor circle)
			)
			(primitives
				(gr_poly
					(pts
						(arc
							(start -0.1778 -0.2794)
							(mid -0.249642 -0.249642)
							(end -0.2794 -0.1778)
						)
						(arc
							(start -0.2794 0.1778)
							(mid -0.249642 0.249642)
							(end -0.1778 0.2794)
						)
						(arc
							(start 0.1778 0.2794)
							(mid 0.249642 0.249642)
							(end 0.2794 0.1778)
						)
						(arc
							(start 0.2794 -0.1778)
							(mid 0.249642 -0.249642)
							(end 0.1778 -0.2794)
						)
					)
					(width 0)
					(fill yes)
				)
			)
		)
	)
	(footprint ""
		(layer "F.Cu")
		(at 16.2814 -47.2694 180)
		(property "Reference" "R11"
			(at 0 0 180)
			(layer "F.SilkS")
			(hide yes)
			(effects
				(font
					(size 1.27 1.27)
				)
			)
		)
		(property "Value" "10R2F-L-GP"
			(at 0.064008 -3.993896 180)
			(unlocked yes)
			(layer "F.Fab")
			(hide yes)
			(effects
				(font
					(size 1.016 1.016)
					(thickness 0.1524)
				)
			)
		)
		(property "Device Type" "R402H14"
			(at 0.064008 -5.517896 180)
			(unlocked yes)
			(layer "F.Fab")
			(hide yes)
			(effects
				(font
					(size 1.016 1.016)
					(thickness 0.1524)
				)
			)
		)
		(duplicate_pad_numbers_are_jumpers no)
		(fp_line
			(start 0.508 -0.9398)
			(end -0.508 -0.9398)
			(stroke
				(width 0.1524)
				(type default)
			)
			(layer "F.SilkS")
		)
		(fp_line
			(start -0.508 -0.9398)
			(end -0.508 0.9398)
			(stroke
				(width 0.1524)
				(type default)
			)
			(layer "F.SilkS")
		)
		(fp_rect
			(start -0.508 0.9398)
			(end 0.508 -0.9398)
			(stroke
				(width 0)
				(type default)
			)
			(fill no)
			(layer "F.CrtYd")
		)
		(fp_rect
			(start -0.508 0.9398)
			(end 0.508 -0.9398)
			(stroke
				(width 0)
				(type default)
			)
			(fill no)
			(layer "F.Fab")
		)
		(pad "1" smd custom
			(at 0 -0.4445 180)
			(size 0.1397 0.1397)
			(layers "F.Cu" "F.Mask" "F.Paste")
			(net "P12V_MAIN")
			(options
				(clearance outline)
				(anchor circle)
			)
			(primitives
				(gr_poly
					(pts
						(arc
							(start -0.1778 -0.2794)
							(mid -0.249642 -0.249642)
							(end -0.2794 -0.1778)
						)
						(arc
							(start -0.2794 0.1778)
							(mid -0.249642 0.249642)
							(end -0.1778 0.2794)
						)
						(arc
							(start 0.1778 0.2794)
							(mid 0.249642 0.249642)
							(end 0.2794 0.1778)
						)
						(arc
							(start 0.2794 -0.1778)
							(mid 0.249642 -0.249642)
							(end 0.1778 -0.2794)
						)
					)
					(width 0)
					(fill yes)
				)
			)
		)
		(pad "2" smd custom
			(at 0 0.4445 180)
			(size 0.1397 0.1397)
			(layers "F.Cu" "F.Mask" "F.Paste")
			(net "MB0_VCC")
			(options
				(clearance outline)
				(anchor circle)
			)
			(primitives
				(gr_poly
					(pts
						(arc
							(start -0.1778 -0.2794)
							(mid -0.249642 -0.249642)
							(end -0.2794 -0.1778)
						)
						(arc
							(start -0.2794 0.1778)
							(mid -0.249642 0.249642)
							(end -0.1778 0.2794)
						)
						(arc
							(start 0.1778 0.2794)
							(mid 0.249642 0.249642)
							(end 0.2794 0.1778)
						)
						(arc
							(start 0.2794 -0.1778)
							(mid 0.249642 -0.249642)
							(end 0.1778 -0.2794)
						)
					)
					(width 0)
					(fill yes)
				)
			)
		)
	)
	(footprint ""
		(layer "F.Cu")
		(at 65.024 -72.6948)
		(property "Reference" "R423"
			(at 0 0 0)
			(layer "F.SilkS")
			(hide yes)
			(effects
				(font
					(size 1.27 1.27)
				)
			)
		)
		(property "Value" "0R2J-2-GP"
			(at 0.064008 -3.993896 0)
			(unlocked yes)
			(layer "F.Fab")
			(hide yes)
			(effects
				(font
					(size 1.016 1.016)
					(thickness 0.1524)
				)
			)
		)
		(property "Device Type" "R402H16"
			(at 0.064008 -5.517896 0)
			(unlocked yes)
			(layer "F.Fab")
			(hide yes)
			(effects
				(font
					(size 1.016 1.016)
					(thickness 0.1524)
				)
			)
		)
		(duplicate_pad_numbers_are_jumpers no)
		(fp_line
			(start -0.508 -0.9398)
			(end -0.508 0.9398)
			(stroke
				(width 0.1524)
				(type default)
			)
			(layer "F.SilkS")
		)
		(fp_line
			(start 0.508 -0.9398)
			(end -0.508 -0.9398)
			(stroke
				(width 0.1524)
				(type default)
			)
			(layer "F.SilkS")
		)
		(fp_rect
			(start -0.508 0.9398)
			(end 0.508 -0.9398)
			(stroke
				(width 0)
				(type default)
			)
			(fill no)
			(layer "F.CrtYd")
		)
		(fp_rect
			(start -0.508 0.9398)
			(end 0.508 -0.9398)
			(stroke
				(width 0)
				(type default)
			)
			(fill no)
			(layer "F.Fab")
		)
		(pad "1" smd custom
			(at 0 -0.4445)
			(size 0.1397 0.1397)
			(layers "F.Cu" "F.Mask" "F.Paste")
			(net "LS_EN_U38")
			(options
				(clearance outline)
				(anchor circle)
			)
			(primitives
				(gr_poly
					(pts
						(arc
							(start -0.1778 -0.2794)
							(mid -0.249642 -0.249642)
							(end -0.2794 -0.1778)
						)
						(arc
							(start -0.2794 0.1778)
							(mid -0.249642 0.249642)
							(end -0.1778 0.2794)
						)
						(arc
							(start 0.1778 0.2794)
							(mid 0.249642 0.249642)
							(end 0.2794 0.1778)
						)
						(arc
							(start 0.2794 -0.1778)
							(mid 0.249642 -0.249642)
							(end 0.1778 -0.2794)
						)
					)
					(width 0)
					(fill yes)
				)
			)
		)
		(pad "2" smd custom
			(at 0 0.4445)
			(size 0.1397 0.1397)
			(layers "F.Cu" "F.Mask" "F.Paste")
			(net "VREF5")
			(options
				(clearance outline)
				(anchor circle)
			)
			(primitives
				(gr_poly
					(pts
						(arc
							(start -0.1778 -0.2794)
							(mid -0.249642 -0.249642)
							(end -0.2794 -0.1778)
						)
						(arc
							(start -0.2794 0.1778)
							(mid -0.249642 0.249642)
							(end -0.1778 0.2794)
						)
						(arc
							(start 0.1778 0.2794)
							(mid 0.249642 0.249642)
							(end 0.2794 0.1778)
						)
						(arc
							(start 0.2794 -0.1778)
							(mid 0.249642 -0.249642)
							(end 0.1778 -0.2794)
						)
					)
					(width 0)
					(fill yes)
				)
			)
		)
	)
	(footprint ""
		(layer "F.Cu")
		(at 142.24 -100.584)
		(property "Reference" "L35"
			(at 0 0 0)
			(layer "F.SilkS")
			(hide yes)
			(effects
				(font
					(size 1.27 1.27)
				)
			)
		)
		(property "Value" "MPZ2012S300AT-GP"
			(at 0 -4.2418 0)
			(unlocked yes)
			(layer "F.Fab")
			(hide yes)
			(effects
				(font
					(size 1.016 1.016)
					(thickness 0.1524)
				)
			)
		)
		(property "Device Type" "L805H42"
			(at 0 -5.7912 0)
			(unlocked yes)
			(layer "F.Fab")
			(hide yes)
			(effects
				(font
					(size 1.016 1.016)
					(thickness 0.1524)
				)
			)
		)
		(duplicate_pad_numbers_are_jumpers no)
		(fp_line
			(start -0.889 -1.7018)
			(end 0.889 -1.7018)
			(stroke
				(width 0.1524)
				(type default)
			)
			(layer "F.SilkS")
		)
		(fp_line
			(start -0.889 1.7018)
			(end -0.889 -1.7018)
			(stroke
				(width 0.1524)
				(type default)
			)
			(layer "F.SilkS")
		)
		(fp_line
			(start 0.889 -1.7018)
			(end 0.889 1.7018)
			(stroke
				(width 0.1524)
				(type default)
			)
			(layer "F.SilkS")
		)
		(fp_line
			(start 0.889 1.7018)
			(end -0.889 1.7018)
			(stroke
				(width 0.1524)
				(type default)
			)
			(layer "F.SilkS")
		)
		(fp_rect
			(start -0.9652 1.778)
			(end 0.9652 -1.778)
			(stroke
				(width 0)
				(type default)
			)
			(fill no)
			(layer "F.CrtYd")
		)
		(fp_rect
			(start -0.9652 1.778)
			(end 0.9652 -1.778)
			(stroke
				(width 0)
				(type default)
			)
			(fill no)
			(layer "F.Fab")
		)
		(pad "1" smd rect
			(at 0 -0.9652)
			(size 1.397 1.143)
			(layers "F.Cu" "F.Mask" "F.Paste")
			(net "P1V5_E")
		)
		(pad "2" smd rect
			(at 0 0.9652)
			(size 1.397 1.143)
			(layers "F.Cu" "F.Mask" "F.Paste")
			(net "GB_VDDH")
		)
	)
	(footprint ""
		(layer "F.Cu")
		(at 54.0512 -77.4954 180)
		(property "Reference" "U41"
			(at 0 0 180)
			(layer "F.SilkS")
			(hide yes)
			(effects
				(font
					(size 1.27 1.27)
				)
			)
		)
		(property "Value" "PCA9306DCTR-GP"
			(at 0 -11.6332 180)
			(unlocked yes)
			(layer "F.Fab")
			(hide yes)
			(effects
				(font
					(size 1.016 1.016)
					(thickness 0.1524)
				)
			)
		)
		(property "Device Type" "SSOIC8H52"
			(at 0 -13.1572 180)
			(unlocked yes)
			(layer "F.Fab")
			(hide yes)
			(effects
				(font
					(size 1.016 1.016)
					(thickness 0.1524)
				)
			)
		)
		(duplicate_pad_numbers_are_jumpers no)
		(fp_line
			(start 1.0668 0.5842)
			(end -1.524 0.5842)
			(stroke
				(width 0.1524)
				(type default)
			)
			(layer "F.SilkS")
		)
		(fp_line
			(start 1.0668 -0.5842)
			(end 1.0668 0.5842)
			(stroke
				(width 0.1524)
				(type default)
			)
			(layer "F.SilkS")
		)
		(fp_line
			(start -1.397 0)
			(end -1.7018 0.3048)
			(stroke
				(width 0.1524)
				(type default)
			)
			(layer "F.SilkS")
		)
		(fp_line
			(start -1.397 0)
			(end -1.7018 -0.3048)
			(stroke
				(width 0.1524)
				(type default)
			)
			(layer "F.SilkS")
		)
		(fp_line
			(start -1.524 0.5842)
			(end -1.524 2.286)
			(stroke
				(width 0.508)
				(type default)
			)
			(layer "F.SilkS")
		)
		(fp_line
			(start -1.7018 -0.5842)
			(end 1.0668 -0.5842)
			(stroke
				(width 0.1524)
				(type default)
			)
			(layer "F.SilkS")
		)
		(fp_line
			(start -1.7018 -0.5842)
			(end -1.7018 2.286)
			(stroke
				(width 0.1524)
				(type default)
			)
			(layer "F.SilkS")
		)
		(fp_poly
			(pts
				(xy -1.1684 -0.5842) (xy 1.0668 -0.5842) (xy 1.0668 0.5842) (xy -1.1684 0.5842)
			)
			(stroke
				(width 0)
				(type default)
			)
			(fill yes)
			(layer "F.SilkS")
		)
		(fp_poly
			(pts
				(xy -1.778 2.54) (xy 1.778 2.54) (xy 1.778 -2.54) (xy -1.778 -2.54)
			)
			(stroke
				(width 0)
				(type default)
			)
			(fill no)
			(layer "F.CrtYd")
		)
		(fp_poly
			(pts
				(xy -1.778 -2.54) (xy 1.778 -2.54) (xy 1.778 2.54) (xy -1.778 2.54)
			)
			(stroke
				(width 0)
				(type default)
			)
			(fill no)
			(layer "F.Fab")
		)
		(pad "1" smd rect
			(at -0.97536 1.6256 180)
			(size 0.3556 1.524)
			(layers "F.Cu" "F.Mask" "F.Paste")
			(net "GND")
		)
		(pad "2" smd rect
			(at -0.32512 1.6256 180)
			(size 0.3556 1.524)
			(layers "F.Cu" "F.Mask" "F.Paste")
			(net "P1V8_E")
		)
		(pad "3" smd rect
			(at 0.32512 1.6256 180)
			(size 0.3556 1.524)
			(layers "F.Cu" "F.Mask" "F.Paste")
			(net "I2C_CLIP_SCL7_LS")
		)
		(pad "4" smd rect
			(at 0.97536 1.6256 180)
			(size 0.3556 1.524)
			(layers "F.Cu" "F.Mask" "F.Paste")
			(net "I2C_CLIP_SDA7_LS")
		)
		(pad "5" smd rect
			(at 0.97536 -1.6256 180)
			(size 0.3556 1.524)
			(layers "F.Cu" "F.Mask" "F.Paste")
			(net "I2C_CLIP_SDA7")
		)
		(pad "6" smd rect
			(at 0.32512 -1.6256 180)
			(size 0.3556 1.524)
			(layers "F.Cu" "F.Mask" "F.Paste")
			(net "I2C_CLIP_SCL7")
		)
		(pad "7" smd rect
			(at -0.32512 -1.6256 180)
			(size 0.3556 1.524)
			(layers "F.Cu" "F.Mask" "F.Paste")
			(net "VREF7")
		)
		(pad "8" smd rect
			(at -0.97536 -1.6256 180)
			(size 0.3556 1.524)
			(layers "F.Cu" "F.Mask" "F.Paste")
			(net "LS_EN_U41")
		)
	)
	(footprint ""
		(layer "F.Cu")
		(at 136.398 -107.6706 -90)
		(property "Reference" "C695"
			(at 0 0 270)
			(layer "F.SilkS")
			(hide yes)
			(effects
				(font
					(size 1.27 1.27)
				)
			)
		)
		(property "Value" "SC10U6D3V5KX-4GP"
			(at -0.0762 -6.1214 270)
			(unlocked yes)
			(layer "F.Fab")
			(hide yes)
			(effects
				(font
					(size 1.016 1.016)
					(thickness 0.1524)
				)
			)
		)
		(property "Device Type" "C805H58"
			(at -0.0762 -8.1534 270)
			(unlocked yes)
			(layer "F.Fab")
			(hide yes)
			(effects
				(font
					(size 1.016 1.016)
					(thickness 0.1524)
				)
			)
		)
		(duplicate_pad_numbers_are_jumpers no)
		(fp_line
			(start 0.635 0)
			(end -0.635 0)
			(stroke
				(width 0.508)
				(type default)
			)
			(layer "F.SilkS")
		)
		(fp_rect
			(start -0.9652 1.778)
			(end 0.9652 -1.778)
			(stroke
				(width 0)
				(type default)
			)
			(fill no)
			(layer "F.CrtYd")
		)
		(fp_poly
			(pts
				(xy -0.9652 -1.778) (xy 0.9652 -1.778) (xy 0.9652 1.778) (xy -0.9652 1.778)
			)
			(stroke
				(width 0)
				(type default)
			)
			(fill no)
			(layer "F.Fab")
		)
		(pad "1" smd rect
			(at 0 -0.9652 270)
			(size 1.397 1.143)
			(layers "F.Cu" "F.Mask" "F.Paste")
			(net "P1V5_E_OUT")
		)
		(pad "2" smd rect
			(at 0 0.9652 270)
			(size 1.397 1.143)
			(layers "F.Cu" "F.Mask" "F.Paste")
			(net "GND")
		)
	)
	(footprint ""
		(layer "F.Cu")
		(at 187.27928 -108.70692 -90)
		(property "Reference" "C715"
			(at 0 0 270)
			(layer "F.SilkS")
			(hide yes)
			(effects
				(font
					(size 1.27 1.27)
				)
			)
		)
		(property "Value" "SCD1U16V2KX-3GP"
			(at 1.1811 -2.7051 270)
			(unlocked yes)
			(layer "F.Fab")
			(hide yes)
			(effects
				(font
					(size 1.016 1.016)
					(thickness 0.1524)
				)
			)
		)
		(property "Device Type" "C402H22"
			(at 1.1811 -4.2291 270)
			(unlocked yes)
			(layer "F.Fab")
			(hide yes)
			(effects
				(font
					(size 1.016 1.016)
					(thickness 0.1524)
				)
			)
		)
		(duplicate_pad_numbers_are_jumpers no)
		(fp_rect
			(start -0.4318 0.9525)
			(end 0.4318 -0.9525)
			(stroke
				(width 0)
				(type default)
			)
			(fill no)
			(layer "F.CrtYd")
		)
		(fp_rect
			(start -0.4318 0.9525)
			(end 0.4318 -0.9525)
			(stroke
				(width 0)
				(type default)
			)
			(fill no)
			(layer "F.Fab")
		)
		(pad "1" smd custom
			(at 0 -0.4445 270)
			(size 0.1524 0.1524)
			(layers "F.Cu" "F.Mask" "F.Paste")
			(net "P1V8_C_S")
			(options
				(clearance outline)
				(anchor circle)
			)
			(primitives
				(gr_poly
					(pts
						(arc
							(start 0.3048 -0.2032)
							(mid 0.275042 -0.275042)
							(end 0.2032 -0.3048)
						)
						(arc
							(start -0.2032 -0.3048)
							(mid -0.275042 -0.275042)
							(end -0.3048 -0.2032)
						)
						(arc
							(start -0.3048 0.2032)
							(mid -0.275042 0.275042)
							(end -0.2032 0.3048)
						)
						(arc
							(start 0.2032 0.3048)
							(mid 0.275042 0.275042)
							(end 0.3048 0.2032)
						)
					)
					(width 0)
					(fill yes)
				)
			)
		)
		(pad "2" smd custom
			(at 0 0.4445 270)
			(size 0.1524 0.1524)
			(layers "F.Cu" "F.Mask" "F.Paste")
			(net "GND")
			(options
				(clearance outline)
				(anchor circle)
			)
			(primitives
				(gr_poly
					(pts
						(arc
							(start 0.3048 -0.2032)
							(mid 0.275042 -0.275042)
							(end 0.2032 -0.3048)
						)
						(arc
							(start -0.2032 -0.3048)
							(mid -0.275042 -0.275042)
							(end -0.3048 -0.2032)
						)
						(arc
							(start -0.3048 0.2032)
							(mid -0.275042 0.275042)
							(end -0.2032 0.3048)
						)
						(arc
							(start 0.2032 0.3048)
							(mid 0.275042 0.275042)
							(end 0.3048 0.2032)
						)
					)
					(width 0)
					(fill yes)
				)
			)
		)
	)
	(footprint ""
		(layer "F.Cu")
		(at 175.48606 -105.47858)
		(property "Reference" "Q11"
			(at 0 0 0)
			(layer "F.SilkS")
			(hide yes)
			(effects
				(font
					(size 1.27 1.27)
				)
			)
		)
		(property "Value" "SSM3K324R-GP"
			(at 0.127 -8.9662 0)
			(unlocked yes)
			(layer "F.Fab")
			(hide yes)
			(effects
				(font
					(size 1.016 1.016)
					(thickness 0.1524)
				)
			)
		)
		(property "Device Type" "SOT23DGS2D4H35"
			(at 0.127 -10.4902 0)
			(unlocked yes)
			(layer "F.Fab")
			(hide yes)
			(effects
				(font
					(size 1.016 1.016)
					(thickness 0.1524)
				)
			)
		)
		(duplicate_pad_numbers_are_jumpers no)
		(fp_line
			(start -1.651 -1.778)
			(end -1.651 1.778)
			(stroke
				(width 0.1524)
				(type default)
			)
			(layer "F.SilkS")
		)
		(fp_line
			(start -1.651 1.778)
			(end 1.651 1.778)
			(stroke
				(width 0.1524)
				(type default)
			)
			(layer "F.SilkS")
		)
		(fp_line
			(start 1.651 -1.778)
			(end -1.651 -1.778)
			(stroke
				(width 0.1524)
				(type default)
			)
			(layer "F.SilkS")
		)
		(fp_line
			(start 1.651 1.778)
			(end 1.651 -1.778)
			(stroke
				(width 0.1524)
				(type default)
			)
			(layer "F.SilkS")
		)
		(fp_poly
			(pts
				(xy -1.778 1.8796) (xy -1.778 -1.8796) (xy 1.778 -1.8796) (xy 1.778 1.8796)
			)
			(stroke
				(width 0)
				(type default)
			)
			(fill no)
			(layer "F.CrtYd")
		)
		(fp_poly
			(pts
				(xy -1.778 1.8796) (xy -1.778 -1.8796) (xy 1.778 -1.8796) (xy 1.778 1.8796)
			)
			(stroke
				(width 0)
				(type default)
			)
			(fill no)
			(layer "F.Fab")
		)
		(pad "D" smd custom
			(at 0 -0.9525)
			(size 0.1905 0.1905)
			(layers "F.Cu" "F.Mask" "F.Paste")
			(net "P12V_STBY_Q12_G")
			(options
				(clearance outline)
				(anchor circle)
			)
			(primitives
				(gr_poly
					(pts
						(arc
							(start -0.1778 0.5715)
							(mid -0.321484 0.511984)
							(end -0.381 0.3683)
						)
						(arc
							(start -0.381 -0.3683)
							(mid -0.321484 -0.511984)
							(end -0.1778 -0.5715)
						)
						(arc
							(start 0.1778 -0.5715)
							(mid 0.321484 -0.511984)
							(end 0.381 -0.3683)
						)
						(arc
							(start 0.381 0.3683)
							(mid 0.321484 0.511984)
							(end 0.1778 0.5715)
						)
					)
					(width 0)
					(fill yes)
				)
			)
		)
		(pad "G" smd custom
			(at -0.98425 0.9525)
			(size 0.1905 0.1905)
			(layers "F.Cu" "F.Mask" "F.Paste")
			(net "P1V8_C_G")
			(options
				(clearance outline)
				(anchor circle)
			)
			(primitives
				(gr_poly
					(pts
						(arc
							(start -0.1778 0.5715)
							(mid -0.321484 0.511984)
							(end -0.381 0.3683)
						)
						(arc
							(start -0.381 -0.3683)
							(mid -0.321484 -0.511984)
							(end -0.1778 -0.5715)
						)
						(arc
							(start 0.1778 -0.5715)
							(mid 0.321484 -0.511984)
							(end 0.381 -0.3683)
						)
						(arc
							(start 0.381 0.3683)
							(mid 0.321484 0.511984)
							(end 0.1778 0.5715)
						)
					)
					(width 0)
					(fill yes)
				)
			)
		)
		(pad "S" smd custom
			(at 0.98425 0.9525)
			(size 0.1905 0.1905)
			(layers "F.Cu" "F.Mask" "F.Paste")
			(net "GND")
			(options
				(clearance outline)
				(anchor circle)
			)
			(primitives
				(gr_poly
					(pts
						(arc
							(start -0.1778 0.5715)
							(mid -0.321484 0.511984)
							(end -0.381 0.3683)
						)
						(arc
							(start -0.381 -0.3683)
							(mid -0.321484 -0.511984)
							(end -0.1778 -0.5715)
						)
						(arc
							(start 0.1778 -0.5715)
							(mid 0.321484 -0.511984)
							(end 0.381 -0.3683)
						)
						(arc
							(start 0.381 0.3683)
							(mid 0.321484 0.511984)
							(end 0.1778 0.5715)
						)
					)
					(width 0)
					(fill yes)
				)
			)
		)
	)
	(footprint ""
		(layer "F.Cu")
		(at 191.850772 -45.479462 -90)
		(property "Reference" "R180"
			(at 0 0 270)
			(layer "F.SilkS")
			(hide yes)
			(effects
				(font
					(size 1.27 1.27)
				)
			)
		)
		(property "Value" "2K2R2F-GP"
			(at 0.064008 -3.993896 270)
			(unlocked yes)
			(layer "F.Fab")
			(hide yes)
			(effects
				(font
					(size 1.016 1.016)
					(thickness 0.1524)
				)
			)
		)
		(property "Device Type" "R402H16"
			(at 0.064008 -5.517896 270)
			(unlocked yes)
			(layer "F.Fab")
			(hide yes)
			(effects
				(font
					(size 1.016 1.016)
					(thickness 0.1524)
				)
			)
		)
		(duplicate_pad_numbers_are_jumpers no)
		(fp_line
			(start -0.508 -0.9398)
			(end -0.508 0.9398)
			(stroke
				(width 0.1524)
				(type default)
			)
			(layer "F.SilkS")
		)
		(fp_line
			(start 0.508 -0.9398)
			(end -0.508 -0.9398)
			(stroke
				(width 0.1524)
				(type default)
			)
			(layer "F.SilkS")
		)
		(fp_rect
			(start -0.508 0.9398)
			(end 0.508 -0.9398)
			(stroke
				(width 0)
				(type default)
			)
			(fill no)
			(layer "F.CrtYd")
		)
		(fp_rect
			(start -0.508 0.9398)
			(end 0.508 -0.9398)
			(stroke
				(width 0)
				(type default)
			)
			(fill no)
			(layer "F.Fab")
		)
		(pad "1" smd custom
			(at 0 -0.4445 270)
			(size 0.1397 0.1397)
			(layers "F.Cu" "F.Mask" "F.Paste")
			(net "P1V8_C")
			(options
				(clearance outline)
				(anchor circle)
			)
			(primitives
				(gr_poly
					(pts
						(arc
							(start -0.1778 -0.2794)
							(mid -0.249642 -0.249642)
							(end -0.2794 -0.1778)
						)
						(arc
							(start -0.2794 0.1778)
							(mid -0.249642 0.249642)
							(end -0.1778 0.2794)
						)
						(arc
							(start 0.1778 0.2794)
							(mid 0.249642 0.249642)
							(end 0.2794 0.1778)
						)
						(arc
							(start 0.2794 -0.1778)
							(mid 0.249642 -0.249642)
							(end 0.1778 -0.2794)
						)
					)
					(width 0)
					(fill yes)
				)
			)
		)
		(pad "2" smd custom
			(at 0 0.4445 270)
			(size 0.1397 0.1397)
			(layers "F.Cu" "F.Mask" "F.Paste")
			(net "SBL_SDA")
			(options
				(clearance outline)
				(anchor circle)
			)
			(primitives
				(gr_poly
					(pts
						(arc
							(start -0.1778 -0.2794)
							(mid -0.249642 -0.249642)
							(end -0.2794 -0.1778)
						)
						(arc
							(start -0.2794 0.1778)
							(mid -0.249642 0.249642)
							(end -0.1778 0.2794)
						)
						(arc
							(start 0.1778 0.2794)
							(mid 0.249642 0.249642)
							(end 0.2794 0.1778)
						)
						(arc
							(start 0.2794 -0.1778)
							(mid 0.249642 -0.249642)
							(end 0.1778 -0.2794)
						)
					)
					(width 0)
					(fill yes)
				)
			)
		)
	)
	(footprint ""
		(layer "F.Cu")
		(at 6.9088 -77.089 180)
		(property "Reference" "R337"
			(at 0 0 180)
			(layer "F.SilkS")
			(hide yes)
			(effects
				(font
					(size 1.27 1.27)
				)
			)
		)
		(property "Value" "4K7R2F-GP"
			(at 0.064008 -3.993896 180)
			(unlocked yes)
			(layer "F.Fab")
			(hide yes)
			(effects
				(font
					(size 1.016 1.016)
					(thickness 0.1524)
				)
			)
		)
		(property "Device Type" "R402H16"
			(at 0.064008 -5.517896 180)
			(unlocked yes)
			(layer "F.Fab")
			(hide yes)
			(effects
				(font
					(size 1.016 1.016)
					(thickness 0.1524)
				)
			)
		)
		(duplicate_pad_numbers_are_jumpers no)
		(fp_line
			(start 0.508 -0.9398)
			(end -0.508 -0.9398)
			(stroke
				(width 0.1524)
				(type default)
			)
			(layer "F.SilkS")
		)
		(fp_line
			(start -0.508 -0.9398)
			(end -0.508 0.9398)
			(stroke
				(width 0.1524)
				(type default)
			)
			(layer "F.SilkS")
		)
		(fp_rect
			(start -0.508 0.9398)
			(end 0.508 -0.9398)
			(stroke
				(width 0)
				(type default)
			)
			(fill no)
			(layer "F.CrtYd")
		)
		(fp_rect
			(start -0.508 0.9398)
			(end 0.508 -0.9398)
			(stroke
				(width 0)
				(type default)
			)
			(fill no)
			(layer "F.Fab")
		)
		(pad "1" smd custom
			(at 0 -0.4445 180)
			(size 0.1397 0.1397)
			(layers "F.Cu" "F.Mask" "F.Paste")
			(net "P3V3")
			(options
				(clearance outline)
				(anchor circle)
			)
			(primitives
				(gr_poly
					(pts
						(arc
							(start -0.1778 -0.2794)
							(mid -0.249642 -0.249642)
							(end -0.2794 -0.1778)
						)
						(arc
							(start -0.2794 0.1778)
							(mid -0.249642 0.249642)
							(end -0.1778 0.2794)
						)
						(arc
							(start 0.1778 0.2794)
							(mid 0.249642 0.249642)
							(end 0.2794 0.1778)
						)
						(arc
							(start 0.2794 -0.1778)
							(mid 0.249642 -0.249642)
							(end 0.1778 -0.2794)
						)
					)
					(width 0)
					(fill yes)
				)
			)
		)
		(pad "2" smd custom
			(at 0 0.4445 180)
			(size 0.1397 0.1397)
			(layers "F.Cu" "F.Mask" "F.Paste")
			(net "EXP_EEPROM_A2")
			(options
				(clearance outline)
				(anchor circle)
			)
			(primitives
				(gr_poly
					(pts
						(arc
							(start -0.1778 -0.2794)
							(mid -0.249642 -0.249642)
							(end -0.2794 -0.1778)
						)
						(arc
							(start -0.2794 0.1778)
							(mid -0.249642 0.249642)
							(end -0.1778 0.2794)
						)
						(arc
							(start 0.1778 0.2794)
							(mid 0.249642 0.249642)
							(end 0.2794 0.1778)
						)
						(arc
							(start 0.2794 -0.1778)
							(mid 0.249642 -0.249642)
							(end 0.1778 -0.2794)
						)
					)
					(width 0)
					(fill yes)
				)
			)
		)
	)
	(footprint ""
		(layer "F.Cu")
		(at 162.961066 -58.13806)
		(property "Reference" "R266"
			(at 0 0 0)
			(layer "F.SilkS")
			(hide yes)
			(effects
				(font
					(size 1.27 1.27)
				)
			)
		)
		(property "Value" "4K7R2F-GP"
			(at 0.064008 -3.993896 0)
			(unlocked yes)
			(layer "F.Fab")
			(hide yes)
			(effects
				(font
					(size 1.016 1.016)
					(thickness 0.1524)
				)
			)
		)
		(property "Device Type" "R402H16"
			(at 0.064008 -5.517896 0)
			(unlocked yes)
			(layer "F.Fab")
			(hide yes)
			(effects
				(font
					(size 1.016 1.016)
					(thickness 0.1524)
				)
			)
		)
		(duplicate_pad_numbers_are_jumpers no)
		(fp_line
			(start -0.508 -0.9398)
			(end -0.508 0.9398)
			(stroke
				(width 0.1524)
				(type default)
			)
			(layer "F.SilkS")
		)
		(fp_line
			(start 0.508 -0.9398)
			(end -0.508 -0.9398)
			(stroke
				(width 0.1524)
				(type default)
			)
			(layer "F.SilkS")
		)
		(fp_rect
			(start -0.508 0.9398)
			(end 0.508 -0.9398)
			(stroke
				(width 0)
				(type default)
			)
			(fill no)
			(layer "F.CrtYd")
		)
		(fp_rect
			(start -0.508 0.9398)
			(end 0.508 -0.9398)
			(stroke
				(width 0)
				(type default)
			)
			(fill no)
			(layer "F.Fab")
		)
		(pad "1" smd custom
			(at 0 -0.4445)
			(size 0.1397 0.1397)
			(layers "F.Cu" "F.Mask" "F.Paste")
			(net "P1V8_C")
			(options
				(clearance outline)
				(anchor circle)
			)
			(primitives
				(gr_poly
					(pts
						(arc
							(start -0.1778 -0.2794)
							(mid -0.249642 -0.249642)
							(end -0.2794 -0.1778)
						)
						(arc
							(start -0.2794 0.1778)
							(mid -0.249642 0.249642)
							(end -0.1778 0.2794)
						)
						(arc
							(start 0.1778 0.2794)
							(mid 0.249642 0.249642)
							(end 0.2794 0.1778)
						)
						(arc
							(start 0.2794 -0.1778)
							(mid 0.249642 -0.249642)
							(end 0.1778 -0.2794)
						)
					)
					(width 0)
					(fill yes)
				)
			)
		)
		(pad "2" smd custom
			(at 0 0.4445)
			(size 0.1397 0.1397)
			(layers "F.Cu" "F.Mask" "F.Paste")
			(net "ICE0_TMS")
			(options
				(clearance outline)
				(anchor circle)
			)
			(primitives
				(gr_poly
					(pts
						(arc
							(start -0.1778 -0.2794)
							(mid -0.249642 -0.249642)
							(end -0.2794 -0.1778)
						)
						(arc
							(start -0.2794 0.1778)
							(mid -0.249642 0.249642)
							(end -0.1778 0.2794)
						)
						(arc
							(start 0.1778 0.2794)
							(mid 0.249642 0.249642)
							(end 0.2794 0.1778)
						)
						(arc
							(start 0.2794 -0.1778)
							(mid 0.249642 -0.249642)
							(end 0.1778 -0.2794)
						)
					)
					(width 0)
					(fill yes)
				)
			)
		)
	)
	(footprint ""
		(layer "F.Cu")
		(at 174.3202 -93.5482)
		(property "Reference" "C623"
			(at 0 0 0)
			(layer "F.SilkS")
			(hide yes)
			(effects
				(font
					(size 1.27 1.27)
				)
			)
		)
		(property "Value" "SC1U25V3KX-GP"
			(at 0 -2.8194 0)
			(unlocked yes)
			(layer "F.Fab")
			(hide yes)
			(effects
				(font
					(size 1.016 1.016)
					(thickness 0.1524)
				)
			)
		)
		(property "Device Type" "C603H36"
			(at 0 -4.3434 0)
			(unlocked yes)
			(layer "F.Fab")
			(hide yes)
			(effects
				(font
					(size 1.016 1.016)
					(thickness 0.1524)
				)
			)
		)
		(duplicate_pad_numbers_are_jumpers no)
		(fp_line
			(start 0.508 0)
			(end -0.508 0)
			(stroke
				(width 0.2032)
				(type default)
			)
			(layer "F.SilkS")
		)
		(fp_rect
			(start -0.5842 1.3335)
			(end 0.5842 -1.3335)
			(stroke
				(width 0)
				(type default)
			)
			(fill no)
			(layer "F.CrtYd")
		)
		(fp_rect
			(start -0.5842 1.3335)
			(end 0.5842 -1.3335)
			(stroke
				(width 0)
				(type default)
			)
			(fill no)
			(layer "F.Fab")
		)
		(pad "1" smd custom
			(at 0 -0.762)
			(size 0.2159 0.2159)
			(layers "F.Cu" "F.Mask" "F.Paste")
			(net "VT235_BST")
			(options
				(clearance outline)
				(anchor circle)
			)
			(primitives
				(gr_poly
					(pts
						(arc
							(start -0.3302 -0.4318)
							(mid -0.402042 -0.402042)
							(end -0.4318 -0.3302)
						)
						(arc
							(start -0.4318 0.3302)
							(mid -0.402042 0.402042)
							(end -0.3302 0.4318)
						)
						(arc
							(start 0.3302 0.4318)
							(mid 0.402042 0.402042)
							(end 0.4318 0.3302)
						)
						(arc
							(start 0.4318 -0.3302)
							(mid 0.402042 -0.402042)
							(end 0.3302 -0.4318)
						)
					)
					(width 0)
					(fill yes)
				)
			)
		)
		(pad "2" smd custom
			(at 0 0.762)
			(size 0.2159 0.2159)
			(layers "F.Cu" "F.Mask" "F.Paste")
			(net "VT235_VX")
			(options
				(clearance outline)
				(anchor circle)
			)
			(primitives
				(gr_poly
					(pts
						(arc
							(start -0.3302 -0.4318)
							(mid -0.402042 -0.402042)
							(end -0.4318 -0.3302)
						)
						(arc
							(start -0.4318 0.3302)
							(mid -0.402042 0.402042)
							(end -0.3302 0.4318)
						)
						(arc
							(start 0.3302 0.4318)
							(mid 0.402042 0.402042)
							(end 0.4318 0.3302)
						)
						(arc
							(start 0.4318 -0.3302)
							(mid 0.402042 -0.402042)
							(end 0.3302 -0.4318)
						)
					)
					(width 0)
					(fill yes)
				)
			)
		)
	)
	(footprint ""
		(layer "F.Cu")
		(at 26.65222 -30.93974)
		(property "Reference" "C566"
			(at 0 0 0)
			(layer "F.SilkS")
			(hide yes)
			(effects
				(font
					(size 1.27 1.27)
				)
			)
		)
		(property "Value" "SC10U16V5KX-7-GP-U"
			(at -0.0762 -6.1214 0)
			(unlocked yes)
			(layer "F.Fab")
			(hide yes)
			(effects
				(font
					(size 1.016 1.016)
					(thickness 0.1524)
				)
			)
		)
		(property "Device Type" "C805H58"
			(at -0.0762 -8.1534 0)
			(unlocked yes)
			(layer "F.Fab")
			(hide yes)
			(effects
				(font
					(size 1.016 1.016)
					(thickness 0.1524)
				)
			)
		)
		(duplicate_pad_numbers_are_jumpers no)
		(fp_line
			(start 0.635 0)
			(end -0.635 0)
			(stroke
				(width 0.508)
				(type default)
			)
			(layer "F.SilkS")
		)
		(fp_rect
			(start -0.9652 1.778)
			(end 0.9652 -1.778)
			(stroke
				(width 0)
				(type default)
			)
			(fill no)
			(layer "F.CrtYd")
		)
		(fp_poly
			(pts
				(xy -0.9652 -1.778) (xy 0.9652 -1.778) (xy 0.9652 1.778) (xy -0.9652 1.778)
			)
			(stroke
				(width 0)
				(type default)
			)
			(fill no)
			(layer "F.Fab")
		)
		(pad "1" smd rect
			(at 0 -0.9652)
			(size 1.397 1.143)
			(layers "F.Cu" "F.Mask" "F.Paste")
			(net "P12V_MAIN")
		)
		(pad "2" smd rect
			(at 0 0.9652)
			(size 1.397 1.143)
			(layers "F.Cu" "F.Mask" "F.Paste")
			(net "GND")
		)
	)
	(footprint ""
		(layer "F.Cu")
		(at 160.274 -85.725 90)
		(property "Reference" "C519"
			(at 0 0 90)
			(layer "F.SilkS")
			(hide yes)
			(effects
				(font
					(size 1.27 1.27)
				)
			)
		)
		(property "Value" "SCD1U16V2KX-3GP"
			(at 1.1811 -2.7051 90)
			(unlocked yes)
			(layer "F.Fab")
			(hide yes)
			(effects
				(font
					(size 1.016 1.016)
					(thickness 0.1524)
				)
			)
		)
		(property "Device Type" "C402H22"
			(at 1.1811 -4.2291 90)
			(unlocked yes)
			(layer "F.Fab")
			(hide yes)
			(effects
				(font
					(size 1.016 1.016)
					(thickness 0.1524)
				)
			)
		)
		(duplicate_pad_numbers_are_jumpers no)
		(fp_rect
			(start -0.4318 0.9525)
			(end 0.4318 -0.9525)
			(stroke
				(width 0)
				(type default)
			)
			(fill no)
			(layer "F.CrtYd")
		)
		(fp_rect
			(start -0.4318 0.9525)
			(end 0.4318 -0.9525)
			(stroke
				(width 0)
				(type default)
			)
			(fill no)
			(layer "F.Fab")
		)
		(pad "1" smd custom
			(at 0 -0.4445 90)
			(size 0.1524 0.1524)
			(layers "F.Cu" "F.Mask" "F.Paste")
			(net "P3V3")
			(options
				(clearance outline)
				(anchor circle)
			)
			(primitives
				(gr_poly
					(pts
						(arc
							(start 0.3048 -0.2032)
							(mid 0.275042 -0.275042)
							(end 0.2032 -0.3048)
						)
						(arc
							(start -0.2032 -0.3048)
							(mid -0.275042 -0.275042)
							(end -0.3048 -0.2032)
						)
						(arc
							(start -0.3048 0.2032)
							(mid -0.275042 0.275042)
							(end -0.2032 0.3048)
						)
						(arc
							(start 0.2032 0.3048)
							(mid 0.275042 0.275042)
							(end 0.3048 0.2032)
						)
					)
					(width 0)
					(fill yes)
				)
			)
		)
		(pad "2" smd custom
			(at 0 0.4445 90)
			(size 0.1524 0.1524)
			(layers "F.Cu" "F.Mask" "F.Paste")
			(net "GND")
			(options
				(clearance outline)
				(anchor circle)
			)
			(primitives
				(gr_poly
					(pts
						(arc
							(start 0.3048 -0.2032)
							(mid 0.275042 -0.275042)
							(end 0.2032 -0.3048)
						)
						(arc
							(start -0.2032 -0.3048)
							(mid -0.275042 -0.275042)
							(end -0.3048 -0.2032)
						)
						(arc
							(start -0.3048 0.2032)
							(mid -0.275042 0.275042)
							(end -0.2032 0.3048)
						)
						(arc
							(start 0.2032 0.3048)
							(mid 0.275042 0.275042)
							(end 0.3048 0.2032)
						)
					)
					(width 0)
					(fill yes)
				)
			)
		)
	)
	(footprint ""
		(layer "F.Cu")
		(at 41.0972 -27.6987 90)
		(property "Reference" "R386"
			(at 0 0 90)
			(layer "F.SilkS")
			(hide yes)
			(effects
				(font
					(size 1.27 1.27)
				)
			)
		)
		(property "Value" "0R2J-2-GP"
			(at 0.064008 -3.993896 90)
			(unlocked yes)
			(layer "F.Fab")
			(hide yes)
			(effects
				(font
					(size 1.016 1.016)
					(thickness 0.1524)
				)
			)
		)
		(property "Device Type" "R402H16"
			(at 0.064008 -5.517896 90)
			(unlocked yes)
			(layer "F.Fab")
			(hide yes)
			(effects
				(font
					(size 1.016 1.016)
					(thickness 0.1524)
				)
			)
		)
		(duplicate_pad_numbers_are_jumpers no)
		(fp_line
			(start 0.508 -0.9398)
			(end -0.508 -0.9398)
			(stroke
				(width 0.1524)
				(type default)
			)
			(layer "F.SilkS")
		)
		(fp_line
			(start -0.508 -0.9398)
			(end -0.508 0.9398)
			(stroke
				(width 0.1524)
				(type default)
			)
			(layer "F.SilkS")
		)
		(fp_rect
			(start -0.508 0.9398)
			(end 0.508 -0.9398)
			(stroke
				(width 0)
				(type default)
			)
			(fill no)
			(layer "F.CrtYd")
		)
		(fp_rect
			(start -0.508 0.9398)
			(end 0.508 -0.9398)
			(stroke
				(width 0)
				(type default)
			)
			(fill no)
			(layer "F.Fab")
		)
		(pad "1" smd custom
			(at 0 -0.4445 90)
			(size 0.1397 0.1397)
			(layers "F.Cu" "F.Mask" "F.Paste")
			(net "P0V9_PG")
			(options
				(clearance outline)
				(anchor circle)
			)
			(primitives
				(gr_poly
					(pts
						(arc
							(start -0.1778 -0.2794)
							(mid -0.249642 -0.249642)
							(end -0.2794 -0.1778)
						)
						(arc
							(start -0.2794 0.1778)
							(mid -0.249642 0.249642)
							(end -0.1778 0.2794)
						)
						(arc
							(start 0.1778 0.2794)
							(mid 0.249642 0.249642)
							(end 0.2794 0.1778)
						)
						(arc
							(start 0.2794 -0.1778)
							(mid 0.249642 -0.249642)
							(end 0.1778 -0.2794)
						)
					)
					(width 0)
					(fill yes)
				)
			)
		)
		(pad "2" smd custom
			(at 0 0.4445 90)
			(size 0.1397 0.1397)
			(layers "F.Cu" "F.Mask" "F.Paste")
			(net "P0V9_U8_PG")
			(options
				(clearance outline)
				(anchor circle)
			)
			(primitives
				(gr_poly
					(pts
						(arc
							(start -0.1778 -0.2794)
							(mid -0.249642 -0.249642)
							(end -0.2794 -0.1778)
						)
						(arc
							(start -0.2794 0.1778)
							(mid -0.249642 0.249642)
							(end -0.1778 0.2794)
						)
						(arc
							(start 0.1778 0.2794)
							(mid 0.249642 0.249642)
							(end 0.2794 0.1778)
						)
						(arc
							(start 0.2794 -0.1778)
							(mid 0.249642 -0.249642)
							(end 0.1778 -0.2794)
						)
					)
					(width 0)
					(fill yes)
				)
			)
		)
	)
	(footprint ""
		(layer "F.Cu")
		(at 18.6944 -56.134 -90)
		(property "Reference" "C648"
			(at 0 0 270)
			(layer "F.SilkS")
			(hide yes)
			(effects
				(font
					(size 1.27 1.27)
				)
			)
		)
		(property "Value" "SCD01U25V2KX-3GP"
			(at 1.1811 -2.7051 270)
			(unlocked yes)
			(layer "F.Fab")
			(hide yes)
			(effects
				(font
					(size 1.016 1.016)
					(thickness 0.1524)
				)
			)
		)
		(property "Device Type" "C402H22"
			(at 1.1811 -4.2291 270)
			(unlocked yes)
			(layer "F.Fab")
			(hide yes)
			(effects
				(font
					(size 1.016 1.016)
					(thickness 0.1524)
				)
			)
		)
		(duplicate_pad_numbers_are_jumpers no)
		(fp_rect
			(start -0.4318 0.9525)
			(end 0.4318 -0.9525)
			(stroke
				(width 0)
				(type default)
			)
			(fill no)
			(layer "F.CrtYd")
		)
		(fp_rect
			(start -0.4318 0.9525)
			(end 0.4318 -0.9525)
			(stroke
				(width 0)
				(type default)
			)
			(fill no)
			(layer "F.Fab")
		)
		(pad "1" smd custom
			(at 0 -0.4445 270)
			(size 0.1524 0.1524)
			(layers "F.Cu" "F.Mask" "F.Paste")
			(net "AGND_CURRENT_MON")
			(options
				(clearance outline)
				(anchor circle)
			)
			(primitives
				(gr_poly
					(pts
						(arc
							(start 0.3048 -0.2032)
							(mid 0.275042 -0.275042)
							(end 0.2032 -0.3048)
						)
						(arc
							(start -0.2032 -0.3048)
							(mid -0.275042 -0.275042)
							(end -0.3048 -0.2032)
						)
						(arc
							(start -0.3048 0.2032)
							(mid -0.275042 0.275042)
							(end -0.2032 0.3048)
						)
						(arc
							(start 0.2032 0.3048)
							(mid 0.275042 0.275042)
							(end 0.3048 0.2032)
						)
					)
					(width 0)
					(fill yes)
				)
			)
		)
		(pad "2" smd custom
			(at 0 0.4445 270)
			(size 0.1524 0.1524)
			(layers "F.Cu" "F.Mask" "F.Paste")
			(net "MB0_TIME_R")
			(options
				(clearance outline)
				(anchor circle)
			)
			(primitives
				(gr_poly
					(pts
						(arc
							(start 0.3048 -0.2032)
							(mid 0.275042 -0.275042)
							(end 0.2032 -0.3048)
						)
						(arc
							(start -0.2032 -0.3048)
							(mid -0.275042 -0.275042)
							(end -0.3048 -0.2032)
						)
						(arc
							(start -0.3048 0.2032)
							(mid -0.275042 0.275042)
							(end -0.2032 0.3048)
						)
						(arc
							(start 0.2032 0.3048)
							(mid 0.275042 0.275042)
							(end 0.3048 0.2032)
						)
					)
					(width 0)
					(fill yes)
				)
			)
		)
	)
	(footprint ""
		(layer "F.Cu")
		(at 11.5316 -93.3196 90)
		(property "Reference" "R434"
			(at 0 0 90)
			(layer "F.SilkS")
			(hide yes)
			(effects
				(font
					(size 1.27 1.27)
				)
			)
		)
		(property "Value" "0R2J-2-GP"
			(at 0.064008 -3.993896 90)
			(unlocked yes)
			(layer "F.Fab")
			(hide yes)
			(effects
				(font
					(size 1.016 1.016)
					(thickness 0.1524)
				)
			)
		)
		(property "Device Type" "R402H16"
			(at 0.064008 -5.517896 90)
			(unlocked yes)
			(layer "F.Fab")
			(hide yes)
			(effects
				(font
					(size 1.016 1.016)
					(thickness 0.1524)
				)
			)
		)
		(duplicate_pad_numbers_are_jumpers no)
		(fp_line
			(start 0.508 -0.9398)
			(end -0.508 -0.9398)
			(stroke
				(width 0.1524)
				(type default)
			)
			(layer "F.SilkS")
		)
		(fp_line
			(start -0.508 -0.9398)
			(end -0.508 0.9398)
			(stroke
				(width 0.1524)
				(type default)
			)
			(layer "F.SilkS")
		)
		(fp_rect
			(start -0.508 0.9398)
			(end 0.508 -0.9398)
			(stroke
				(width 0)
				(type default)
			)
			(fill no)
			(layer "F.CrtYd")
		)
		(fp_rect
			(start -0.508 0.9398)
			(end 0.508 -0.9398)
			(stroke
				(width 0)
				(type default)
			)
			(fill no)
			(layer "F.Fab")
		)
		(pad "1" smd custom
			(at 0 -0.4445 90)
			(size 0.1397 0.1397)
			(layers "F.Cu" "F.Mask" "F.Paste")
			(net "LS_EN_U40")
			(options
				(clearance outline)
				(anchor circle)
			)
			(primitives
				(gr_poly
					(pts
						(arc
							(start -0.1778 -0.2794)
							(mid -0.249642 -0.249642)
							(end -0.2794 -0.1778)
						)
						(arc
							(start -0.2794 0.1778)
							(mid -0.249642 0.249642)
							(end -0.1778 0.2794)
						)
						(arc
							(start 0.1778 0.2794)
							(mid 0.249642 0.249642)
							(end 0.2794 0.1778)
						)
						(arc
							(start 0.2794 -0.1778)
							(mid 0.249642 -0.249642)
							(end 0.1778 -0.2794)
						)
					)
					(width 0)
					(fill yes)
				)
			)
		)
		(pad "2" smd custom
			(at 0 0.4445 90)
			(size 0.1397 0.1397)
			(layers "F.Cu" "F.Mask" "F.Paste")
			(net "VREF3")
			(options
				(clearance outline)
				(anchor circle)
			)
			(primitives
				(gr_poly
					(pts
						(arc
							(start -0.1778 -0.2794)
							(mid -0.249642 -0.249642)
							(end -0.2794 -0.1778)
						)
						(arc
							(start -0.2794 0.1778)
							(mid -0.249642 0.249642)
							(end -0.1778 0.2794)
						)
						(arc
							(start 0.1778 0.2794)
							(mid 0.249642 0.249642)
							(end 0.2794 0.1778)
						)
						(arc
							(start 0.2794 -0.1778)
							(mid 0.249642 -0.249642)
							(end 0.1778 -0.2794)
						)
					)
					(width 0)
					(fill yes)
				)
			)
		)
	)
	(footprint ""
		(layer "F.Cu")
		(at 55.937658 -17.40281 180)
		(property "Reference" "R587"
			(at 0 0 180)
			(layer "F.SilkS")
			(hide yes)
			(effects
				(font
					(size 1.27 1.27)
				)
			)
		)
		(property "Value" "10KR2F-2-GP"
			(at 0.064008 -3.993896 180)
			(unlocked yes)
			(layer "F.Fab")
			(hide yes)
			(effects
				(font
					(size 1.016 1.016)
					(thickness 0.1524)
				)
			)
		)
		(property "Device Type" "R402H16"
			(at 0.064008 -5.517896 180)
			(unlocked yes)
			(layer "F.Fab")
			(hide yes)
			(effects
				(font
					(size 1.016 1.016)
					(thickness 0.1524)
				)
			)
		)
		(duplicate_pad_numbers_are_jumpers no)
		(fp_line
			(start 0.508 -0.9398)
			(end -0.508 -0.9398)
			(stroke
				(width 0.1524)
				(type default)
			)
			(layer "F.SilkS")
		)
		(fp_line
			(start -0.508 -0.9398)
			(end -0.508 0.9398)
			(stroke
				(width 0.1524)
				(type default)
			)
			(layer "F.SilkS")
		)
		(fp_rect
			(start -0.508 0.9398)
			(end 0.508 -0.9398)
			(stroke
				(width 0)
				(type default)
			)
			(fill no)
			(layer "F.CrtYd")
		)
		(fp_rect
			(start -0.508 0.9398)
			(end 0.508 -0.9398)
			(stroke
				(width 0)
				(type default)
			)
			(fill no)
			(layer "F.Fab")
		)
		(pad "1" smd custom
			(at 0 -0.4445 180)
			(size 0.1397 0.1397)
			(layers "F.Cu" "F.Mask" "F.Paste")
			(net "P3V3_DPB")
			(options
				(clearance outline)
				(anchor circle)
			)
			(primitives
				(gr_poly
					(pts
						(arc
							(start -0.1778 -0.2794)
							(mid -0.249642 -0.249642)
							(end -0.2794 -0.1778)
						)
						(arc
							(start -0.2794 0.1778)
							(mid -0.249642 0.249642)
							(end -0.1778 0.2794)
						)
						(arc
							(start 0.1778 0.2794)
							(mid 0.249642 0.249642)
							(end 0.2794 0.1778)
						)
						(arc
							(start 0.2794 -0.1778)
							(mid 0.249642 -0.249642)
							(end 0.1778 -0.2794)
						)
					)
					(width 0)
					(fill yes)
				)
			)
		)
		(pad "2" smd custom
			(at 0 0.4445 180)
			(size 0.1397 0.1397)
			(layers "F.Cu" "F.Mask" "F.Paste")
			(net "U47_OE")
			(options
				(clearance outline)
				(anchor circle)
			)
			(primitives
				(gr_poly
					(pts
						(arc
							(start -0.1778 -0.2794)
							(mid -0.249642 -0.249642)
							(end -0.2794 -0.1778)
						)
						(arc
							(start -0.2794 0.1778)
							(mid -0.249642 0.249642)
							(end -0.1778 0.2794)
						)
						(arc
							(start 0.1778 0.2794)
							(mid 0.249642 0.249642)
							(end 0.2794 0.1778)
						)
						(arc
							(start 0.2794 -0.1778)
							(mid 0.249642 -0.249642)
							(end 0.1778 -0.2794)
						)
					)
					(width 0)
					(fill yes)
				)
			)
		)
	)
	(footprint ""
		(layer "F.Cu")
		(at 8.382 -39.497 180)
		(property "Reference" "R526"
			(at 0 0 180)
			(layer "F.SilkS")
			(hide yes)
			(effects
				(font
					(size 1.27 1.27)
				)
			)
		)
		(property "Value" "10R5F-1-GP"
			(at 0 -8.9535 180)
			(unlocked yes)
			(layer "F.Fab")
			(hide yes)
			(effects
				(font
					(size 1.27 1.016)
					(thickness 0.1524)
				)
			)
		)
		(property "Device Type" "R805H24"
			(at 0 -10.6299 180)
			(unlocked yes)
			(layer "F.Fab")
			(hide yes)
			(effects
				(font
					(size 1.27 1.016)
					(thickness 0.1524)
				)
			)
		)
		(duplicate_pad_numbers_are_jumpers no)
		(fp_line
			(start 0.889 1.7018)
			(end 0.889 -0.508)
			(stroke
				(width 0.1524)
				(type default)
			)
			(layer "F.SilkS")
		)
		(fp_line
			(start 0.889 -1.7018)
			(end 0.889 -0.381)
			(stroke
				(width 0.1524)
				(type default)
			)
			(layer "F.SilkS")
		)
		(fp_line
			(start 0.889 -1.7018)
			(end -0.889 -1.7018)
			(stroke
				(width 0.1524)
				(type default)
			)
			(layer "F.SilkS")
		)
		(fp_line
			(start -0.889 1.7018)
			(end 0.889 1.7018)
			(stroke
				(width 0.1524)
				(type default)
			)
			(layer "F.SilkS")
		)
		(fp_line
			(start -0.889 0.0762)
			(end -0.889 1.7018)
			(stroke
				(width 0.1524)
				(type default)
			)
			(layer "F.SilkS")
		)
		(fp_line
			(start -0.889 -1.7018)
			(end -0.889 0.2794)
			(stroke
				(width 0.1524)
				(type default)
			)
			(layer "F.SilkS")
		)
		(fp_poly
			(pts
				(xy 0.9652 -1.778) (xy 0.9652 1.778) (xy -0.9652 1.778) (xy -0.9652 -1.778)
			)
			(stroke
				(width 0)
				(type default)
			)
			(fill no)
			(layer "F.CrtYd")
		)
		(fp_rect
			(start -0.9652 1.778)
			(end 0.9652 -1.778)
			(stroke
				(width 0)
				(type default)
			)
			(fill no)
			(layer "F.Fab")
		)
		(pad "1" smd rect
			(at 0 -0.9652 180)
			(size 1.397 1.143)
			(layers "F.Cu" "F.Mask" "F.Paste")
			(net "MB0_12V_CTRL_GATE1")
		)
		(pad "2" smd rect
			(at 0 0.9652 180)
			(size 1.397 1.143)
			(layers "F.Cu" "F.Mask" "F.Paste")
			(net "MB0_CM_GATE_R")
		)
	)
	(footprint ""
		(layer "F.Cu")
		(at 152.155398 -72.140318 -90)
		(property "Reference" "C532"
			(at 0 0 270)
			(layer "F.SilkS")
			(hide yes)
			(effects
				(font
					(size 1.27 1.27)
				)
			)
		)
		(property "Value" "SCD1U16V2KX-3GP"
			(at 1.1811 -2.7051 270)
			(unlocked yes)
			(layer "F.Fab")
			(hide yes)
			(effects
				(font
					(size 1.016 1.016)
					(thickness 0.1524)
				)
			)
		)
		(property "Device Type" "C402H22"
			(at 1.1811 -4.2291 270)
			(unlocked yes)
			(layer "F.Fab")
			(hide yes)
			(effects
				(font
					(size 1.016 1.016)
					(thickness 0.1524)
				)
			)
		)
		(duplicate_pad_numbers_are_jumpers no)
		(fp_rect
			(start -0.4318 0.9525)
			(end 0.4318 -0.9525)
			(stroke
				(width 0)
				(type default)
			)
			(fill no)
			(layer "F.CrtYd")
		)
		(fp_rect
			(start -0.4318 0.9525)
			(end 0.4318 -0.9525)
			(stroke
				(width 0)
				(type default)
			)
			(fill no)
			(layer "F.Fab")
		)
		(pad "1" smd custom
			(at 0 -0.4445 270)
			(size 0.1524 0.1524)
			(layers "F.Cu" "F.Mask" "F.Paste")
			(net "P1V8_C_SENSE")
			(options
				(clearance outline)
				(anchor circle)
			)
			(primitives
				(gr_poly
					(pts
						(arc
							(start 0.3048 -0.2032)
							(mid 0.275042 -0.275042)
							(end 0.2032 -0.3048)
						)
						(arc
							(start -0.2032 -0.3048)
							(mid -0.275042 -0.275042)
							(end -0.3048 -0.2032)
						)
						(arc
							(start -0.3048 0.2032)
							(mid -0.275042 0.275042)
							(end -0.2032 0.3048)
						)
						(arc
							(start 0.2032 0.3048)
							(mid 0.275042 0.275042)
							(end 0.3048 0.2032)
						)
					)
					(width 0)
					(fill yes)
				)
			)
		)
		(pad "2" smd custom
			(at 0 0.4445 270)
			(size 0.1524 0.1524)
			(layers "F.Cu" "F.Mask" "F.Paste")
			(net "GND")
			(options
				(clearance outline)
				(anchor circle)
			)
			(primitives
				(gr_poly
					(pts
						(arc
							(start 0.3048 -0.2032)
							(mid 0.275042 -0.275042)
							(end 0.2032 -0.3048)
						)
						(arc
							(start -0.2032 -0.3048)
							(mid -0.275042 -0.275042)
							(end -0.3048 -0.2032)
						)
						(arc
							(start -0.3048 0.2032)
							(mid -0.275042 0.275042)
							(end -0.2032 0.3048)
						)
						(arc
							(start 0.2032 0.3048)
							(mid 0.275042 0.275042)
							(end 0.3048 0.2032)
						)
					)
					(width 0)
					(fill yes)
				)
			)
		)
	)
	(footprint ""
		(layer "F.Cu")
		(at 185.138822 -84.046568 90)
		(property "Reference" "TC7"
			(at 0 0 90)
			(layer "F.SilkS")
			(hide yes)
			(effects
				(font
					(size 1.27 1.27)
				)
			)
		)
		(property "Value" "SE470UF2VDM-GP"
			(at 0 -9.6012 90)
			(unlocked yes)
			(layer "F.Fab")
			(hide yes)
			(effects
				(font
					(size 1.016 1.016)
					(thickness 0.1524)
				)
			)
		)
		(property "Device Type" "CT7343H83"
			(at 0 -11.1252 90)
			(unlocked yes)
			(layer "F.Fab")
			(hide yes)
			(effects
				(font
					(size 1.016 1.016)
					(thickness 0.1524)
				)
			)
		)
		(duplicate_pad_numbers_are_jumpers no)
		(fp_line
			(start 2.286 -4.8768)
			(end -2.286 -4.8768)
			(stroke
				(width 0.1524)
				(type default)
			)
			(layer "F.SilkS")
		)
		(fp_line
			(start -2.286 -4.8768)
			(end -2.286 -2.032)
			(stroke
				(width 0.1524)
				(type default)
			)
			(layer "F.SilkS")
		)
		(fp_line
			(start 2.1082 -4.699)
			(end -2.1082 -4.699)
			(stroke
				(width 0.508)
				(type default)
			)
			(layer "F.SilkS")
		)
		(fp_line
			(start 2.286 -2.032)
			(end 2.286 -4.8768)
			(stroke
				(width 0.1524)
				(type default)
			)
			(layer "F.SilkS")
		)
		(fp_line
			(start 2.286 2.032)
			(end 2.286 4.8768)
			(stroke
				(width 0.1524)
				(type default)
			)
			(layer "F.SilkS")
		)
		(fp_line
			(start 2.286 4.8768)
			(end -2.286 4.8768)
			(stroke
				(width 0.1524)
				(type default)
			)
			(layer "F.SilkS")
		)
		(fp_line
			(start -2.286 4.8768)
			(end -2.286 2.032)
			(stroke
				(width 0.1524)
				(type default)
			)
			(layer "F.SilkS")
		)
		(fp_rect
			(start -2.1463 3.6449)
			(end 2.1463 -3.6449)
			(stroke
				(width 0)
				(type default)
			)
			(fill no)
			(layer "F.CrtYd")
		)
		(fp_poly
			(pts
				(xy -2.54 4.953) (xy -2.54 4.2926) (xy -3.81 4.2926) (xy -3.81 -4.2926) (xy -2.54 -4.2926) (xy -2.54 -4.953)
				(xy 2.54 -4.953) (xy 2.54 -4.2926) (xy 3.81 -4.2926) (xy 3.81 -1.6256) (xy 2.1463 -1.6256) (xy 2.1463 -3.6449)
				(xy -2.1463 -3.6449) (xy -2.1463 3.6449) (xy 2.1463 3.6449) (xy 2.1463 -1.6129) (xy 3.81 -1.6129)
				(xy 3.81 4.2926) (xy 2.54 4.2926) (xy 2.54 4.953)
			)
			(stroke
				(width 0)
				(type default)
			)
			(fill no)
			(layer "F.CrtYd")
		)
		(fp_rect
			(start 2.54 4.2926)
			(end 3.81 -4.2926)
			(stroke
				(width 0)
				(type default)
			)
			(fill no)
			(layer "F.Fab")
		)
		(fp_rect
			(start -3.81 4.2926)
			(end -2.54 -4.2926)
			(stroke
				(width 0)
				(type default)
			)
			(fill no)
			(layer "F.Fab")
		)
		(fp_rect
			(start -2.54 4.953)
			(end 2.54 -4.953)
			(stroke
				(width 0)
				(type default)
			)
			(fill no)
			(layer "F.Fab")
		)
		(pad "1" smd rect
			(at 0 -3.1496 90)
			(size 2.413 2.286)
			(layers "F.Cu" "F.Mask" "F.Paste")
			(net "P0V975")
		)
		(pad "2" smd rect
			(at 0 3.1496 90)
			(size 2.413 2.286)
			(layers "F.Cu" "F.Mask" "F.Paste")
			(net "GND")
		)
		(zone
			(layer "F.Cu")
			(hatch none 0.5)
			(connect_pads
				(clearance 0)
			)
			(min_thickness 0.25)
			(keepout
				(tracks allowed)
				(vias not_allowed)
				(pads allowed)
				(copperpour not_allowed)
				(footprints allowed)
			)
			(placement
				(enabled no)
				(sheetname "")
			)
			(fill
				(thermal_gap 0.5)
				(thermal_bridge_width 0.5)
				(island_removal_mode 0)
			)
			(polygon
				(pts
					(xy 183.449722 -85.557868) (xy 180.541422 -85.557868) (xy 180.541422 -82.535268) (xy 183.437022 -82.535268)
					(xy 183.767222 -82.535268) (xy 183.767222 -85.557868)
				)
			)
		)
		(zone
			(layer "F.Cu")
			(hatch none 0.5)
			(connect_pads
				(clearance 0)
			)
			(min_thickness 0.25)
			(keepout
				(tracks allowed)
				(vias not_allowed)
				(pads allowed)
				(copperpour not_allowed)
				(footprints allowed)
			)
			(placement
				(enabled no)
				(sheetname "")
			)
			(fill
				(thermal_gap 0.5)
				(thermal_bridge_width 0.5)
				(island_removal_mode 0)
			)
			(polygon
				(pts
					(xy 189.736222 -82.535268) (xy 189.736222 -85.557868) (xy 186.840622 -85.557868) (xy 186.510422 -85.557868)
					(xy 186.510422 -82.535268) (xy 186.840622 -82.535268)
				)
			)
		)
	)
	(footprint ""
		(layer "F.Cu")
		(at 16.146018 -61.552582 -90)
		(property "Reference" "R691"
			(at 0 0 270)
			(layer "F.SilkS")
			(hide yes)
			(effects
				(font
					(size 1.27 1.27)
				)
			)
		)
		(property "Value" "0R2J-2-GP"
			(at 0.064008 -3.993896 270)
			(unlocked yes)
			(layer "F.Fab")
			(hide yes)
			(effects
				(font
					(size 1.016 1.016)
					(thickness 0.1524)
				)
			)
		)
		(property "Device Type" "R402H16"
			(at 0.064008 -5.517896 270)
			(unlocked yes)
			(layer "F.Fab")
			(hide yes)
			(effects
				(font
					(size 1.016 1.016)
					(thickness 0.1524)
				)
			)
		)
		(duplicate_pad_numbers_are_jumpers no)
		(fp_line
			(start -0.508 -0.9398)
			(end -0.508 0.9398)
			(stroke
				(width 0.1524)
				(type default)
			)
			(layer "F.SilkS")
		)
		(fp_line
			(start 0.508 -0.9398)
			(end -0.508 -0.9398)
			(stroke
				(width 0.1524)
				(type default)
			)
			(layer "F.SilkS")
		)
		(fp_rect
			(start -0.508 0.9398)
			(end 0.508 -0.9398)
			(stroke
				(width 0)
				(type default)
			)
			(fill no)
			(layer "F.CrtYd")
		)
		(fp_rect
			(start -0.508 0.9398)
			(end 0.508 -0.9398)
			(stroke
				(width 0)
				(type default)
			)
			(fill no)
			(layer "F.Fab")
		)
		(pad "1" smd custom
			(at 0 -0.4445 270)
			(size 0.1397 0.1397)
			(layers "F.Cu" "F.Mask" "F.Paste")
			(net "SCC_STBY_PWR_BUF_EN")
			(options
				(clearance outline)
				(anchor circle)
			)
			(primitives
				(gr_poly
					(pts
						(arc
							(start -0.1778 -0.2794)
							(mid -0.249642 -0.249642)
							(end -0.2794 -0.1778)
						)
						(arc
							(start -0.2794 0.1778)
							(mid -0.249642 0.249642)
							(end -0.1778 0.2794)
						)
						(arc
							(start 0.1778 0.2794)
							(mid 0.249642 0.249642)
							(end 0.2794 0.1778)
						)
						(arc
							(start 0.2794 -0.1778)
							(mid 0.249642 -0.249642)
							(end 0.1778 -0.2794)
						)
					)
					(width 0)
					(fill yes)
				)
			)
		)
		(pad "2" smd custom
			(at 0 0.4445 270)
			(size 0.1397 0.1397)
			(layers "F.Cu" "F.Mask" "F.Paste")
			(net "MB0_HS_ENABLE")
			(options
				(clearance outline)
				(anchor circle)
			)
			(primitives
				(gr_poly
					(pts
						(arc
							(start -0.1778 -0.2794)
							(mid -0.249642 -0.249642)
							(end -0.2794 -0.1778)
						)
						(arc
							(start -0.2794 0.1778)
							(mid -0.249642 0.249642)
							(end -0.1778 0.2794)
						)
						(arc
							(start 0.1778 0.2794)
							(mid 0.249642 0.249642)
							(end 0.2794 0.1778)
						)
						(arc
							(start 0.2794 -0.1778)
							(mid 0.249642 -0.249642)
							(end 0.1778 -0.2794)
						)
					)
					(width 0)
					(fill yes)
				)
			)
		)
	)
	(footprint ""
		(layer "F.Cu")
		(at 139.414758 -82.308446 180)
		(property "Reference" "VIA28"
			(at 0 0 180)
			(layer "F.SilkS")
			(hide yes)
			(effects
				(font
					(size 1.27 1.27)
				)
			)
		)
		(property "Value" "100OHM-8L-1D6MM-L18L16-GP"
			(at -3.7211 -4.5085 180)
			(unlocked yes)
			(layer "F.Fab")
			(hide yes)
			(effects
				(font
					(size 1.016 1.016)
					(thickness 0.1524)
				)
			)
		)
		(property "Device Type" "VIA-PCIE-4P-394076"
			(at -3.7211 -6.0325 180)
			(unlocked yes)
			(layer "F.Fab")
			(hide yes)
			(effects
				(font
					(size 1.016 1.016)
					(thickness 0.1524)
				)
			)
		)
		(duplicate_pad_numbers_are_jumpers no)
		(fp_rect
			(start -1.9685 0.381)
			(end 1.9685 -0.381)
			(stroke
				(width 0)
				(type default)
			)
			(fill no)
			(layer "F.CrtYd")
		)
		(fp_rect
			(start -1.9685 0.381)
			(end 1.9685 -0.381)
			(stroke
				(width 0)
				(type default)
			)
			(fill no)
			(layer "F.Fab")
		)
		(pad "1" thru_hole circle
			(at -1.5875 0 180)
			(size 0.508 0.508)
			(drill 0.254)
			(layers "*.Cu" "*.Mask")
			(remove_unused_layers no)
			(net "GND")
			(clearance 0.127)
			(thermal_gap 0.127)
		)
		(pad "2" thru_hole circle
			(at -0.5715 0 180)
			(size 0.508 0.508)
			(drill 0.254)
			(layers "*.Cu" "*.Mask")
			(remove_unused_layers no)
			(net "PHY_EXP_TO_CONN_11_DP")
			(clearance 0.127)
			(thermal_gap 0.127)
		)
		(pad "3" thru_hole circle
			(at 0.5715 0 180)
			(size 0.508 0.508)
			(drill 0.254)
			(layers "*.Cu" "*.Mask")
			(remove_unused_layers no)
			(net "PHY_EXP_TO_CONN_11_DN")
			(clearance 0.127)
			(thermal_gap 0.127)
		)
		(pad "4" thru_hole circle
			(at 1.5875 0 180)
			(size 0.508 0.508)
			(drill 0.254)
			(layers "*.Cu" "*.Mask")
			(remove_unused_layers no)
			(net "GND")
			(clearance 0.127)
			(thermal_gap 0.127)
		)
	)
	(footprint ""
		(layer "F.Cu")
		(at 19.252184 -71.55053 90)
		(property "Reference" "R354"
			(at 0 0 90)
			(layer "F.SilkS")
			(hide yes)
			(effects
				(font
					(size 1.27 1.27)
				)
			)
		)
		(property "Value" "0R2J-2-GP"
			(at 0.064008 -3.993896 90)
			(unlocked yes)
			(layer "F.Fab")
			(hide yes)
			(effects
				(font
					(size 1.016 1.016)
					(thickness 0.1524)
				)
			)
		)
		(property "Device Type" "R402H16"
			(at 0.064008 -5.517896 90)
			(unlocked yes)
			(layer "F.Fab")
			(hide yes)
			(effects
				(font
					(size 1.016 1.016)
					(thickness 0.1524)
				)
			)
		)
		(duplicate_pad_numbers_are_jumpers no)
		(fp_line
			(start 0.508 -0.9398)
			(end -0.508 -0.9398)
			(stroke
				(width 0.1524)
				(type default)
			)
			(layer "F.SilkS")
		)
		(fp_line
			(start -0.508 -0.9398)
			(end -0.508 0.9398)
			(stroke
				(width 0.1524)
				(type default)
			)
			(layer "F.SilkS")
		)
		(fp_rect
			(start -0.508 0.9398)
			(end 0.508 -0.9398)
			(stroke
				(width 0)
				(type default)
			)
			(fill no)
			(layer "F.CrtYd")
		)
		(fp_rect
			(start -0.508 0.9398)
			(end 0.508 -0.9398)
			(stroke
				(width 0)
				(type default)
			)
			(fill no)
			(layer "F.Fab")
		)
		(pad "1" smd custom
			(at 0 -0.4445 90)
			(size 0.1397 0.1397)
			(layers "F.Cu" "F.Mask" "F.Paste")
			(net "EEPROM_SCL")
			(options
				(clearance outline)
				(anchor circle)
			)
			(primitives
				(gr_poly
					(pts
						(arc
							(start -0.1778 -0.2794)
							(mid -0.249642 -0.249642)
							(end -0.2794 -0.1778)
						)
						(arc
							(start -0.2794 0.1778)
							(mid -0.249642 0.249642)
							(end -0.1778 0.2794)
						)
						(arc
							(start 0.1778 0.2794)
							(mid 0.249642 0.249642)
							(end 0.2794 0.1778)
						)
						(arc
							(start 0.2794 -0.1778)
							(mid 0.249642 -0.249642)
							(end 0.1778 -0.2794)
						)
					)
					(width 0)
					(fill yes)
				)
			)
		)
		(pad "2" smd custom
			(at 0 0.4445 90)
			(size 0.1397 0.1397)
			(layers "F.Cu" "F.Mask" "F.Paste")
			(net "I2C_SCC_SCL2")
			(options
				(clearance outline)
				(anchor circle)
			)
			(primitives
				(gr_poly
					(pts
						(arc
							(start -0.1778 -0.2794)
							(mid -0.249642 -0.249642)
							(end -0.2794 -0.1778)
						)
						(arc
							(start -0.2794 0.1778)
							(mid -0.249642 0.249642)
							(end -0.1778 0.2794)
						)
						(arc
							(start 0.1778 0.2794)
							(mid 0.249642 0.249642)
							(end 0.2794 0.1778)
						)
						(arc
							(start 0.2794 -0.1778)
							(mid 0.249642 -0.249642)
							(end 0.1778 -0.2794)
						)
					)
					(width 0)
					(fill yes)
				)
			)
		)
	)
	(footprint ""
		(layer "F.Cu")
		(at 174.34306 -108.34878)
		(property "Reference" "R443"
			(at 0 0 0)
			(layer "F.SilkS")
			(hide yes)
			(effects
				(font
					(size 1.27 1.27)
				)
			)
		)
		(property "Value" "4K7R2F-GP"
			(at 0.064008 -3.993896 0)
			(unlocked yes)
			(layer "F.Fab")
			(hide yes)
			(effects
				(font
					(size 1.016 1.016)
					(thickness 0.1524)
				)
			)
		)
		(property "Device Type" "R402H16"
			(at 0.064008 -5.517896 0)
			(unlocked yes)
			(layer "F.Fab")
			(hide yes)
			(effects
				(font
					(size 1.016 1.016)
					(thickness 0.1524)
				)
			)
		)
		(duplicate_pad_numbers_are_jumpers no)
		(fp_line
			(start -0.508 -0.9398)
			(end -0.508 0.9398)
			(stroke
				(width 0.1524)
				(type default)
			)
			(layer "F.SilkS")
		)
		(fp_line
			(start 0.508 -0.9398)
			(end -0.508 -0.9398)
			(stroke
				(width 0.1524)
				(type default)
			)
			(layer "F.SilkS")
		)
		(fp_rect
			(start -0.508 0.9398)
			(end 0.508 -0.9398)
			(stroke
				(width 0)
				(type default)
			)
			(fill no)
			(layer "F.CrtYd")
		)
		(fp_rect
			(start -0.508 0.9398)
			(end 0.508 -0.9398)
			(stroke
				(width 0)
				(type default)
			)
			(fill no)
			(layer "F.Fab")
		)
		(pad "1" smd custom
			(at 0 -0.4445)
			(size 0.1397 0.1397)
			(layers "F.Cu" "F.Mask" "F.Paste")
			(net "P1V8_C")
			(options
				(clearance outline)
				(anchor circle)
			)
			(primitives
				(gr_poly
					(pts
						(arc
							(start -0.1778 -0.2794)
							(mid -0.249642 -0.249642)
							(end -0.2794 -0.1778)
						)
						(arc
							(start -0.2794 0.1778)
							(mid -0.249642 0.249642)
							(end -0.1778 0.2794)
						)
						(arc
							(start 0.1778 0.2794)
							(mid 0.249642 0.249642)
							(end 0.2794 0.1778)
						)
						(arc
							(start 0.2794 -0.1778)
							(mid 0.249642 -0.249642)
							(end 0.1778 -0.2794)
						)
					)
					(width 0)
					(fill yes)
				)
			)
		)
		(pad "2" smd custom
			(at 0 0.4445)
			(size 0.1397 0.1397)
			(layers "F.Cu" "F.Mask" "F.Paste")
			(net "Q22_D")
			(options
				(clearance outline)
				(anchor circle)
			)
			(primitives
				(gr_poly
					(pts
						(arc
							(start -0.1778 -0.2794)
							(mid -0.249642 -0.249642)
							(end -0.2794 -0.1778)
						)
						(arc
							(start -0.2794 0.1778)
							(mid -0.249642 0.249642)
							(end -0.1778 0.2794)
						)
						(arc
							(start 0.1778 0.2794)
							(mid 0.249642 0.249642)
							(end 0.2794 0.1778)
						)
						(arc
							(start 0.2794 -0.1778)
							(mid 0.249642 -0.249642)
							(end 0.1778 -0.2794)
						)
					)
					(width 0)
					(fill yes)
				)
			)
		)
	)
	(footprint ""
		(layer "F.Cu")
		(at 145.149824 -112.148874 -90)
		(property "Reference" "L29"
			(at 0 0 270)
			(layer "F.SilkS")
			(hide yes)
			(effects
				(font
					(size 1.27 1.27)
				)
			)
		)
		(property "Value" "IND-2D2UH-179-GP"
			(at -4.699 -4.0132 270)
			(unlocked yes)
			(layer "F.Fab")
			(hide yes)
			(effects
				(font
					(size 1.016 1.016)
					(thickness 0.1524)
				)
			)
		)
		(property "Device Type" "L7066-1830-UH119"
			(at -4.699 -5.5372 270)
			(unlocked yes)
			(layer "F.Fab")
			(hide yes)
			(effects
				(font
					(size 1.016 1.016)
					(thickness 0.1524)
				)
			)
		)
		(duplicate_pad_numbers_are_jumpers no)
		(fp_line
			(start -3.556 4.4958)
			(end -3.556 -4.4958)
			(stroke
				(width 0.1524)
				(type default)
			)
			(layer "F.SilkS")
		)
		(fp_line
			(start 3.556 4.4958)
			(end -3.556 4.4958)
			(stroke
				(width 0.1524)
				(type default)
			)
			(layer "F.SilkS")
		)
		(fp_line
			(start -3.556 -4.4958)
			(end 3.556 -4.4958)
			(stroke
				(width 0.1524)
				(type default)
			)
			(layer "F.SilkS")
		)
		(fp_line
			(start 3.556 -4.4958)
			(end 3.556 4.4958)
			(stroke
				(width 0.1524)
				(type default)
			)
			(layer "F.SilkS")
		)
		(fp_rect
			(start -3.302 3.4798)
			(end 3.302 -3.4798)
			(stroke
				(width 0)
				(type default)
			)
			(fill no)
			(layer "F.CrtYd")
		)
		(fp_poly
			(pts
				(xy -3.81 4.572) (xy -3.81 -4.572) (xy 3.81 -4.572) (xy 3.81 -0.5588) (xy 3.302 -0.5588) (xy 3.302 -3.4798)
				(xy -3.302 -3.4798) (xy -3.302 3.4798) (xy 3.302 3.4798) (xy 3.302 -0.5461) (xy 3.81 -0.5461) (xy 3.81 4.572)
			)
			(stroke
				(width 0)
				(type default)
			)
			(fill no)
			(layer "F.CrtYd")
		)
		(fp_rect
			(start -3.81 4.572)
			(end 3.81 -4.572)
			(stroke
				(width 0)
				(type default)
			)
			(fill no)
			(layer "F.Fab")
		)
		(pad "1" smd rect
			(at 0 -2.779522 270)
			(size 3.5052 2.921)
			(layers "F.Cu" "F.Mask" "F.Paste")
			(net "P1V5_E_LL")
		)
		(pad "2" smd rect
			(at 0 2.779522 270)
			(size 3.5052 2.921)
			(layers "F.Cu" "F.Mask" "F.Paste")
			(net "P1V5_E_OUT")
		)
	)
	(footprint ""
		(layer "F.Cu")
		(at 189.2808 -24.003 -90)
		(property "Reference" "R258"
			(at 0 0 270)
			(layer "F.SilkS")
			(hide yes)
			(effects
				(font
					(size 1.27 1.27)
				)
			)
		)
		(property "Value" "4K7R2F-GP"
			(at 0.064008 -3.993896 270)
			(unlocked yes)
			(layer "F.Fab")
			(hide yes)
			(effects
				(font
					(size 1.016 1.016)
					(thickness 0.1524)
				)
			)
		)
		(property "Device Type" "R402H16"
			(at 0.064008 -5.517896 270)
			(unlocked yes)
			(layer "F.Fab")
			(hide yes)
			(effects
				(font
					(size 1.016 1.016)
					(thickness 0.1524)
				)
			)
		)
		(duplicate_pad_numbers_are_jumpers no)
		(fp_line
			(start -0.508 -0.9398)
			(end -0.508 0.9398)
			(stroke
				(width 0.1524)
				(type default)
			)
			(layer "F.SilkS")
		)
		(fp_line
			(start 0.508 -0.9398)
			(end -0.508 -0.9398)
			(stroke
				(width 0.1524)
				(type default)
			)
			(layer "F.SilkS")
		)
		(fp_rect
			(start -0.508 0.9398)
			(end 0.508 -0.9398)
			(stroke
				(width 0)
				(type default)
			)
			(fill no)
			(layer "F.CrtYd")
		)
		(fp_rect
			(start -0.508 0.9398)
			(end 0.508 -0.9398)
			(stroke
				(width 0)
				(type default)
			)
			(fill no)
			(layer "F.Fab")
		)
		(pad "1" smd custom
			(at 0 -0.4445 270)
			(size 0.1397 0.1397)
			(layers "F.Cu" "F.Mask" "F.Paste")
			(net "P1V8_C")
			(options
				(clearance outline)
				(anchor circle)
			)
			(primitives
				(gr_poly
					(pts
						(arc
							(start -0.1778 -0.2794)
							(mid -0.249642 -0.249642)
							(end -0.2794 -0.1778)
						)
						(arc
							(start -0.2794 0.1778)
							(mid -0.249642 0.249642)
							(end -0.1778 0.2794)
						)
						(arc
							(start 0.1778 0.2794)
							(mid 0.249642 0.249642)
							(end 0.2794 0.1778)
						)
						(arc
							(start 0.2794 -0.1778)
							(mid 0.249642 -0.249642)
							(end 0.1778 -0.2794)
						)
					)
					(width 0)
					(fill yes)
				)
			)
		)
		(pad "2" smd custom
			(at 0 0.4445 270)
			(size 0.1397 0.1397)
			(layers "F.Cu" "F.Mask" "F.Paste")
			(net "SYS_HALT0#")
			(options
				(clearance outline)
				(anchor circle)
			)
			(primitives
				(gr_poly
					(pts
						(arc
							(start -0.1778 -0.2794)
							(mid -0.249642 -0.249642)
							(end -0.2794 -0.1778)
						)
						(arc
							(start -0.2794 0.1778)
							(mid -0.249642 0.249642)
							(end -0.1778 0.2794)
						)
						(arc
							(start 0.1778 0.2794)
							(mid 0.249642 0.249642)
							(end 0.2794 0.1778)
						)
						(arc
							(start 0.2794 -0.1778)
							(mid 0.249642 -0.249642)
							(end 0.1778 -0.2794)
						)
					)
					(width 0)
					(fill yes)
				)
			)
		)
	)
	(footprint ""
		(layer "F.Cu")
		(at 47.573692 -36.92652 90)
		(property "Reference" "C616"
			(at 0 0 90)
			(layer "F.SilkS")
			(hide yes)
			(effects
				(font
					(size 1.27 1.27)
				)
			)
		)
		(property "Value" "SC4D7U25V5KX-1-GP"
			(at -0.0762 -6.1214 90)
			(unlocked yes)
			(layer "F.Fab")
			(hide yes)
			(effects
				(font
					(size 1.016 1.016)
					(thickness 0.1524)
				)
			)
		)
		(property "Device Type" "C805H58"
			(at -0.0762 -8.1534 90)
			(unlocked yes)
			(layer "F.Fab")
			(hide yes)
			(effects
				(font
					(size 1.016 1.016)
					(thickness 0.1524)
				)
			)
		)
		(duplicate_pad_numbers_are_jumpers no)
		(fp_line
			(start 0.635 0)
			(end -0.635 0)
			(stroke
				(width 0.508)
				(type default)
			)
			(layer "F.SilkS")
		)
		(fp_rect
			(start -0.9652 1.778)
			(end 0.9652 -1.778)
			(stroke
				(width 0)
				(type default)
			)
			(fill no)
			(layer "F.CrtYd")
		)
		(fp_poly
			(pts
				(xy -0.9652 -1.778) (xy 0.9652 -1.778) (xy 0.9652 1.778) (xy -0.9652 1.778)
			)
			(stroke
				(width 0)
				(type default)
			)
			(fill no)
			(layer "F.Fab")
		)
		(pad "1" smd rect
			(at 0 -0.9652 90)
			(size 1.397 1.143)
			(layers "F.Cu" "F.Mask" "F.Paste")
			(net "P0V9_V5")
		)
		(pad "2" smd rect
			(at 0 0.9652 90)
			(size 1.397 1.143)
			(layers "F.Cu" "F.Mask" "F.Paste")
			(net "GND")
		)
	)
	(footprint ""
		(layer "F.Cu")
		(at 9.525 -97.9678)
		(property "Reference" "R585"
			(at 0 0 0)
			(layer "F.SilkS")
			(hide yes)
			(effects
				(font
					(size 1.27 1.27)
				)
			)
		)
		(property "Value" "0R2J-2-GP"
			(at 0.064008 -3.993896 0)
			(unlocked yes)
			(layer "F.Fab")
			(hide yes)
			(effects
				(font
					(size 1.016 1.016)
					(thickness 0.1524)
				)
			)
		)
		(property "Device Type" "R402H16"
			(at 0.064008 -5.517896 0)
			(unlocked yes)
			(layer "F.Fab")
			(hide yes)
			(effects
				(font
					(size 1.016 1.016)
					(thickness 0.1524)
				)
			)
		)
		(duplicate_pad_numbers_are_jumpers no)
		(fp_line
			(start -0.508 -0.9398)
			(end -0.508 0.9398)
			(stroke
				(width 0.1524)
				(type default)
			)
			(layer "F.SilkS")
		)
		(fp_line
			(start 0.508 -0.9398)
			(end -0.508 -0.9398)
			(stroke
				(width 0.1524)
				(type default)
			)
			(layer "F.SilkS")
		)
		(fp_rect
			(start -0.508 0.9398)
			(end 0.508 -0.9398)
			(stroke
				(width 0)
				(type default)
			)
			(fill no)
			(layer "F.CrtYd")
		)
		(fp_rect
			(start -0.508 0.9398)
			(end 0.508 -0.9398)
			(stroke
				(width 0)
				(type default)
			)
			(fill no)
			(layer "F.Fab")
		)
		(pad "1" smd custom
			(at 0 -0.4445)
			(size 0.1397 0.1397)
			(layers "F.Cu" "F.Mask" "F.Paste")
			(net "SCC_FULL_PGOOD")
			(options
				(clearance outline)
				(anchor circle)
			)
			(primitives
				(gr_poly
					(pts
						(arc
							(start -0.1778 -0.2794)
							(mid -0.249642 -0.249642)
							(end -0.2794 -0.1778)
						)
						(arc
							(start -0.2794 0.1778)
							(mid -0.249642 0.249642)
							(end -0.1778 0.2794)
						)
						(arc
							(start 0.1778 0.2794)
							(mid 0.249642 0.249642)
							(end 0.2794 0.1778)
						)
						(arc
							(start 0.2794 -0.1778)
							(mid 0.249642 -0.249642)
							(end 0.1778 -0.2794)
						)
					)
					(width 0)
					(fill yes)
				)
			)
		)
		(pad "2" smd custom
			(at 0 0.4445)
			(size 0.1397 0.1397)
			(layers "F.Cu" "F.Mask" "F.Paste")
			(net "U120_EN")
			(options
				(clearance outline)
				(anchor circle)
			)
			(primitives
				(gr_poly
					(pts
						(arc
							(start -0.1778 -0.2794)
							(mid -0.249642 -0.249642)
							(end -0.2794 -0.1778)
						)
						(arc
							(start -0.2794 0.1778)
							(mid -0.249642 0.249642)
							(end -0.1778 0.2794)
						)
						(arc
							(start 0.1778 0.2794)
							(mid 0.249642 0.249642)
							(end 0.2794 0.1778)
						)
						(arc
							(start 0.2794 -0.1778)
							(mid 0.249642 -0.249642)
							(end 0.1778 -0.2794)
						)
					)
					(width 0)
					(fill yes)
				)
			)
		)
	)
	(footprint ""
		(layer "F.Cu")
		(at 23.1902 -57.2516)
		(property "Reference" "R19"
			(at 0 0 0)
			(layer "F.SilkS")
			(hide yes)
			(effects
				(font
					(size 1.27 1.27)
				)
			)
		)
		(property "Value" "100KR2J-4-GP"
			(at 0.064008 -3.993896 0)
			(unlocked yes)
			(layer "F.Fab")
			(hide yes)
			(effects
				(font
					(size 1.016 1.016)
					(thickness 0.1524)
				)
			)
		)
		(property "Device Type" "R402H15"
			(at 0.064008 -5.517896 0)
			(unlocked yes)
			(layer "F.Fab")
			(hide yes)
			(effects
				(font
					(size 1.016 1.016)
					(thickness 0.1524)
				)
			)
		)
		(duplicate_pad_numbers_are_jumpers no)
		(fp_line
			(start -0.508 -0.9398)
			(end -0.508 0.9398)
			(stroke
				(width 0.1524)
				(type default)
			)
			(layer "F.SilkS")
		)
		(fp_line
			(start 0.508 -0.9398)
			(end -0.508 -0.9398)
			(stroke
				(width 0.1524)
				(type default)
			)
			(layer "F.SilkS")
		)
		(fp_rect
			(start -0.508 0.9398)
			(end 0.508 -0.9398)
			(stroke
				(width 0)
				(type default)
			)
			(fill no)
			(layer "F.CrtYd")
		)
		(fp_rect
			(start -0.508 0.9398)
			(end 0.508 -0.9398)
			(stroke
				(width 0)
				(type default)
			)
			(fill no)
			(layer "F.Fab")
		)
		(pad "1" smd custom
			(at 0 -0.4445)
			(size 0.1397 0.1397)
			(layers "F.Cu" "F.Mask" "F.Paste")
			(net "MB0_VCAP_R")
			(options
				(clearance outline)
				(anchor circle)
			)
			(primitives
				(gr_poly
					(pts
						(arc
							(start -0.1778 -0.2794)
							(mid -0.249642 -0.249642)
							(end -0.2794 -0.1778)
						)
						(arc
							(start -0.2794 0.1778)
							(mid -0.249642 0.249642)
							(end -0.1778 0.2794)
						)
						(arc
							(start 0.1778 0.2794)
							(mid 0.249642 0.249642)
							(end 0.2794 0.1778)
						)
						(arc
							(start 0.2794 -0.1778)
							(mid 0.249642 -0.249642)
							(end 0.1778 -0.2794)
						)
					)
					(width 0)
					(fill yes)
				)
			)
		)
		(pad "2" smd custom
			(at 0 0.4445)
			(size 0.1397 0.1397)
			(layers "F.Cu" "F.Mask" "F.Paste")
			(net "MB0_ISTART_R")
			(options
				(clearance outline)
				(anchor circle)
			)
			(primitives
				(gr_poly
					(pts
						(arc
							(start -0.1778 -0.2794)
							(mid -0.249642 -0.249642)
							(end -0.2794 -0.1778)
						)
						(arc
							(start -0.2794 0.1778)
							(mid -0.249642 0.249642)
							(end -0.1778 0.2794)
						)
						(arc
							(start 0.1778 0.2794)
							(mid 0.249642 0.249642)
							(end 0.2794 0.1778)
						)
						(arc
							(start 0.2794 -0.1778)
							(mid 0.249642 -0.249642)
							(end 0.1778 -0.2794)
						)
					)
					(width 0)
					(fill yes)
				)
			)
		)
	)
	(footprint ""
		(layer "F.Cu")
		(at 94.518226 -65.93332)
		(property "Reference" "R556"
			(at 0 0 0)
			(layer "F.SilkS")
			(hide yes)
			(effects
				(font
					(size 1.27 1.27)
				)
			)
		)
		(property "Value" "0R2J-2-GP"
			(at 0.064008 -3.993896 0)
			(unlocked yes)
			(layer "F.Fab")
			(hide yes)
			(effects
				(font
					(size 1.016 1.016)
					(thickness 0.1524)
				)
			)
		)
		(property "Device Type" "R402H16"
			(at 0.064008 -5.517896 0)
			(unlocked yes)
			(layer "F.Fab")
			(hide yes)
			(effects
				(font
					(size 1.016 1.016)
					(thickness 0.1524)
				)
			)
		)
		(duplicate_pad_numbers_are_jumpers no)
		(fp_line
			(start -0.508 -0.9398)
			(end -0.508 0.9398)
			(stroke
				(width 0.1524)
				(type default)
			)
			(layer "F.SilkS")
		)
		(fp_line
			(start 0.508 -0.9398)
			(end -0.508 -0.9398)
			(stroke
				(width 0.1524)
				(type default)
			)
			(layer "F.SilkS")
		)
		(fp_rect
			(start -0.508 0.9398)
			(end 0.508 -0.9398)
			(stroke
				(width 0)
				(type default)
			)
			(fill no)
			(layer "F.CrtYd")
		)
		(fp_rect
			(start -0.508 0.9398)
			(end 0.508 -0.9398)
			(stroke
				(width 0)
				(type default)
			)
			(fill no)
			(layer "F.Fab")
		)
		(pad "1" smd custom
			(at 0 -0.4445)
			(size 0.1397 0.1397)
			(layers "F.Cu" "F.Mask" "F.Paste")
			(net "GND")
			(options
				(clearance outline)
				(anchor circle)
			)
			(primitives
				(gr_poly
					(pts
						(arc
							(start -0.1778 -0.2794)
							(mid -0.249642 -0.249642)
							(end -0.2794 -0.1778)
						)
						(arc
							(start -0.2794 0.1778)
							(mid -0.249642 0.249642)
							(end -0.1778 0.2794)
						)
						(arc
							(start 0.1778 0.2794)
							(mid 0.249642 0.249642)
							(end 0.2794 0.1778)
						)
						(arc
							(start 0.2794 -0.1778)
							(mid 0.249642 -0.249642)
							(end 0.1778 -0.2794)
						)
					)
					(width 0)
					(fill yes)
				)
			)
		)
		(pad "2" smd custom
			(at 0 0.4445)
			(size 0.1397 0.1397)
			(layers "F.Cu" "F.Mask" "F.Paste")
			(net "LED47")
			(options
				(clearance outline)
				(anchor circle)
			)
			(primitives
				(gr_poly
					(pts
						(arc
							(start -0.1778 -0.2794)
							(mid -0.249642 -0.249642)
							(end -0.2794 -0.1778)
						)
						(arc
							(start -0.2794 0.1778)
							(mid -0.249642 0.249642)
							(end -0.1778 0.2794)
						)
						(arc
							(start 0.1778 0.2794)
							(mid 0.249642 0.249642)
							(end 0.2794 0.1778)
						)
						(arc
							(start 0.2794 -0.1778)
							(mid 0.249642 -0.249642)
							(end 0.1778 -0.2794)
						)
					)
					(width 0)
					(fill yes)
				)
			)
		)
	)
	(footprint ""
		(layer "F.Cu")
		(at 94.234 -69.977 -90)
		(property "Reference" "R108"
			(at 0 0 270)
			(layer "F.SilkS")
			(hide yes)
			(effects
				(font
					(size 1.27 1.27)
				)
			)
		)
		(property "Value" "4K75R2F-1-GP"
			(at 0.064008 -3.993896 270)
			(unlocked yes)
			(layer "F.Fab")
			(hide yes)
			(effects
				(font
					(size 1.016 1.016)
					(thickness 0.1524)
				)
			)
		)
		(property "Device Type" "R402H16"
			(at 0.064008 -5.517896 270)
			(unlocked yes)
			(layer "F.Fab")
			(hide yes)
			(effects
				(font
					(size 1.016 1.016)
					(thickness 0.1524)
				)
			)
		)
		(duplicate_pad_numbers_are_jumpers no)
		(fp_line
			(start -0.508 -0.9398)
			(end -0.508 0.9398)
			(stroke
				(width 0.1524)
				(type default)
			)
			(layer "F.SilkS")
		)
		(fp_line
			(start 0.508 -0.9398)
			(end -0.508 -0.9398)
			(stroke
				(width 0.1524)
				(type default)
			)
			(layer "F.SilkS")
		)
		(fp_rect
			(start -0.508 0.9398)
			(end 0.508 -0.9398)
			(stroke
				(width 0)
				(type default)
			)
			(fill no)
			(layer "F.CrtYd")
		)
		(fp_rect
			(start -0.508 0.9398)
			(end 0.508 -0.9398)
			(stroke
				(width 0)
				(type default)
			)
			(fill no)
			(layer "F.Fab")
		)
		(pad "1" smd custom
			(at 0 -0.4445 270)
			(size 0.1397 0.1397)
			(layers "F.Cu" "F.Mask" "F.Paste")
			(net "LSI_SCAN_ENABLE")
			(options
				(clearance outline)
				(anchor circle)
			)
			(primitives
				(gr_poly
					(pts
						(arc
							(start -0.1778 -0.2794)
							(mid -0.249642 -0.249642)
							(end -0.2794 -0.1778)
						)
						(arc
							(start -0.2794 0.1778)
							(mid -0.249642 0.249642)
							(end -0.1778 0.2794)
						)
						(arc
							(start 0.1778 0.2794)
							(mid 0.249642 0.249642)
							(end 0.2794 0.1778)
						)
						(arc
							(start 0.2794 -0.1778)
							(mid 0.249642 -0.249642)
							(end 0.1778 -0.2794)
						)
					)
					(width 0)
					(fill yes)
				)
			)
		)
		(pad "2" smd custom
			(at 0 0.4445 270)
			(size 0.1397 0.1397)
			(layers "F.Cu" "F.Mask" "F.Paste")
			(net "GND")
			(options
				(clearance outline)
				(anchor circle)
			)
			(primitives
				(gr_poly
					(pts
						(arc
							(start -0.1778 -0.2794)
							(mid -0.249642 -0.249642)
							(end -0.2794 -0.1778)
						)
						(arc
							(start -0.2794 0.1778)
							(mid -0.249642 0.249642)
							(end -0.1778 0.2794)
						)
						(arc
							(start 0.1778 0.2794)
							(mid 0.249642 0.249642)
							(end 0.2794 0.1778)
						)
						(arc
							(start 0.2794 -0.1778)
							(mid 0.249642 -0.249642)
							(end 0.1778 -0.2794)
						)
					)
					(width 0)
					(fill yes)
				)
			)
		)
	)
	(footprint ""
		(layer "F.Cu")
		(at 191.846708 -44.12361 -90)
		(property "Reference" "R237"
			(at 0 0 270)
			(layer "F.SilkS")
			(hide yes)
			(effects
				(font
					(size 1.27 1.27)
				)
			)
		)
		(property "Value" "10KR2F-2-GP"
			(at 0.064008 -3.993896 270)
			(unlocked yes)
			(layer "F.Fab")
			(hide yes)
			(effects
				(font
					(size 1.016 1.016)
					(thickness 0.1524)
				)
			)
		)
		(property "Device Type" "R402H16"
			(at 0.064008 -5.517896 270)
			(unlocked yes)
			(layer "F.Fab")
			(hide yes)
			(effects
				(font
					(size 1.016 1.016)
					(thickness 0.1524)
				)
			)
		)
		(duplicate_pad_numbers_are_jumpers no)
		(fp_line
			(start -0.508 -0.9398)
			(end -0.508 0.9398)
			(stroke
				(width 0.1524)
				(type default)
			)
			(layer "F.SilkS")
		)
		(fp_line
			(start 0.508 -0.9398)
			(end -0.508 -0.9398)
			(stroke
				(width 0.1524)
				(type default)
			)
			(layer "F.SilkS")
		)
		(fp_rect
			(start -0.508 0.9398)
			(end 0.508 -0.9398)
			(stroke
				(width 0)
				(type default)
			)
			(fill no)
			(layer "F.CrtYd")
		)
		(fp_rect
			(start -0.508 0.9398)
			(end 0.508 -0.9398)
			(stroke
				(width 0)
				(type default)
			)
			(fill no)
			(layer "F.Fab")
		)
		(pad "1" smd custom
			(at 0 -0.4445 270)
			(size 0.1397 0.1397)
			(layers "F.Cu" "F.Mask" "F.Paste")
			(net "GND")
			(options
				(clearance outline)
				(anchor circle)
			)
			(primitives
				(gr_poly
					(pts
						(arc
							(start -0.1778 -0.2794)
							(mid -0.249642 -0.249642)
							(end -0.2794 -0.1778)
						)
						(arc
							(start -0.2794 0.1778)
							(mid -0.249642 0.249642)
							(end -0.1778 0.2794)
						)
						(arc
							(start 0.1778 0.2794)
							(mid 0.249642 0.249642)
							(end 0.2794 0.1778)
						)
						(arc
							(start 0.2794 -0.1778)
							(mid 0.249642 -0.249642)
							(end 0.1778 -0.2794)
						)
					)
					(width 0)
					(fill yes)
				)
			)
		)
		(pad "2" smd custom
			(at 0 0.4445 270)
			(size 0.1397 0.1397)
			(layers "F.Cu" "F.Mask" "F.Paste")
			(net "MEM_CLK_SEL")
			(options
				(clearance outline)
				(anchor circle)
			)
			(primitives
				(gr_poly
					(pts
						(arc
							(start -0.1778 -0.2794)
							(mid -0.249642 -0.249642)
							(end -0.2794 -0.1778)
						)
						(arc
							(start -0.2794 0.1778)
							(mid -0.249642 0.249642)
							(end -0.1778 0.2794)
						)
						(arc
							(start 0.1778 0.2794)
							(mid 0.249642 0.249642)
							(end 0.2794 0.1778)
						)
						(arc
							(start 0.2794 -0.1778)
							(mid 0.249642 -0.249642)
							(end 0.1778 -0.2794)
						)
					)
					(width 0)
					(fill yes)
				)
			)
		)
	)
	(footprint ""
		(layer "F.Cu")
		(at 60.452 -45.847 90)
		(property "Reference" "L31"
			(at 0 0 90)
			(layer "F.SilkS")
			(hide yes)
			(effects
				(font
					(size 1.27 1.27)
				)
			)
		)
		(property "Value" "IND-180NH-8-GP"
			(at -5.273802 -3.640836 90)
			(unlocked yes)
			(layer "F.Fab")
			(hide yes)
			(effects
				(font
					(size 1.016 1.016)
					(thickness 0.1524)
				)
			)
		)
		(property "Device Type" "L105080-2221H276"
			(at -5.273802 -5.164836 90)
			(unlocked yes)
			(layer "F.Fab")
			(hide yes)
			(effects
				(font
					(size 1.016 1.016)
					(thickness 0.1524)
				)
			)
		)
		(duplicate_pad_numbers_are_jumpers no)
		(fp_line
			(start 4.2545 -5.8928)
			(end -4.2545 -5.8928)
			(stroke
				(width 0.1524)
				(type default)
			)
			(layer "F.SilkS")
		)
		(fp_line
			(start -4.2545 -5.8928)
			(end -4.2545 5.8928)
			(stroke
				(width 0.1524)
				(type default)
			)
			(layer "F.SilkS")
		)
		(fp_line
			(start 4.2545 5.8928)
			(end 4.2545 -5.8928)
			(stroke
				(width 0.1524)
				(type default)
			)
			(layer "F.SilkS")
		)
		(fp_line
			(start -4.2545 5.8928)
			(end 4.2545 5.8928)
			(stroke
				(width 0.1524)
				(type default)
			)
			(layer "F.SilkS")
		)
		(fp_rect
			(start -4.0005 5.2451)
			(end 4.0005 -5.2451)
			(stroke
				(width 0)
				(type default)
			)
			(fill no)
			(layer "F.CrtYd")
		)
		(fp_poly
			(pts
				(xy -4.5085 5.969) (xy -4.5085 -5.969) (xy 4.5085 -5.969) (xy 4.5085 -0.00254) (xy 4.0005 -0.00254)
				(xy 4.0005 -5.2451) (xy -4.0005 -5.2451) (xy -4.0005 5.2451) (xy 4.0005 5.2451) (xy 4.0005 0.00254)
				(xy 4.5085 0.00254) (xy 4.5085 5.969)
			)
			(stroke
				(width 0)
				(type default)
			)
			(fill no)
			(layer "F.CrtYd")
		)
		(fp_rect
			(start -4.5085 5.969)
			(end 4.5085 -5.969)
			(stroke
				(width 0)
				(type default)
			)
			(fill no)
			(layer "F.Fab")
		)
		(pad "1" smd rect
			(at 0 -4.095496 90)
			(size 2.3622 3.0988)
			(layers "F.Cu" "F.Mask" "F.Paste")
			(net "P0V9_VSW")
		)
		(pad "2" smd rect
			(at 0 4.095496 90)
			(size 2.3622 3.0988)
			(layers "F.Cu" "F.Mask" "F.Paste")
			(net "P0V9")
		)
	)
	(footprint ""
		(layer "F.Cu")
		(at 19.2278 -77.343 90)
		(property "Reference" "R351"
			(at 0 0 90)
			(layer "F.SilkS")
			(hide yes)
			(effects
				(font
					(size 1.27 1.27)
				)
			)
		)
		(property "Value" "0R2J-2-GP"
			(at 0.064008 -3.993896 90)
			(unlocked yes)
			(layer "F.Fab")
			(hide yes)
			(effects
				(font
					(size 1.016 1.016)
					(thickness 0.1524)
				)
			)
		)
		(property "Device Type" "R402H16"
			(at 0.064008 -5.517896 90)
			(unlocked yes)
			(layer "F.Fab")
			(hide yes)
			(effects
				(font
					(size 1.016 1.016)
					(thickness 0.1524)
				)
			)
		)
		(duplicate_pad_numbers_are_jumpers no)
		(fp_line
			(start 0.508 -0.9398)
			(end -0.508 -0.9398)
			(stroke
				(width 0.1524)
				(type default)
			)
			(layer "F.SilkS")
		)
		(fp_line
			(start -0.508 -0.9398)
			(end -0.508 0.9398)
			(stroke
				(width 0.1524)
				(type default)
			)
			(layer "F.SilkS")
		)
		(fp_rect
			(start -0.508 0.9398)
			(end 0.508 -0.9398)
			(stroke
				(width 0)
				(type default)
			)
			(fill no)
			(layer "F.CrtYd")
		)
		(fp_rect
			(start -0.508 0.9398)
			(end 0.508 -0.9398)
			(stroke
				(width 0)
				(type default)
			)
			(fill no)
			(layer "F.Fab")
		)
		(pad "1" smd custom
			(at 0 -0.4445 90)
			(size 0.1397 0.1397)
			(layers "F.Cu" "F.Mask" "F.Paste")
			(net "EXP_EEPROM_SDA")
			(options
				(clearance outline)
				(anchor circle)
			)
			(primitives
				(gr_poly
					(pts
						(arc
							(start -0.1778 -0.2794)
							(mid -0.249642 -0.249642)
							(end -0.2794 -0.1778)
						)
						(arc
							(start -0.2794 0.1778)
							(mid -0.249642 0.249642)
							(end -0.1778 0.2794)
						)
						(arc
							(start 0.1778 0.2794)
							(mid 0.249642 0.249642)
							(end 0.2794 0.1778)
						)
						(arc
							(start 0.2794 -0.1778)
							(mid 0.249642 -0.249642)
							(end 0.1778 -0.2794)
						)
					)
					(width 0)
					(fill yes)
				)
			)
		)
		(pad "2" smd custom
			(at 0 0.4445 90)
			(size 0.1397 0.1397)
			(layers "F.Cu" "F.Mask" "F.Paste")
			(net "I2C_SCC_SDA2")
			(options
				(clearance outline)
				(anchor circle)
			)
			(primitives
				(gr_poly
					(pts
						(arc
							(start -0.1778 -0.2794)
							(mid -0.249642 -0.249642)
							(end -0.2794 -0.1778)
						)
						(arc
							(start -0.2794 0.1778)
							(mid -0.249642 0.249642)
							(end -0.1778 0.2794)
						)
						(arc
							(start 0.1778 0.2794)
							(mid 0.249642 0.249642)
							(end 0.2794 0.1778)
						)
						(arc
							(start 0.2794 -0.1778)
							(mid 0.249642 -0.249642)
							(end 0.1778 -0.2794)
						)
					)
					(width 0)
					(fill yes)
				)
			)
		)
	)
	(footprint ""
		(layer "F.Cu")
		(at 175.5394 -59.817)
		(property "Reference" "R247"
			(at 0 0 0)
			(layer "F.SilkS")
			(hide yes)
			(effects
				(font
					(size 1.27 1.27)
				)
			)
		)
		(property "Value" "4K7R2F-GP"
			(at 0.064008 -3.993896 0)
			(unlocked yes)
			(layer "F.Fab")
			(hide yes)
			(effects
				(font
					(size 1.016 1.016)
					(thickness 0.1524)
				)
			)
		)
		(property "Device Type" "R402H16"
			(at 0.064008 -5.517896 0)
			(unlocked yes)
			(layer "F.Fab")
			(hide yes)
			(effects
				(font
					(size 1.016 1.016)
					(thickness 0.1524)
				)
			)
		)
		(duplicate_pad_numbers_are_jumpers no)
		(fp_line
			(start -0.508 -0.9398)
			(end -0.508 0.9398)
			(stroke
				(width 0.1524)
				(type default)
			)
			(layer "F.SilkS")
		)
		(fp_line
			(start 0.508 -0.9398)
			(end -0.508 -0.9398)
			(stroke
				(width 0.1524)
				(type default)
			)
			(layer "F.SilkS")
		)
		(fp_rect
			(start -0.508 0.9398)
			(end 0.508 -0.9398)
			(stroke
				(width 0)
				(type default)
			)
			(fill no)
			(layer "F.CrtYd")
		)
		(fp_rect
			(start -0.508 0.9398)
			(end 0.508 -0.9398)
			(stroke
				(width 0)
				(type default)
			)
			(fill no)
			(layer "F.Fab")
		)
		(pad "1" smd custom
			(at 0 -0.4445)
			(size 0.1397 0.1397)
			(layers "F.Cu" "F.Mask" "F.Paste")
			(net "P1V8_C")
			(options
				(clearance outline)
				(anchor circle)
			)
			(primitives
				(gr_poly
					(pts
						(arc
							(start -0.1778 -0.2794)
							(mid -0.249642 -0.249642)
							(end -0.2794 -0.1778)
						)
						(arc
							(start -0.2794 0.1778)
							(mid -0.249642 0.249642)
							(end -0.1778 0.2794)
						)
						(arc
							(start 0.1778 0.2794)
							(mid 0.249642 0.249642)
							(end 0.2794 0.1778)
						)
						(arc
							(start 0.2794 -0.1778)
							(mid 0.249642 -0.249642)
							(end 0.1778 -0.2794)
						)
					)
					(width 0)
					(fill yes)
				)
			)
		)
		(pad "2" smd custom
			(at 0 0.4445)
			(size 0.1397 0.1397)
			(layers "F.Cu" "F.Mask" "F.Paste")
			(net "LSI_SCAN_EN")
			(options
				(clearance outline)
				(anchor circle)
			)
			(primitives
				(gr_poly
					(pts
						(arc
							(start -0.1778 -0.2794)
							(mid -0.249642 -0.249642)
							(end -0.2794 -0.1778)
						)
						(arc
							(start -0.2794 0.1778)
							(mid -0.249642 0.249642)
							(end -0.1778 0.2794)
						)
						(arc
							(start 0.1778 0.2794)
							(mid 0.249642 0.249642)
							(end 0.2794 0.1778)
						)
						(arc
							(start 0.2794 -0.1778)
							(mid 0.249642 -0.249642)
							(end 0.1778 -0.2794)
						)
					)
					(width 0)
					(fill yes)
				)
			)
		)
	)
	(footprint ""
		(layer "F.Cu")
		(at 124.6632 -111.28248)
		(property "Reference" "TP24"
			(at 0 0 0)
			(layer "F.SilkS")
			(hide yes)
			(effects
				(font
					(size 1.27 1.27)
				)
			)
		)
		(property "Value" "TPAD28-2-GP"
			(at -0.0127 -1.6637 0)
			(unlocked yes)
			(layer "F.Fab")
			(hide yes)
			(effects
				(font
					(size 1.016 1.016)
					(thickness 0.1524)
				)
			)
		)
		(property "Device Type" "TPAD28"
			(at -0.0127 -3.1877 0)
			(unlocked yes)
			(layer "F.Fab")
			(hide yes)
			(effects
				(font
					(size 1.016 1.016)
					(thickness 0.1524)
				)
			)
		)
		(duplicate_pad_numbers_are_jumpers no)
		(fp_poly
			(pts
				(arc
					(start 0.3556 0)
					(mid -0.3556 0)
					(end 0.3556 0)
				)
			)
			(stroke
				(width 0)
				(type default)
			)
			(fill no)
			(layer "F.CrtYd")
		)
		(fp_poly
			(pts
				(arc
					(start 0.6096 0)
					(mid -0.6096 0)
					(end 0.6096 0)
				)
			)
			(stroke
				(width 0)
				(type default)
			)
			(fill no)
			(layer "F.Fab")
		)
		(pad "1" smd circle
			(at 0 0)
			(size 0.7112 0.7112)
			(layers "F.Cu" "F.Mask" "F.Paste")
			(net "INT_B2_CONN1")
		)
	)
	(footprint ""
		(layer "F.Cu")
		(at 165.4556 -88.0618 90)
		(property "Reference" "C643"
			(at 0 0 90)
			(layer "F.SilkS")
			(hide yes)
			(effects
				(font
					(size 1.27 1.27)
				)
			)
		)
		(property "Value" "SC10U16V5KX-7-GP-U"
			(at -0.0762 -6.1214 90)
			(unlocked yes)
			(layer "F.Fab")
			(hide yes)
			(effects
				(font
					(size 1.016 1.016)
					(thickness 0.1524)
				)
			)
		)
		(property "Device Type" "C805H58"
			(at -0.0762 -8.1534 90)
			(unlocked yes)
			(layer "F.Fab")
			(hide yes)
			(effects
				(font
					(size 1.016 1.016)
					(thickness 0.1524)
				)
			)
		)
		(duplicate_pad_numbers_are_jumpers no)
		(fp_line
			(start 0.635 0)
			(end -0.635 0)
			(stroke
				(width 0.508)
				(type default)
			)
			(layer "F.SilkS")
		)
		(fp_rect
			(start -0.9652 1.778)
			(end 0.9652 -1.778)
			(stroke
				(width 0)
				(type default)
			)
			(fill no)
			(layer "F.CrtYd")
		)
		(fp_poly
			(pts
				(xy -0.9652 -1.778) (xy 0.9652 -1.778) (xy 0.9652 1.778) (xy -0.9652 1.778)
			)
			(stroke
				(width 0)
				(type default)
			)
			(fill no)
			(layer "F.Fab")
		)
		(pad "1" smd rect
			(at 0 -0.9652 90)
			(size 1.397 1.143)
			(layers "F.Cu" "F.Mask" "F.Paste")
			(net "P12V_SYBY_VDD_U6")
		)
		(pad "2" smd rect
			(at 0 0.9652 90)
			(size 1.397 1.143)
			(layers "F.Cu" "F.Mask" "F.Paste")
			(net "GND")
		)
	)
	(footprint ""
		(layer "F.Cu")
		(at 15.0114 -99.3267 -90)
		(property "Reference" "C732"
			(at 0 0 270)
			(layer "F.SilkS")
			(hide yes)
			(effects
				(font
					(size 1.27 1.27)
				)
			)
		)
		(property "Value" "SCD1U16V2KX-3GP"
			(at 1.1811 -2.7051 270)
			(unlocked yes)
			(layer "F.Fab")
			(hide yes)
			(effects
				(font
					(size 1.016 1.016)
					(thickness 0.1524)
				)
			)
		)
		(property "Device Type" "C402H22"
			(at 1.1811 -4.2291 270)
			(unlocked yes)
			(layer "F.Fab")
			(hide yes)
			(effects
				(font
					(size 1.016 1.016)
					(thickness 0.1524)
				)
			)
		)
		(duplicate_pad_numbers_are_jumpers no)
		(fp_rect
			(start -0.4318 0.9525)
			(end 0.4318 -0.9525)
			(stroke
				(width 0)
				(type default)
			)
			(fill no)
			(layer "F.CrtYd")
		)
		(fp_rect
			(start -0.4318 0.9525)
			(end 0.4318 -0.9525)
			(stroke
				(width 0)
				(type default)
			)
			(fill no)
			(layer "F.Fab")
		)
		(pad "1" smd custom
			(at 0 -0.4445 270)
			(size 0.1524 0.1524)
			(layers "F.Cu" "F.Mask" "F.Paste")
			(net "P3V3")
			(options
				(clearance outline)
				(anchor circle)
			)
			(primitives
				(gr_poly
					(pts
						(arc
							(start 0.3048 -0.2032)
							(mid 0.275042 -0.275042)
							(end 0.2032 -0.3048)
						)
						(arc
							(start -0.2032 -0.3048)
							(mid -0.275042 -0.275042)
							(end -0.3048 -0.2032)
						)
						(arc
							(start -0.3048 0.2032)
							(mid -0.275042 0.275042)
							(end -0.2032 0.3048)
						)
						(arc
							(start 0.2032 0.3048)
							(mid 0.275042 0.275042)
							(end 0.3048 0.2032)
						)
					)
					(width 0)
					(fill yes)
				)
			)
		)
		(pad "2" smd custom
			(at 0 0.4445 270)
			(size 0.1524 0.1524)
			(layers "F.Cu" "F.Mask" "F.Paste")
			(net "GND")
			(options
				(clearance outline)
				(anchor circle)
			)
			(primitives
				(gr_poly
					(pts
						(arc
							(start 0.3048 -0.2032)
							(mid 0.275042 -0.275042)
							(end 0.2032 -0.3048)
						)
						(arc
							(start -0.2032 -0.3048)
							(mid -0.275042 -0.275042)
							(end -0.3048 -0.2032)
						)
						(arc
							(start -0.3048 0.2032)
							(mid -0.275042 0.275042)
							(end -0.2032 0.3048)
						)
						(arc
							(start 0.2032 0.3048)
							(mid 0.275042 0.275042)
							(end 0.3048 0.2032)
						)
					)
					(width 0)
					(fill yes)
				)
			)
		)
	)
	(footprint ""
		(layer "F.Cu")
		(at 24.96693 -93.622622)
		(property "Reference" "R448"
			(at 0 0 0)
			(layer "F.SilkS")
			(hide yes)
			(effects
				(font
					(size 1.27 1.27)
				)
			)
		)
		(property "Value" "1KR2F-3-GP"
			(at 0.064008 -3.993896 0)
			(unlocked yes)
			(layer "F.Fab")
			(hide yes)
			(effects
				(font
					(size 1.016 1.016)
					(thickness 0.1524)
				)
			)
		)
		(property "Device Type" "R402H16"
			(at 0.064008 -5.517896 0)
			(unlocked yes)
			(layer "F.Fab")
			(hide yes)
			(effects
				(font
					(size 1.016 1.016)
					(thickness 0.1524)
				)
			)
		)
		(duplicate_pad_numbers_are_jumpers no)
		(fp_line
			(start -0.508 -0.9398)
			(end -0.508 0.9398)
			(stroke
				(width 0.1524)
				(type default)
			)
			(layer "F.SilkS")
		)
		(fp_line
			(start 0.508 -0.9398)
			(end -0.508 -0.9398)
			(stroke
				(width 0.1524)
				(type default)
			)
			(layer "F.SilkS")
		)
		(fp_rect
			(start -0.508 0.9398)
			(end 0.508 -0.9398)
			(stroke
				(width 0)
				(type default)
			)
			(fill no)
			(layer "F.CrtYd")
		)
		(fp_rect
			(start -0.508 0.9398)
			(end 0.508 -0.9398)
			(stroke
				(width 0)
				(type default)
			)
			(fill no)
			(layer "F.Fab")
		)
		(pad "1" smd custom
			(at 0 -0.4445)
			(size 0.1397 0.1397)
			(layers "F.Cu" "F.Mask" "F.Paste")
			(net "P3V3")
			(options
				(clearance outline)
				(anchor circle)
			)
			(primitives
				(gr_poly
					(pts
						(arc
							(start -0.1778 -0.2794)
							(mid -0.249642 -0.249642)
							(end -0.2794 -0.1778)
						)
						(arc
							(start -0.2794 0.1778)
							(mid -0.249642 0.249642)
							(end -0.1778 0.2794)
						)
						(arc
							(start 0.1778 0.2794)
							(mid 0.249642 0.249642)
							(end 0.2794 0.1778)
						)
						(arc
							(start 0.2794 -0.1778)
							(mid 0.249642 -0.249642)
							(end 0.1778 -0.2794)
						)
					)
					(width 0)
					(fill yes)
				)
			)
		)
		(pad "2" smd custom
			(at 0 0.4445)
			(size 0.1397 0.1397)
			(layers "F.Cu" "F.Mask" "F.Paste")
			(net "I2C_BMC_RMT_SCL1")
			(options
				(clearance outline)
				(anchor circle)
			)
			(primitives
				(gr_poly
					(pts
						(arc
							(start -0.1778 -0.2794)
							(mid -0.249642 -0.249642)
							(end -0.2794 -0.1778)
						)
						(arc
							(start -0.2794 0.1778)
							(mid -0.249642 0.249642)
							(end -0.1778 0.2794)
						)
						(arc
							(start 0.1778 0.2794)
							(mid 0.249642 0.249642)
							(end 0.2794 0.1778)
						)
						(arc
							(start 0.2794 -0.1778)
							(mid 0.249642 -0.249642)
							(end 0.1778 -0.2794)
						)
					)
					(width 0)
					(fill yes)
				)
			)
		)
	)
	(footprint ""
		(layer "F.Cu")
		(at 140.054076 -84.705952)
		(property "Reference" "R48"
			(at 0 0 0)
			(layer "F.SilkS")
			(hide yes)
			(effects
				(font
					(size 1.27 1.27)
				)
			)
		)
		(property "Value" "4K7R2F-GP"
			(at 0.064008 -3.993896 0)
			(unlocked yes)
			(layer "F.Fab")
			(hide yes)
			(effects
				(font
					(size 1.016 1.016)
					(thickness 0.1524)
				)
			)
		)
		(property "Device Type" "R402H16"
			(at 0.064008 -5.517896 0)
			(unlocked yes)
			(layer "F.Fab")
			(hide yes)
			(effects
				(font
					(size 1.016 1.016)
					(thickness 0.1524)
				)
			)
		)
		(duplicate_pad_numbers_are_jumpers no)
		(fp_line
			(start -0.508 -0.9398)
			(end -0.508 0.9398)
			(stroke
				(width 0.1524)
				(type default)
			)
			(layer "F.SilkS")
		)
		(fp_line
			(start 0.508 -0.9398)
			(end -0.508 -0.9398)
			(stroke
				(width 0.1524)
				(type default)
			)
			(layer "F.SilkS")
		)
		(fp_rect
			(start -0.508 0.9398)
			(end 0.508 -0.9398)
			(stroke
				(width 0)
				(type default)
			)
			(fill no)
			(layer "F.CrtYd")
		)
		(fp_rect
			(start -0.508 0.9398)
			(end 0.508 -0.9398)
			(stroke
				(width 0)
				(type default)
			)
			(fill no)
			(layer "F.Fab")
		)
		(pad "1" smd custom
			(at 0 -0.4445)
			(size 0.1397 0.1397)
			(layers "F.Cu" "F.Mask" "F.Paste")
			(net "P1V8_E")
			(options
				(clearance outline)
				(anchor circle)
			)
			(primitives
				(gr_poly
					(pts
						(arc
							(start -0.1778 -0.2794)
							(mid -0.249642 -0.249642)
							(end -0.2794 -0.1778)
						)
						(arc
							(start -0.2794 0.1778)
							(mid -0.249642 0.249642)
							(end -0.1778 0.2794)
						)
						(arc
							(start 0.1778 0.2794)
							(mid 0.249642 0.249642)
							(end 0.2794 0.1778)
						)
						(arc
							(start 0.2794 -0.1778)
							(mid 0.249642 -0.249642)
							(end 0.1778 -0.2794)
						)
					)
					(width 0)
					(fill yes)
				)
			)
		)
		(pad "2" smd custom
			(at 0 0.4445)
			(size 0.1397 0.1397)
			(layers "F.Cu" "F.Mask" "F.Paste")
			(net "I2C_BMC_LOC_SCL0_LS")
			(options
				(clearance outline)
				(anchor circle)
			)
			(primitives
				(gr_poly
					(pts
						(arc
							(start -0.1778 -0.2794)
							(mid -0.249642 -0.249642)
							(end -0.2794 -0.1778)
						)
						(arc
							(start -0.2794 0.1778)
							(mid -0.249642 0.249642)
							(end -0.1778 0.2794)
						)
						(arc
							(start 0.1778 0.2794)
							(mid 0.249642 0.249642)
							(end 0.2794 0.1778)
						)
						(arc
							(start 0.2794 -0.1778)
							(mid 0.249642 -0.249642)
							(end 0.1778 -0.2794)
						)
					)
					(width 0)
					(fill yes)
				)
			)
		)
	)
	(footprint ""
		(layer "F.Cu")
		(at 10.5918 -36.195 180)
		(property "Reference" "Q23"
			(at 0 0 180)
			(layer "F.SilkS")
			(hide yes)
			(effects
				(font
					(size 1.27 1.27)
				)
			)
		)
		(property "Value" "PSMN0R9-25YLC-GP"
			(at -4.2799 -0.4572 180)
			(unlocked yes)
			(layer "F.Fab")
			(hide yes)
			(effects
				(font
					(size 1.016 1.016)
					(thickness 0.1524)
				)
			)
		)
		(property "Device Type" "LFPAK-5PH48-U"
			(at -4.2799 -1.9812 180)
			(unlocked yes)
			(layer "F.Fab")
			(hide yes)
			(effects
				(font
					(size 1.016 1.016)
					(thickness 0.1524)
				)
			)
		)
		(duplicate_pad_numbers_are_jumpers no)
		(fp_line
			(start 2.7559 1.0668)
			(end 2.7559 -6.5532)
			(stroke
				(width 0.1524)
				(type default)
			)
			(layer "F.SilkS")
		)
		(fp_line
			(start 2.7559 -6.5532)
			(end -2.7559 -6.5532)
			(stroke
				(width 0.1524)
				(type default)
			)
			(layer "F.SilkS")
		)
		(fp_line
			(start -1.7272 1.1684)
			(end -2.1082 1.1684)
			(stroke
				(width 0.3302)
				(type default)
			)
			(layer "F.SilkS")
		)
		(fp_line
			(start -2.7559 1.0668)
			(end 2.7559 1.0668)
			(stroke
				(width 0.1524)
				(type default)
			)
			(layer "F.SilkS")
		)
		(fp_line
			(start -2.7559 -6.5532)
			(end -2.7559 1.0668)
			(stroke
				(width 0.1524)
				(type default)
			)
			(layer "F.SilkS")
		)
		(fp_poly
			(pts
				(xy -2.3368 1.5748) (xy -1.905 1.143) (xy -1.4732 1.5748)
			)
			(stroke
				(width 0)
				(type default)
			)
			(fill yes)
			(layer "F.SilkS")
		)
		(fp_poly
			(pts
				(xy 0.3302 -1.09601) (xy 2.5019 -1.09601) (xy 2.5019 -3.36931) (xy 0.3302 -3.36931)
			)
			(stroke
				(width 0)
				(type default)
			)
			(fill yes)
			(layer "F.Paste")
		)
		(fp_poly
			(pts
				(xy 0.3302 -4.02971) (xy 2.5019 -4.02971) (xy 2.5019 -6.30301) (xy 0.3302 -6.30301)
			)
			(stroke
				(width 0)
				(type default)
			)
			(fill yes)
			(layer "F.Paste")
		)
		(fp_poly
			(pts
				(xy -2.5019 -1.09601) (xy -0.3302 -1.09601) (xy -0.3302 -3.36931) (xy -2.5019 -3.36931)
			)
			(stroke
				(width 0)
				(type default)
			)
			(fill yes)
			(layer "F.Paste")
		)
		(fp_poly
			(pts
				(xy -2.5019 -4.02971) (xy -0.3302 -4.02971) (xy -0.3302 -6.30301) (xy -2.5019 -6.30301)
			)
			(stroke
				(width 0)
				(type default)
			)
			(fill yes)
			(layer "F.Paste")
		)
		(fp_rect
			(start -2.4511 0.3048)
			(end 2.4511 -5.6896)
			(stroke
				(width 0)
				(type default)
			)
			(fill no)
			(layer "F.CrtYd")
		)
		(fp_poly
			(pts
				(xy -3.0099 1.3208) (xy -3.0099 -6.8072) (xy 3.0099 -6.8072) (xy 3.0099 -1.016) (xy 2.4511 -1.016)
				(xy 2.4511 -5.6896) (xy -2.4511 -5.6896) (xy -2.4511 0.3048) (xy 2.4511 0.3048) (xy 2.4511 -1.0033)
				(xy 3.0099 -1.0033) (xy 3.0099 1.3208)
			)
			(stroke
				(width 0)
				(type default)
			)
			(fill no)
			(layer "F.CrtYd")
		)
		(fp_rect
			(start -3.0099 1.3208)
			(end 3.0099 -6.8072)
			(stroke
				(width 0)
				(type default)
			)
			(fill no)
			(layer "F.Fab")
		)
		(pad "1" smd rect
			(at -1.905 0 180)
			(size 0.762 1.6256)
			(layers "F.Cu" "F.Mask" "F.Paste")
			(net "P12V_STBY_SCC")
		)
		(pad "2" smd rect
			(at -0.635 0 180)
			(size 0.762 1.6256)
			(layers "F.Cu" "F.Mask" "F.Paste")
			(net "P12V_STBY_SCC")
		)
		(pad "3" smd rect
			(at 0.635 0 180)
			(size 0.762 1.6256)
			(layers "F.Cu" "F.Mask" "F.Paste")
			(net "P12V_STBY_SCC")
		)
		(pad "4" smd rect
			(at 1.905 0 180)
			(size 0.762 1.6256)
			(layers "F.Cu" "F.Mask" "F.Paste")
			(net "MB0_12V_CTRL_GATE1")
		)
		(pad "5" smd rect
			(at 0 -3.69951 180)
			(size 5.0038 5.207)
			(layers "F.Cu" "F.Mask" "F.Paste")
			(net "MB0_P12V_MAIN_R")
		)
	)
	(footprint ""
		(layer "F.Cu")
		(at 149.4282 -123.6091 -90)
		(property "Reference" "R377"
			(at 0 0 270)
			(layer "F.SilkS")
			(hide yes)
			(effects
				(font
					(size 1.27 1.27)
				)
			)
		)
		(property "Value" "15KR2F-GP"
			(at 0.064008 -3.993896 270)
			(unlocked yes)
			(layer "F.Fab")
			(hide yes)
			(effects
				(font
					(size 1.016 1.016)
					(thickness 0.1524)
				)
			)
		)
		(property "Device Type" "R402H16"
			(at 0.064008 -5.517896 270)
			(unlocked yes)
			(layer "F.Fab")
			(hide yes)
			(effects
				(font
					(size 1.016 1.016)
					(thickness 0.1524)
				)
			)
		)
		(duplicate_pad_numbers_are_jumpers no)
		(fp_line
			(start -0.508 -0.9398)
			(end -0.508 0.9398)
			(stroke
				(width 0.1524)
				(type default)
			)
			(layer "F.SilkS")
		)
		(fp_line
			(start 0.508 -0.9398)
			(end -0.508 -0.9398)
			(stroke
				(width 0.1524)
				(type default)
			)
			(layer "F.SilkS")
		)
		(fp_rect
			(start -0.508 0.9398)
			(end 0.508 -0.9398)
			(stroke
				(width 0)
				(type default)
			)
			(fill no)
			(layer "F.CrtYd")
		)
		(fp_rect
			(start -0.508 0.9398)
			(end 0.508 -0.9398)
			(stroke
				(width 0)
				(type default)
			)
			(fill no)
			(layer "F.Fab")
		)
		(pad "1" smd custom
			(at 0 -0.4445 270)
			(size 0.1397 0.1397)
			(layers "F.Cu" "F.Mask" "F.Paste")
			(net "P1V5_E_VFB")
			(options
				(clearance outline)
				(anchor circle)
			)
			(primitives
				(gr_poly
					(pts
						(arc
							(start -0.1778 -0.2794)
							(mid -0.249642 -0.249642)
							(end -0.2794 -0.1778)
						)
						(arc
							(start -0.2794 0.1778)
							(mid -0.249642 0.249642)
							(end -0.1778 0.2794)
						)
						(arc
							(start 0.1778 0.2794)
							(mid 0.249642 0.249642)
							(end 0.2794 0.1778)
						)
						(arc
							(start 0.2794 -0.1778)
							(mid 0.249642 -0.249642)
							(end 0.1778 -0.2794)
						)
					)
					(width 0)
					(fill yes)
				)
			)
		)
		(pad "2" smd custom
			(at 0 0.4445 270)
			(size 0.1397 0.1397)
			(layers "F.Cu" "F.Mask" "F.Paste")
			(net "P1V5_E_VFB_R")
			(options
				(clearance outline)
				(anchor circle)
			)
			(primitives
				(gr_poly
					(pts
						(arc
							(start -0.1778 -0.2794)
							(mid -0.249642 -0.249642)
							(end -0.2794 -0.1778)
						)
						(arc
							(start -0.2794 0.1778)
							(mid -0.249642 0.249642)
							(end -0.1778 0.2794)
						)
						(arc
							(start 0.1778 0.2794)
							(mid 0.249642 0.249642)
							(end 0.2794 0.1778)
						)
						(arc
							(start 0.2794 -0.1778)
							(mid 0.249642 -0.249642)
							(end 0.1778 -0.2794)
						)
					)
					(width 0)
					(fill yes)
				)
			)
		)
	)
	(footprint ""
		(layer "F.Cu")
		(at 181.229 -55.245 -90)
		(property "Reference" "R229"
			(at 0 0 270)
			(layer "F.SilkS")
			(hide yes)
			(effects
				(font
					(size 1.27 1.27)
				)
			)
		)
		(property "Value" "10KR2F-2-GP"
			(at 0.064008 -3.993896 270)
			(unlocked yes)
			(layer "F.Fab")
			(hide yes)
			(effects
				(font
					(size 1.016 1.016)
					(thickness 0.1524)
				)
			)
		)
		(property "Device Type" "R402H16"
			(at 0.064008 -5.517896 270)
			(unlocked yes)
			(layer "F.Fab")
			(hide yes)
			(effects
				(font
					(size 1.016 1.016)
					(thickness 0.1524)
				)
			)
		)
		(duplicate_pad_numbers_are_jumpers no)
		(fp_line
			(start -0.508 -0.9398)
			(end -0.508 0.9398)
			(stroke
				(width 0.1524)
				(type default)
			)
			(layer "F.SilkS")
		)
		(fp_line
			(start 0.508 -0.9398)
			(end -0.508 -0.9398)
			(stroke
				(width 0.1524)
				(type default)
			)
			(layer "F.SilkS")
		)
		(fp_rect
			(start -0.508 0.9398)
			(end 0.508 -0.9398)
			(stroke
				(width 0)
				(type default)
			)
			(fill no)
			(layer "F.CrtYd")
		)
		(fp_rect
			(start -0.508 0.9398)
			(end 0.508 -0.9398)
			(stroke
				(width 0)
				(type default)
			)
			(fill no)
			(layer "F.Fab")
		)
		(pad "1" smd custom
			(at 0 -0.4445 270)
			(size 0.1397 0.1397)
			(layers "F.Cu" "F.Mask" "F.Paste")
			(net "P1V8_C")
			(options
				(clearance outline)
				(anchor circle)
			)
			(primitives
				(gr_poly
					(pts
						(arc
							(start -0.1778 -0.2794)
							(mid -0.249642 -0.249642)
							(end -0.2794 -0.1778)
						)
						(arc
							(start -0.2794 0.1778)
							(mid -0.249642 0.249642)
							(end -0.1778 0.2794)
						)
						(arc
							(start 0.1778 0.2794)
							(mid 0.249642 0.249642)
							(end 0.2794 0.1778)
						)
						(arc
							(start 0.2794 -0.1778)
							(mid 0.249642 -0.249642)
							(end 0.1778 -0.2794)
						)
					)
					(width 0)
					(fill yes)
				)
			)
		)
		(pad "2" smd custom
			(at 0 0.4445 270)
			(size 0.1397 0.1397)
			(layers "F.Cu" "F.Mask" "F.Paste")
			(net "XM_RB")
			(options
				(clearance outline)
				(anchor circle)
			)
			(primitives
				(gr_poly
					(pts
						(arc
							(start -0.1778 -0.2794)
							(mid -0.249642 -0.249642)
							(end -0.2794 -0.1778)
						)
						(arc
							(start -0.2794 0.1778)
							(mid -0.249642 0.249642)
							(end -0.1778 0.2794)
						)
						(arc
							(start 0.1778 0.2794)
							(mid 0.249642 0.249642)
							(end 0.2794 0.1778)
						)
						(arc
							(start 0.2794 -0.1778)
							(mid 0.249642 -0.249642)
							(end 0.1778 -0.2794)
						)
					)
					(width 0)
					(fill yes)
				)
			)
		)
	)
	(footprint ""
		(layer "F.Cu")
		(at 17.0307 -93.408754 90)
		(property "Reference" "R410"
			(at 0 0 90)
			(layer "F.SilkS")
			(hide yes)
			(effects
				(font
					(size 1.27 1.27)
				)
			)
		)
		(property "Value" "0R2J-2-GP"
			(at 0.064008 -3.993896 90)
			(unlocked yes)
			(layer "F.Fab")
			(hide yes)
			(effects
				(font
					(size 1.016 1.016)
					(thickness 0.1524)
				)
			)
		)
		(property "Device Type" "R402H16"
			(at 0.064008 -5.517896 90)
			(unlocked yes)
			(layer "F.Fab")
			(hide yes)
			(effects
				(font
					(size 1.016 1.016)
					(thickness 0.1524)
				)
			)
		)
		(duplicate_pad_numbers_are_jumpers no)
		(fp_line
			(start 0.508 -0.9398)
			(end -0.508 -0.9398)
			(stroke
				(width 0.1524)
				(type default)
			)
			(layer "F.SilkS")
		)
		(fp_line
			(start -0.508 -0.9398)
			(end -0.508 0.9398)
			(stroke
				(width 0.1524)
				(type default)
			)
			(layer "F.SilkS")
		)
		(fp_rect
			(start -0.508 0.9398)
			(end 0.508 -0.9398)
			(stroke
				(width 0)
				(type default)
			)
			(fill no)
			(layer "F.CrtYd")
		)
		(fp_rect
			(start -0.508 0.9398)
			(end 0.508 -0.9398)
			(stroke
				(width 0)
				(type default)
			)
			(fill no)
			(layer "F.Fab")
		)
		(pad "1" smd custom
			(at 0 -0.4445 90)
			(size 0.1397 0.1397)
			(layers "F.Cu" "F.Mask" "F.Paste")
			(net "LS_EN_U35")
			(options
				(clearance outline)
				(anchor circle)
			)
			(primitives
				(gr_poly
					(pts
						(arc
							(start -0.1778 -0.2794)
							(mid -0.249642 -0.249642)
							(end -0.2794 -0.1778)
						)
						(arc
							(start -0.2794 0.1778)
							(mid -0.249642 0.249642)
							(end -0.1778 0.2794)
						)
						(arc
							(start 0.1778 0.2794)
							(mid 0.249642 0.249642)
							(end 0.2794 0.1778)
						)
						(arc
							(start 0.2794 -0.1778)
							(mid 0.249642 -0.249642)
							(end 0.1778 -0.2794)
						)
					)
					(width 0)
					(fill yes)
				)
			)
		)
		(pad "2" smd custom
			(at 0 0.4445 90)
			(size 0.1397 0.1397)
			(layers "F.Cu" "F.Mask" "F.Paste")
			(net "VREF0")
			(options
				(clearance outline)
				(anchor circle)
			)
			(primitives
				(gr_poly
					(pts
						(arc
							(start -0.1778 -0.2794)
							(mid -0.249642 -0.249642)
							(end -0.2794 -0.1778)
						)
						(arc
							(start -0.2794 0.1778)
							(mid -0.249642 0.249642)
							(end -0.1778 0.2794)
						)
						(arc
							(start 0.1778 0.2794)
							(mid 0.249642 0.249642)
							(end 0.2794 0.1778)
						)
						(arc
							(start 0.2794 -0.1778)
							(mid 0.249642 -0.249642)
							(end 0.1778 -0.2794)
						)
					)
					(width 0)
					(fill yes)
				)
			)
		)
	)
	(footprint ""
		(layer "F.Cu")
		(at 70.866 -81.6864 -90)
		(property "Reference" "R584"
			(at 0 0 270)
			(layer "F.SilkS")
			(hide yes)
			(effects
				(font
					(size 1.27 1.27)
				)
			)
		)
		(property "Value" "0R2J-2-GP"
			(at 0.064008 -3.993896 270)
			(unlocked yes)
			(layer "F.Fab")
			(hide yes)
			(effects
				(font
					(size 1.016 1.016)
					(thickness 0.1524)
				)
			)
		)
		(property "Device Type" "R402H16"
			(at 0.064008 -5.517896 270)
			(unlocked yes)
			(layer "F.Fab")
			(hide yes)
			(effects
				(font
					(size 1.016 1.016)
					(thickness 0.1524)
				)
			)
		)
		(duplicate_pad_numbers_are_jumpers no)
		(fp_line
			(start -0.508 -0.9398)
			(end -0.508 0.9398)
			(stroke
				(width 0.1524)
				(type default)
			)
			(layer "F.SilkS")
		)
		(fp_line
			(start 0.508 -0.9398)
			(end -0.508 -0.9398)
			(stroke
				(width 0.1524)
				(type default)
			)
			(layer "F.SilkS")
		)
		(fp_rect
			(start -0.508 0.9398)
			(end 0.508 -0.9398)
			(stroke
				(width 0)
				(type default)
			)
			(fill no)
			(layer "F.CrtYd")
		)
		(fp_rect
			(start -0.508 0.9398)
			(end 0.508 -0.9398)
			(stroke
				(width 0)
				(type default)
			)
			(fill no)
			(layer "F.Fab")
		)
		(pad "1" smd custom
			(at 0 -0.4445 270)
			(size 0.1397 0.1397)
			(layers "F.Cu" "F.Mask" "F.Paste")
			(net "P1V8_E")
			(options
				(clearance outline)
				(anchor circle)
			)
			(primitives
				(gr_poly
					(pts
						(arc
							(start -0.1778 -0.2794)
							(mid -0.249642 -0.249642)
							(end -0.2794 -0.1778)
						)
						(arc
							(start -0.2794 0.1778)
							(mid -0.249642 0.249642)
							(end -0.1778 0.2794)
						)
						(arc
							(start 0.1778 0.2794)
							(mid 0.249642 0.249642)
							(end 0.2794 0.1778)
						)
						(arc
							(start 0.2794 -0.1778)
							(mid 0.249642 -0.249642)
							(end 0.1778 -0.2794)
						)
					)
					(width 0)
					(fill yes)
				)
			)
		)
		(pad "2" smd custom
			(at 0 0.4445 270)
			(size 0.1397 0.1397)
			(layers "F.Cu" "F.Mask" "F.Paste")
			(net "U122_VCC")
			(options
				(clearance outline)
				(anchor circle)
			)
			(primitives
				(gr_poly
					(pts
						(arc
							(start -0.1778 -0.2794)
							(mid -0.249642 -0.249642)
							(end -0.2794 -0.1778)
						)
						(arc
							(start -0.2794 0.1778)
							(mid -0.249642 0.249642)
							(end -0.1778 0.2794)
						)
						(arc
							(start 0.1778 0.2794)
							(mid 0.249642 0.249642)
							(end 0.2794 0.1778)
						)
						(arc
							(start 0.2794 -0.1778)
							(mid 0.249642 -0.249642)
							(end 0.1778 -0.2794)
						)
					)
					(width 0)
					(fill yes)
				)
			)
		)
	)
	(footprint ""
		(layer "F.Cu")
		(at 192.829434 -36.480496 -90)
		(property "Reference" "R189"
			(at 0 0 270)
			(layer "F.SilkS")
			(hide yes)
			(effects
				(font
					(size 1.27 1.27)
				)
			)
		)
		(property "Value" "2K2R2F-GP"
			(at 0.064008 -3.993896 270)
			(unlocked yes)
			(layer "F.Fab")
			(hide yes)
			(effects
				(font
					(size 1.016 1.016)
					(thickness 0.1524)
				)
			)
		)
		(property "Device Type" "R402H16"
			(at 0.064008 -5.517896 270)
			(unlocked yes)
			(layer "F.Fab")
			(hide yes)
			(effects
				(font
					(size 1.016 1.016)
					(thickness 0.1524)
				)
			)
		)
		(duplicate_pad_numbers_are_jumpers no)
		(fp_line
			(start -0.508 -0.9398)
			(end -0.508 0.9398)
			(stroke
				(width 0.1524)
				(type default)
			)
			(layer "F.SilkS")
		)
		(fp_line
			(start 0.508 -0.9398)
			(end -0.508 -0.9398)
			(stroke
				(width 0.1524)
				(type default)
			)
			(layer "F.SilkS")
		)
		(fp_rect
			(start -0.508 0.9398)
			(end 0.508 -0.9398)
			(stroke
				(width 0)
				(type default)
			)
			(fill no)
			(layer "F.CrtYd")
		)
		(fp_rect
			(start -0.508 0.9398)
			(end 0.508 -0.9398)
			(stroke
				(width 0)
				(type default)
			)
			(fill no)
			(layer "F.Fab")
		)
		(pad "1" smd custom
			(at 0 -0.4445 270)
			(size 0.1397 0.1397)
			(layers "F.Cu" "F.Mask" "F.Paste")
			(net "P1V8_C")
			(options
				(clearance outline)
				(anchor circle)
			)
			(primitives
				(gr_poly
					(pts
						(arc
							(start -0.1778 -0.2794)
							(mid -0.249642 -0.249642)
							(end -0.2794 -0.1778)
						)
						(arc
							(start -0.2794 0.1778)
							(mid -0.249642 0.249642)
							(end -0.1778 0.2794)
						)
						(arc
							(start 0.1778 0.2794)
							(mid 0.249642 0.249642)
							(end 0.2794 0.1778)
						)
						(arc
							(start 0.2794 -0.1778)
							(mid 0.249642 -0.249642)
							(end 0.1778 -0.2794)
						)
					)
					(width 0)
					(fill yes)
				)
			)
		)
		(pad "2" smd custom
			(at 0 0.4445 270)
			(size 0.1397 0.1397)
			(layers "F.Cu" "F.Mask" "F.Paste")
			(net "I2C_IOC_3_SDA")
			(options
				(clearance outline)
				(anchor circle)
			)
			(primitives
				(gr_poly
					(pts
						(arc
							(start -0.1778 -0.2794)
							(mid -0.249642 -0.249642)
							(end -0.2794 -0.1778)
						)
						(arc
							(start -0.2794 0.1778)
							(mid -0.249642 0.249642)
							(end -0.1778 0.2794)
						)
						(arc
							(start 0.1778 0.2794)
							(mid 0.249642 0.249642)
							(end 0.2794 0.1778)
						)
						(arc
							(start 0.2794 -0.1778)
							(mid 0.249642 -0.249642)
							(end 0.1778 -0.2794)
						)
					)
					(width 0)
					(fill yes)
				)
			)
		)
	)
	(footprint ""
		(layer "F.Cu")
		(at 19.252184 -72.82053 90)
		(property "Reference" "R356"
			(at 0 0 90)
			(layer "F.SilkS")
			(hide yes)
			(effects
				(font
					(size 1.27 1.27)
				)
			)
		)
		(property "Value" "8K2R2J-3-GP"
			(at 0.064008 -3.993896 90)
			(unlocked yes)
			(layer "F.Fab")
			(hide yes)
			(effects
				(font
					(size 1.016 1.016)
					(thickness 0.1524)
				)
			)
		)
		(property "Device Type" "R402H16"
			(at 0.064008 -5.517896 90)
			(unlocked yes)
			(layer "F.Fab")
			(hide yes)
			(effects
				(font
					(size 1.016 1.016)
					(thickness 0.1524)
				)
			)
		)
		(duplicate_pad_numbers_are_jumpers no)
		(fp_line
			(start 0.508 -0.9398)
			(end -0.508 -0.9398)
			(stroke
				(width 0.1524)
				(type default)
			)
			(layer "F.SilkS")
		)
		(fp_line
			(start -0.508 -0.9398)
			(end -0.508 0.9398)
			(stroke
				(width 0.1524)
				(type default)
			)
			(layer "F.SilkS")
		)
		(fp_rect
			(start -0.508 0.9398)
			(end 0.508 -0.9398)
			(stroke
				(width 0)
				(type default)
			)
			(fill no)
			(layer "F.CrtYd")
		)
		(fp_rect
			(start -0.508 0.9398)
			(end 0.508 -0.9398)
			(stroke
				(width 0)
				(type default)
			)
			(fill no)
			(layer "F.Fab")
		)
		(pad "1" smd custom
			(at 0 -0.4445 90)
			(size 0.1397 0.1397)
			(layers "F.Cu" "F.Mask" "F.Paste")
			(net "EEPROM_WP")
			(options
				(clearance outline)
				(anchor circle)
			)
			(primitives
				(gr_poly
					(pts
						(arc
							(start -0.1778 -0.2794)
							(mid -0.249642 -0.249642)
							(end -0.2794 -0.1778)
						)
						(arc
							(start -0.2794 0.1778)
							(mid -0.249642 0.249642)
							(end -0.1778 0.2794)
						)
						(arc
							(start 0.1778 0.2794)
							(mid 0.249642 0.249642)
							(end 0.2794 0.1778)
						)
						(arc
							(start 0.2794 -0.1778)
							(mid 0.249642 -0.249642)
							(end 0.1778 -0.2794)
						)
					)
					(width 0)
					(fill yes)
				)
			)
		)
		(pad "2" smd custom
			(at 0 0.4445 90)
			(size 0.1397 0.1397)
			(layers "F.Cu" "F.Mask" "F.Paste")
			(net "GND")
			(options
				(clearance outline)
				(anchor circle)
			)
			(primitives
				(gr_poly
					(pts
						(arc
							(start -0.1778 -0.2794)
							(mid -0.249642 -0.249642)
							(end -0.2794 -0.1778)
						)
						(arc
							(start -0.2794 0.1778)
							(mid -0.249642 0.249642)
							(end -0.1778 0.2794)
						)
						(arc
							(start 0.1778 0.2794)
							(mid 0.249642 0.249642)
							(end 0.2794 0.1778)
						)
						(arc
							(start 0.2794 -0.1778)
							(mid 0.249642 -0.249642)
							(end 0.1778 -0.2794)
						)
					)
					(width 0)
					(fill yes)
				)
			)
		)
	)
	(footprint ""
		(layer "F.Cu")
		(at 176.6824 -57.785)
		(property "Reference" "TP140"
			(at 0 0 0)
			(layer "F.SilkS")
			(hide yes)
			(effects
				(font
					(size 1.27 1.27)
				)
			)
		)
		(property "Value" "TPAD28-2-GP"
			(at -0.0127 -1.6637 0)
			(unlocked yes)
			(layer "F.Fab")
			(hide yes)
			(effects
				(font
					(size 1.016 1.016)
					(thickness 0.1524)
				)
			)
		)
		(property "Device Type" "TPAD28"
			(at -0.0127 -3.1877 0)
			(unlocked yes)
			(layer "F.Fab")
			(hide yes)
			(effects
				(font
					(size 1.016 1.016)
					(thickness 0.1524)
				)
			)
		)
		(duplicate_pad_numbers_are_jumpers no)
		(fp_poly
			(pts
				(arc
					(start 0.3556 0)
					(mid -0.3556 0)
					(end 0.3556 0)
				)
			)
			(stroke
				(width 0)
				(type default)
			)
			(fill no)
			(layer "F.CrtYd")
		)
		(fp_poly
			(pts
				(arc
					(start 0.6096 0)
					(mid -0.6096 0)
					(end 0.6096 0)
				)
			)
			(stroke
				(width 0)
				(type default)
			)
			(fill no)
			(layer "F.Fab")
		)
		(pad "1" smd circle
			(at 0 0)
			(size 0.7112 0.7112)
			(layers "F.Cu" "F.Mask" "F.Paste")
			(net "LSI_SCAN_EN")
		)
	)
	(footprint ""
		(layer "F.Cu")
		(at 153.924 -110.49 180)
		(property "Reference" "R379"
			(at 0 0 180)
			(layer "F.SilkS")
			(hide yes)
			(effects
				(font
					(size 1.27 1.27)
				)
			)
		)
		(property "Value" "3D01R5F-GP"
			(at 0 -8.9535 180)
			(unlocked yes)
			(layer "F.Fab")
			(hide yes)
			(effects
				(font
					(size 1.27 1.016)
					(thickness 0.1524)
				)
			)
		)
		(property "Device Type" "R805H24"
			(at 0 -10.6299 180)
			(unlocked yes)
			(layer "F.Fab")
			(hide yes)
			(effects
				(font
					(size 1.27 1.016)
					(thickness 0.1524)
				)
			)
		)
		(duplicate_pad_numbers_are_jumpers no)
		(fp_line
			(start 0.889 1.7018)
			(end 0.889 -0.508)
			(stroke
				(width 0.1524)
				(type default)
			)
			(layer "F.SilkS")
		)
		(fp_line
			(start 0.889 -1.7018)
			(end 0.889 -0.381)
			(stroke
				(width 0.1524)
				(type default)
			)
			(layer "F.SilkS")
		)
		(fp_line
			(start 0.889 -1.7018)
			(end -0.889 -1.7018)
			(stroke
				(width 0.1524)
				(type default)
			)
			(layer "F.SilkS")
		)
		(fp_line
			(start -0.889 1.7018)
			(end 0.889 1.7018)
			(stroke
				(width 0.1524)
				(type default)
			)
			(layer "F.SilkS")
		)
		(fp_line
			(start -0.889 0.0762)
			(end -0.889 1.7018)
			(stroke
				(width 0.1524)
				(type default)
			)
			(layer "F.SilkS")
		)
		(fp_line
			(start -0.889 -1.7018)
			(end -0.889 0.2794)
			(stroke
				(width 0.1524)
				(type default)
			)
			(layer "F.SilkS")
		)
		(fp_poly
			(pts
				(xy 0.9652 -1.778) (xy 0.9652 1.778) (xy -0.9652 1.778) (xy -0.9652 -1.778)
			)
			(stroke
				(width 0)
				(type default)
			)
			(fill no)
			(layer "F.CrtYd")
		)
		(fp_rect
			(start -0.9652 1.778)
			(end 0.9652 -1.778)
			(stroke
				(width 0)
				(type default)
			)
			(fill no)
			(layer "F.Fab")
		)
		(pad "1" smd rect
			(at 0 -0.9652 180)
			(size 1.397 1.143)
			(layers "F.Cu" "F.Mask" "F.Paste")
			(net "P1V5_E_SNB")
		)
		(pad "2" smd rect
			(at 0 0.9652 180)
			(size 1.397 1.143)
			(layers "F.Cu" "F.Mask" "F.Paste")
			(net "GND")
		)
	)
	(footprint ""
		(layer "F.Cu")
		(at 16.0528 -34.4678 90)
		(property "Reference" "R14"
			(at 0 0 90)
			(layer "F.SilkS")
			(hide yes)
			(effects
				(font
					(size 1.27 1.27)
				)
			)
		)
		(property "Value" "D003R0612F-L-GP"
			(at 3.2766 1.3843 90)
			(unlocked yes)
			(layer "F.Fab")
			(hide yes)
			(effects
				(font
					(size 1.016 1.016)
					(thickness 0.1524)
				)
			)
		)
		(property "Device Type" "RL3115-4PH25"
			(at 3.2766 -0.1397 90)
			(unlocked yes)
			(layer "F.Fab")
			(hide yes)
			(effects
				(font
					(size 1.016 1.016)
					(thickness 0.1524)
				)
			)
		)
		(duplicate_pad_numbers_are_jumpers no)
		(fp_line
			(start -0.5461 -1.778)
			(end -2.0828 -1.778)
			(stroke
				(width 0.3302)
				(type default)
			)
			(layer "F.SilkS")
		)
		(fp_line
			(start -2.0828 -1.778)
			(end -2.0828 -0.4445)
			(stroke
				(width 0.3302)
				(type default)
			)
			(layer "F.SilkS")
		)
		(fp_line
			(start 1.9685 -1.651)
			(end 1.9685 1.651)
			(stroke
				(width 0.1524)
				(type default)
			)
			(layer "F.SilkS")
		)
		(fp_line
			(start -1.9685 -1.651)
			(end 1.9685 -1.651)
			(stroke
				(width 0.1524)
				(type default)
			)
			(layer "F.SilkS")
		)
		(fp_line
			(start 1.9685 1.651)
			(end -1.9685 1.651)
			(stroke
				(width 0.1524)
				(type default)
			)
			(layer "F.SilkS")
		)
		(fp_line
			(start -1.9685 1.651)
			(end -1.9685 -1.651)
			(stroke
				(width 0.1524)
				(type default)
			)
			(layer "F.SilkS")
		)
		(fp_poly
			(pts
				(xy -0.561594 -1.726946) (xy -0.053594 -2.234946) (xy -1.069594 -2.234946)
			)
			(stroke
				(width 0)
				(type default)
			)
			(fill yes)
			(layer "F.SilkS")
		)
		(fp_rect
			(start -1.524 0.7493)
			(end 1.524 -0.7493)
			(stroke
				(width 0)
				(type default)
			)
			(fill no)
			(layer "F.CrtYd")
		)
		(fp_poly
			(pts
				(xy -2.2225 1.905) (xy -2.2225 -1.905) (xy 2.2225 -1.905) (xy 2.2225 -0.7493) (xy -1.524 -0.7493)
				(xy -1.524 0.7493) (xy 1.524 0.7493) (xy 1.524 -0.7366) (xy 2.2225 -0.7366) (xy 2.2225 1.905)
			)
			(stroke
				(width 0)
				(type default)
			)
			(fill no)
			(layer "F.CrtYd")
		)
		(fp_rect
			(start -2.2225 1.905)
			(end 2.2225 -1.905)
			(stroke
				(width 0)
				(type default)
			)
			(fill no)
			(layer "F.Fab")
		)
		(pad "1" smd rect
			(at -0.5715 -0.813562 90)
			(size 2.286 1.143)
			(layers "F.Cu" "F.Mask" "F.Paste")
			(net "MB0_P12V_MAIN_R")
		)
		(pad "2" smd rect
			(at -0.5715 0.813562 90)
			(size 2.286 1.143)
			(layers "F.Cu" "F.Mask" "F.Paste")
			(net "P12V_MAIN")
		)
		(pad "3" smd rect
			(at 1.334008 -0.813562 90)
			(size 0.762 1.143)
			(layers "F.Cu" "F.Mask" "F.Paste")
			(net "MB0_CM_SENSE_R1_N")
		)
		(pad "4" smd rect
			(at 1.334008 0.813562 90)
			(size 0.762 1.143)
			(layers "F.Cu" "F.Mask" "F.Paste")
			(net "MB0_CM_SENSE_R1_P")
		)
		(zone
			(layer "F.Cu")
			(hatch none 0.5)
			(connect_pads
				(clearance 0)
			)
			(min_thickness 0.25)
			(keepout
				(tracks allowed)
				(vias not_allowed)
				(pads allowed)
				(copperpour not_allowed)
				(footprints allowed)
			)
			(placement
				(enabled no)
				(sheetname "")
			)
			(fill
				(thermal_gap 0.5)
				(thermal_bridge_width 0.5)
				(island_removal_mode 0)
			)
			(polygon
				(pts
					(xy 15.810738 -35.0393) (xy 15.810738 -35.420808) (xy 15.3035 -35.420808) (xy 15.3035 -35.0393)
				)
			)
		)
		(zone
			(layer "F.Cu")
			(hatch none 0.5)
			(connect_pads
				(clearance 0)
			)
			(min_thickness 0.25)
			(keepout
				(tracks not_allowed)
				(vias allowed)
				(pads allowed)
				(copperpour not_allowed)
				(footprints allowed)
			)
			(placement
				(enabled no)
				(sheetname "")
			)
			(fill
				(thermal_gap 0.5)
				(thermal_bridge_width 0.5)
				(island_removal_mode 0)
			)
			(polygon
				(pts
					(xy 15.810738 -35.0393) (xy 15.810738 -35.420808) (xy 15.3035 -35.420808) (xy 15.3035 -35.0393)
				)
			)
		)
		(zone
			(layer "F.Cu")
			(hatch none 0.5)
			(connect_pads
				(clearance 0)
			)
			(min_thickness 0.25)
			(keepout
				(tracks allowed)
				(vias not_allowed)
				(pads allowed)
				(copperpour not_allowed)
				(footprints allowed)
			)
			(placement
				(enabled no)
				(sheetname "")
			)
			(fill
				(thermal_gap 0.5)
				(thermal_bridge_width 0.5)
				(island_removal_mode 0)
			)
			(polygon
				(pts
					(xy 16.8021 -35.0393) (xy 16.8021 -35.420808) (xy 16.294862 -35.420808) (xy 16.294862 -35.0393)
				)
			)
		)
		(zone
			(layer "F.Cu")
			(hatch none 0.5)
			(connect_pads
				(clearance 0)
			)
			(min_thickness 0.25)
			(keepout
				(tracks not_allowed)
				(vias allowed)
				(pads allowed)
				(copperpour not_allowed)
				(footprints allowed)
			)
			(placement
				(enabled no)
				(sheetname "")
			)
			(fill
				(thermal_gap 0.5)
				(thermal_bridge_width 0.5)
				(island_removal_mode 0)
			)
			(polygon
				(pts
					(xy 16.8021 -35.0393) (xy 16.8021 -35.420808) (xy 16.294862 -35.420808) (xy 16.294862 -35.0393)
				)
			)
		)
	)
	(footprint ""
		(layer "F.Cu")
		(at 142.99311 -57.7215 -90)
		(property "Reference" "C39"
			(at 0 0 270)
			(layer "F.SilkS")
			(hide yes)
			(effects
				(font
					(size 1.27 1.27)
				)
			)
		)
		(property "Value" "SCD01U16V1KX-GP"
			(at -2.8321 -1.7399 270)
			(unlocked yes)
			(layer "F.Fab")
			(hide yes)
			(effects
				(font
					(size 1.016 1.016)
					(thickness 0.1524)
				)
			)
		)
		(property "Device Type" "C0201H13"
			(at -2.8321 -3.2639 270)
			(unlocked yes)
			(layer "F.Fab")
			(hide yes)
			(effects
				(font
					(size 1.016 1.016)
					(thickness 0.1524)
				)
			)
		)
		(duplicate_pad_numbers_are_jumpers no)
		(fp_rect
			(start -0.2794 0.6477)
			(end 0.2794 -0.6477)
			(stroke
				(width 0)
				(type default)
			)
			(fill no)
			(layer "F.CrtYd")
		)
		(fp_rect
			(start -0.2794 0.6477)
			(end 0.2794 -0.6477)
			(stroke
				(width 0)
				(type default)
			)
			(fill no)
			(layer "F.Fab")
		)
		(pad "1" smd custom
			(at 0 -0.2794 270)
			(size 0.0762 0.0762)
			(layers "F.Cu" "F.Mask" "F.Paste")
			(net "PHY_IOC_TO_SCC_44_DP")
			(options
				(clearance outline)
				(anchor circle)
			)
			(primitives
				(gr_poly
					(pts
						(arc
							(start 0.1524 -0.127)
							(mid 0.137521 -0.162921)
							(end 0.1016 -0.1778)
						)
						(arc
							(start -0.1016 -0.1778)
							(mid -0.137521 -0.162921)
							(end -0.1524 -0.127)
						)
						(arc
							(start -0.1524 0.127)
							(mid -0.137521 0.162921)
							(end -0.1016 0.1778)
						)
						(arc
							(start 0.1016 0.1778)
							(mid 0.137521 0.162921)
							(end 0.1524 0.127)
						)
					)
					(width 0)
					(fill yes)
				)
			)
		)
		(pad "2" smd custom
			(at 0 0.2794 270)
			(size 0.0762 0.0762)
			(layers "F.Cu" "F.Mask" "F.Paste")
			(net "PHY_IOC_TO_SCC_C_44_DP")
			(options
				(clearance outline)
				(anchor circle)
			)
			(primitives
				(gr_poly
					(pts
						(arc
							(start 0.1524 -0.127)
							(mid 0.137521 -0.162921)
							(end 0.1016 -0.1778)
						)
						(arc
							(start -0.1016 -0.1778)
							(mid -0.137521 -0.162921)
							(end -0.1524 -0.127)
						)
						(arc
							(start -0.1524 0.127)
							(mid -0.137521 0.162921)
							(end -0.1016 0.1778)
						)
						(arc
							(start 0.1016 0.1778)
							(mid 0.137521 0.162921)
							(end 0.1524 0.127)
						)
					)
					(width 0)
					(fill yes)
				)
			)
		)
	)
	(footprint ""
		(layer "F.Cu")
		(at 94.216728 -81.788 180)
		(property "Reference" "R133"
			(at 0 0 180)
			(layer "F.SilkS")
			(hide yes)
			(effects
				(font
					(size 1.27 1.27)
				)
			)
		)
		(property "Value" "0R2J-2-GP"
			(at 0.064008 -3.993896 180)
			(unlocked yes)
			(layer "F.Fab")
			(hide yes)
			(effects
				(font
					(size 1.016 1.016)
					(thickness 0.1524)
				)
			)
		)
		(property "Device Type" "R402H16"
			(at 0.064008 -5.517896 180)
			(unlocked yes)
			(layer "F.Fab")
			(hide yes)
			(effects
				(font
					(size 1.016 1.016)
					(thickness 0.1524)
				)
			)
		)
		(duplicate_pad_numbers_are_jumpers no)
		(fp_line
			(start 0.508 -0.9398)
			(end -0.508 -0.9398)
			(stroke
				(width 0.1524)
				(type default)
			)
			(layer "F.SilkS")
		)
		(fp_line
			(start -0.508 -0.9398)
			(end -0.508 0.9398)
			(stroke
				(width 0.1524)
				(type default)
			)
			(layer "F.SilkS")
		)
		(fp_rect
			(start -0.508 0.9398)
			(end 0.508 -0.9398)
			(stroke
				(width 0)
				(type default)
			)
			(fill no)
			(layer "F.CrtYd")
		)
		(fp_rect
			(start -0.508 0.9398)
			(end 0.508 -0.9398)
			(stroke
				(width 0)
				(type default)
			)
			(fill no)
			(layer "F.Fab")
		)
		(pad "1" smd custom
			(at 0 -0.4445 180)
			(size 0.1397 0.1397)
			(layers "F.Cu" "F.Mask" "F.Paste")
			(net "SCC_RESET_LS_R_N")
			(options
				(clearance outline)
				(anchor circle)
			)
			(primitives
				(gr_poly
					(pts
						(arc
							(start -0.1778 -0.2794)
							(mid -0.249642 -0.249642)
							(end -0.2794 -0.1778)
						)
						(arc
							(start -0.2794 0.1778)
							(mid -0.249642 0.249642)
							(end -0.1778 0.2794)
						)
						(arc
							(start 0.1778 0.2794)
							(mid 0.249642 0.249642)
							(end 0.2794 0.1778)
						)
						(arc
							(start 0.2794 -0.1778)
							(mid 0.249642 -0.249642)
							(end 0.1778 -0.2794)
						)
					)
					(width 0)
					(fill yes)
				)
			)
		)
		(pad "2" smd custom
			(at 0 0.4445 180)
			(size 0.1397 0.1397)
			(layers "F.Cu" "F.Mask" "F.Paste")
			(net "SCC_RESET_LS_N")
			(options
				(clearance outline)
				(anchor circle)
			)
			(primitives
				(gr_poly
					(pts
						(arc
							(start -0.1778 -0.2794)
							(mid -0.249642 -0.249642)
							(end -0.2794 -0.1778)
						)
						(arc
							(start -0.2794 0.1778)
							(mid -0.249642 0.249642)
							(end -0.1778 0.2794)
						)
						(arc
							(start 0.1778 0.2794)
							(mid 0.249642 0.249642)
							(end 0.2794 0.1778)
						)
						(arc
							(start 0.2794 -0.1778)
							(mid 0.249642 -0.249642)
							(end 0.1778 -0.2794)
						)
					)
					(width 0)
					(fill yes)
				)
			)
		)
	)
	(footprint ""
		(layer "F.Cu")
		(at 22.1742 -49.5046 -90)
		(property "Reference" "R18"
			(at 0 0 270)
			(layer "F.SilkS")
			(hide yes)
			(effects
				(font
					(size 1.27 1.27)
				)
			)
		)
		(property "Value" "100KR2J-4-GP"
			(at 0.064008 -3.993896 270)
			(unlocked yes)
			(layer "F.Fab")
			(hide yes)
			(effects
				(font
					(size 1.016 1.016)
					(thickness 0.1524)
				)
			)
		)
		(property "Device Type" "R402H15"
			(at 0.064008 -5.517896 270)
			(unlocked yes)
			(layer "F.Fab")
			(hide yes)
			(effects
				(font
					(size 1.016 1.016)
					(thickness 0.1524)
				)
			)
		)
		(duplicate_pad_numbers_are_jumpers no)
		(fp_line
			(start -0.508 -0.9398)
			(end -0.508 0.9398)
			(stroke
				(width 0.1524)
				(type default)
			)
			(layer "F.SilkS")
		)
		(fp_line
			(start 0.508 -0.9398)
			(end -0.508 -0.9398)
			(stroke
				(width 0.1524)
				(type default)
			)
			(layer "F.SilkS")
		)
		(fp_rect
			(start -0.508 0.9398)
			(end 0.508 -0.9398)
			(stroke
				(width 0)
				(type default)
			)
			(fill no)
			(layer "F.CrtYd")
		)
		(fp_rect
			(start -0.508 0.9398)
			(end 0.508 -0.9398)
			(stroke
				(width 0)
				(type default)
			)
			(fill no)
			(layer "F.Fab")
		)
		(pad "1" smd custom
			(at 0 -0.4445 270)
			(size 0.1397 0.1397)
			(layers "F.Cu" "F.Mask" "F.Paste")
			(net "MB0_VCAP_R")
			(options
				(clearance outline)
				(anchor circle)
			)
			(primitives
				(gr_poly
					(pts
						(arc
							(start -0.1778 -0.2794)
							(mid -0.249642 -0.249642)
							(end -0.2794 -0.1778)
						)
						(arc
							(start -0.2794 0.1778)
							(mid -0.249642 0.249642)
							(end -0.1778 0.2794)
						)
						(arc
							(start 0.1778 0.2794)
							(mid 0.249642 0.249642)
							(end 0.2794 0.1778)
						)
						(arc
							(start 0.2794 -0.1778)
							(mid 0.249642 -0.249642)
							(end 0.1778 -0.2794)
						)
					)
					(width 0)
					(fill yes)
				)
			)
		)
		(pad "2" smd custom
			(at 0 0.4445 270)
			(size 0.1397 0.1397)
			(layers "F.Cu" "F.Mask" "F.Paste")
			(net "MB0_PSET_R")
			(options
				(clearance outline)
				(anchor circle)
			)
			(primitives
				(gr_poly
					(pts
						(arc
							(start -0.1778 -0.2794)
							(mid -0.249642 -0.249642)
							(end -0.2794 -0.1778)
						)
						(arc
							(start -0.2794 0.1778)
							(mid -0.249642 0.249642)
							(end -0.1778 0.2794)
						)
						(arc
							(start 0.1778 0.2794)
							(mid 0.249642 0.249642)
							(end 0.2794 0.1778)
						)
						(arc
							(start 0.2794 -0.1778)
							(mid 0.249642 -0.249642)
							(end 0.1778 -0.2794)
						)
					)
					(width 0)
					(fill yes)
				)
			)
		)
	)
	(footprint ""
		(layer "F.Cu")
		(at 158.69158 -116.39042)
		(property "Reference" "C606"
			(at 0 0 0)
			(layer "F.SilkS")
			(hide yes)
			(effects
				(font
					(size 1.27 1.27)
				)
			)
		)
		(property "Value" "SC1U16V3KX-5GP"
			(at 0 -2.8194 0)
			(unlocked yes)
			(layer "F.Fab")
			(hide yes)
			(effects
				(font
					(size 1.016 1.016)
					(thickness 0.1524)
				)
			)
		)
		(property "Device Type" "C603H36"
			(at 0 -4.3434 0)
			(unlocked yes)
			(layer "F.Fab")
			(hide yes)
			(effects
				(font
					(size 1.016 1.016)
					(thickness 0.1524)
				)
			)
		)
		(duplicate_pad_numbers_are_jumpers no)
		(fp_line
			(start 0.508 0)
			(end -0.508 0)
			(stroke
				(width 0.2032)
				(type default)
			)
			(layer "F.SilkS")
		)
		(fp_rect
			(start -0.5842 1.3335)
			(end 0.5842 -1.3335)
			(stroke
				(width 0)
				(type default)
			)
			(fill no)
			(layer "F.CrtYd")
		)
		(fp_rect
			(start -0.5842 1.3335)
			(end 0.5842 -1.3335)
			(stroke
				(width 0)
				(type default)
			)
			(fill no)
			(layer "F.Fab")
		)
		(pad "1" smd custom
			(at 0 -0.762)
			(size 0.2159 0.2159)
			(layers "F.Cu" "F.Mask" "F.Paste")
			(net "GND")
			(options
				(clearance outline)
				(anchor circle)
			)
			(primitives
				(gr_poly
					(pts
						(arc
							(start -0.3302 -0.4318)
							(mid -0.402042 -0.402042)
							(end -0.4318 -0.3302)
						)
						(arc
							(start -0.4318 0.3302)
							(mid -0.402042 0.402042)
							(end -0.3302 0.4318)
						)
						(arc
							(start 0.3302 0.4318)
							(mid 0.402042 0.402042)
							(end 0.4318 0.3302)
						)
						(arc
							(start 0.4318 -0.3302)
							(mid 0.402042 -0.402042)
							(end 0.3302 -0.4318)
						)
					)
					(width 0)
					(fill yes)
				)
			)
		)
		(pad "2" smd custom
			(at 0 0.762)
			(size 0.2159 0.2159)
			(layers "F.Cu" "F.Mask" "F.Paste")
			(net "P1V5_E_VREG")
			(options
				(clearance outline)
				(anchor circle)
			)
			(primitives
				(gr_poly
					(pts
						(arc
							(start -0.3302 -0.4318)
							(mid -0.402042 -0.402042)
							(end -0.4318 -0.3302)
						)
						(arc
							(start -0.4318 0.3302)
							(mid -0.402042 0.402042)
							(end -0.3302 0.4318)
						)
						(arc
							(start 0.3302 0.4318)
							(mid 0.402042 0.402042)
							(end 0.4318 0.3302)
						)
						(arc
							(start 0.4318 -0.3302)
							(mid 0.402042 -0.402042)
							(end 0.3302 -0.4318)
						)
					)
					(width 0)
					(fill yes)
				)
			)
		)
	)
	(footprint ""
		(layer "F.Cu")
		(at 70.104 -8.509 90)
		(property "Reference" "R105"
			(at 0 0 90)
			(layer "F.SilkS")
			(hide yes)
			(effects
				(font
					(size 1.27 1.27)
				)
			)
		)
		(property "Value" "0R2J-2-GP"
			(at 0.064008 -3.993896 90)
			(unlocked yes)
			(layer "F.Fab")
			(hide yes)
			(effects
				(font
					(size 1.016 1.016)
					(thickness 0.1524)
				)
			)
		)
		(property "Device Type" "R402H16"
			(at 0.064008 -5.517896 90)
			(unlocked yes)
			(layer "F.Fab")
			(hide yes)
			(effects
				(font
					(size 1.016 1.016)
					(thickness 0.1524)
				)
			)
		)
		(duplicate_pad_numbers_are_jumpers no)
		(fp_line
			(start 0.508 -0.9398)
			(end -0.508 -0.9398)
			(stroke
				(width 0.1524)
				(type default)
			)
			(layer "F.SilkS")
		)
		(fp_line
			(start -0.508 -0.9398)
			(end -0.508 0.9398)
			(stroke
				(width 0.1524)
				(type default)
			)
			(layer "F.SilkS")
		)
		(fp_rect
			(start -0.508 0.9398)
			(end 0.508 -0.9398)
			(stroke
				(width 0)
				(type default)
			)
			(fill no)
			(layer "F.CrtYd")
		)
		(fp_rect
			(start -0.508 0.9398)
			(end 0.508 -0.9398)
			(stroke
				(width 0)
				(type default)
			)
			(fill no)
			(layer "F.Fab")
		)
		(pad "1" smd custom
			(at 0 -0.4445 90)
			(size 0.1397 0.1397)
			(layers "F.Cu" "F.Mask" "F.Paste")
			(net "GND")
			(options
				(clearance outline)
				(anchor circle)
			)
			(primitives
				(gr_poly
					(pts
						(arc
							(start -0.1778 -0.2794)
							(mid -0.249642 -0.249642)
							(end -0.2794 -0.1778)
						)
						(arc
							(start -0.2794 0.1778)
							(mid -0.249642 0.249642)
							(end -0.1778 0.2794)
						)
						(arc
							(start 0.1778 0.2794)
							(mid 0.249642 0.249642)
							(end 0.2794 0.1778)
						)
						(arc
							(start 0.2794 -0.1778)
							(mid 0.249642 -0.249642)
							(end 0.1778 -0.2794)
						)
					)
					(width 0)
					(fill yes)
				)
			)
		)
		(pad "2" smd custom
			(at 0 0.4445 90)
			(size 0.1397 0.1397)
			(layers "F.Cu" "F.Mask" "F.Paste")
			(net "SCC_TYPE_2")
			(options
				(clearance outline)
				(anchor circle)
			)
			(primitives
				(gr_poly
					(pts
						(arc
							(start -0.1778 -0.2794)
							(mid -0.249642 -0.249642)
							(end -0.2794 -0.1778)
						)
						(arc
							(start -0.2794 0.1778)
							(mid -0.249642 0.249642)
							(end -0.1778 0.2794)
						)
						(arc
							(start 0.1778 0.2794)
							(mid 0.249642 0.249642)
							(end 0.2794 0.1778)
						)
						(arc
							(start 0.2794 -0.1778)
							(mid 0.249642 -0.249642)
							(end 0.1778 -0.2794)
						)
					)
					(width 0)
					(fill yes)
				)
			)
		)
	)
	(footprint ""
		(layer "F.Cu")
		(at 62.7761 -60.6044 -90)
		(property "Reference" "TC2"
			(at 0 0 270)
			(layer "F.SilkS")
			(hide yes)
			(effects
				(font
					(size 1.27 1.27)
				)
			)
		)
		(property "Value" "SE470UF2VDM-GP"
			(at 0 -9.6012 270)
			(unlocked yes)
			(layer "F.Fab")
			(hide yes)
			(effects
				(font
					(size 1.016 1.016)
					(thickness 0.1524)
				)
			)
		)
		(property "Device Type" "CT7343H83"
			(at 0 -11.1252 270)
			(unlocked yes)
			(layer "F.Fab")
			(hide yes)
			(effects
				(font
					(size 1.016 1.016)
					(thickness 0.1524)
				)
			)
		)
		(duplicate_pad_numbers_are_jumpers no)
		(fp_line
			(start -2.286 4.8768)
			(end -2.286 2.032)
			(stroke
				(width 0.1524)
				(type default)
			)
			(layer "F.SilkS")
		)
		(fp_line
			(start 2.286 4.8768)
			(end -2.286 4.8768)
			(stroke
				(width 0.1524)
				(type default)
			)
			(layer "F.SilkS")
		)
		(fp_line
			(start 2.286 2.032)
			(end 2.286 4.8768)
			(stroke
				(width 0.1524)
				(type default)
			)
			(layer "F.SilkS")
		)
		(fp_line
			(start 2.286 -2.032)
			(end 2.286 -4.8768)
			(stroke
				(width 0.1524)
				(type default)
			)
			(layer "F.SilkS")
		)
		(fp_line
			(start 2.1082 -4.699)
			(end -2.1082 -4.699)
			(stroke
				(width 0.508)
				(type default)
			)
			(layer "F.SilkS")
		)
		(fp_line
			(start -2.286 -4.8768)
			(end -2.286 -2.032)
			(stroke
				(width 0.1524)
				(type default)
			)
			(layer "F.SilkS")
		)
		(fp_line
			(start 2.286 -4.8768)
			(end -2.286 -4.8768)
			(stroke
				(width 0.1524)
				(type default)
			)
			(layer "F.SilkS")
		)
		(fp_rect
			(start -2.1463 3.6449)
			(end 2.1463 -3.6449)
			(stroke
				(width 0)
				(type default)
			)
			(fill no)
			(layer "F.CrtYd")
		)
		(fp_poly
			(pts
				(xy -2.54 4.953) (xy -2.54 4.2926) (xy -3.81 4.2926) (xy -3.81 -4.2926) (xy -2.54 -4.2926) (xy -2.54 -4.953)
				(xy 2.54 -4.953) (xy 2.54 -4.2926) (xy 3.81 -4.2926) (xy 3.81 -1.6256) (xy 2.1463 -1.6256) (xy 2.1463 -3.6449)
				(xy -2.1463 -3.6449) (xy -2.1463 3.6449) (xy 2.1463 3.6449) (xy 2.1463 -1.6129) (xy 3.81 -1.6129)
				(xy 3.81 4.2926) (xy 2.54 4.2926) (xy 2.54 4.953)
			)
			(stroke
				(width 0)
				(type default)
			)
			(fill no)
			(layer "F.CrtYd")
		)
		(fp_rect
			(start -2.54 4.953)
			(end 2.54 -4.953)
			(stroke
				(width 0)
				(type default)
			)
			(fill no)
			(layer "F.Fab")
		)
		(fp_rect
			(start -3.81 4.2926)
			(end -2.54 -4.2926)
			(stroke
				(width 0)
				(type default)
			)
			(fill no)
			(layer "F.Fab")
		)
		(fp_rect
			(start 2.54 4.2926)
			(end 3.81 -4.2926)
			(stroke
				(width 0)
				(type default)
			)
			(fill no)
			(layer "F.Fab")
		)
		(pad "1" smd rect
			(at 0 -3.1496 270)
			(size 2.413 2.286)
			(layers "F.Cu" "F.Mask" "F.Paste")
			(net "P0V9")
		)
		(pad "2" smd rect
			(at 0 3.1496 270)
			(size 2.413 2.286)
			(layers "F.Cu" "F.Mask" "F.Paste")
			(net "GND")
		)
		(zone
			(layer "F.Cu")
			(hatch none 0.5)
			(connect_pads
				(clearance 0)
			)
			(min_thickness 0.25)
			(keepout
				(tracks allowed)
				(vias not_allowed)
				(pads allowed)
				(copperpour not_allowed)
				(footprints allowed)
			)
			(placement
				(enabled no)
				(sheetname "")
			)
			(fill
				(thermal_gap 0.5)
				(thermal_bridge_width 0.5)
				(island_removal_mode 0)
			)
			(polygon
				(pts
					(xy 58.1787 -62.1157) (xy 58.1787 -59.0931) (xy 61.0743 -59.0931) (xy 61.4045 -59.0931) (xy 61.4045 -62.1157)
					(xy 61.0743 -62.1157)
				)
			)
		)
		(zone
			(layer "F.Cu")
			(hatch none 0.5)
			(connect_pads
				(clearance 0)
			)
			(min_thickness 0.25)
			(keepout
				(tracks allowed)
				(vias not_allowed)
				(pads allowed)
				(copperpour not_allowed)
				(footprints allowed)
			)
			(placement
				(enabled no)
				(sheetname "")
			)
			(fill
				(thermal_gap 0.5)
				(thermal_bridge_width 0.5)
				(island_removal_mode 0)
			)
			(polygon
				(pts
					(xy 64.4652 -59.0931) (xy 67.3735 -59.0931) (xy 67.3735 -62.1157) (xy 64.4779 -62.1157) (xy 64.1477 -62.1157)
					(xy 64.1477 -59.0931)
				)
			)
		)
	)
	(footprint ""
		(layer "F.Cu")
		(at 196.528944 -74.46772 90)
		(property "Reference" "R296"
			(at 0 0 90)
			(layer "F.SilkS")
			(hide yes)
			(effects
				(font
					(size 1.27 1.27)
				)
			)
		)
		(property "Value" "0R2J-2-GP"
			(at 0.064008 -3.993896 90)
			(unlocked yes)
			(layer "F.Fab")
			(hide yes)
			(effects
				(font
					(size 1.016 1.016)
					(thickness 0.1524)
				)
			)
		)
		(property "Device Type" "R402H16"
			(at 0.064008 -5.517896 90)
			(unlocked yes)
			(layer "F.Fab")
			(hide yes)
			(effects
				(font
					(size 1.016 1.016)
					(thickness 0.1524)
				)
			)
		)
		(duplicate_pad_numbers_are_jumpers no)
		(fp_line
			(start 0.508 -0.9398)
			(end -0.508 -0.9398)
			(stroke
				(width 0.1524)
				(type default)
			)
			(layer "F.SilkS")
		)
		(fp_line
			(start -0.508 -0.9398)
			(end -0.508 0.9398)
			(stroke
				(width 0.1524)
				(type default)
			)
			(layer "F.SilkS")
		)
		(fp_rect
			(start -0.508 0.9398)
			(end 0.508 -0.9398)
			(stroke
				(width 0)
				(type default)
			)
			(fill no)
			(layer "F.CrtYd")
		)
		(fp_rect
			(start -0.508 0.9398)
			(end 0.508 -0.9398)
			(stroke
				(width 0)
				(type default)
			)
			(fill no)
			(layer "F.Fab")
		)
		(pad "1" smd custom
			(at 0 -0.4445 90)
			(size 0.1397 0.1397)
			(layers "F.Cu" "F.Mask" "F.Paste")
			(net "IOC_UART_0_TX_R")
			(options
				(clearance outline)
				(anchor circle)
			)
			(primitives
				(gr_poly
					(pts
						(arc
							(start -0.1778 -0.2794)
							(mid -0.249642 -0.249642)
							(end -0.2794 -0.1778)
						)
						(arc
							(start -0.2794 0.1778)
							(mid -0.249642 0.249642)
							(end -0.1778 0.2794)
						)
						(arc
							(start 0.1778 0.2794)
							(mid 0.249642 0.249642)
							(end 0.2794 0.1778)
						)
						(arc
							(start 0.2794 -0.1778)
							(mid 0.249642 -0.249642)
							(end 0.1778 -0.2794)
						)
					)
					(width 0)
					(fill yes)
				)
			)
		)
		(pad "2" smd custom
			(at 0 0.4445 90)
			(size 0.1397 0.1397)
			(layers "F.Cu" "F.Mask" "F.Paste")
			(net "IOC_UART_0_TX")
			(options
				(clearance outline)
				(anchor circle)
			)
			(primitives
				(gr_poly
					(pts
						(arc
							(start -0.1778 -0.2794)
							(mid -0.249642 -0.249642)
							(end -0.2794 -0.1778)
						)
						(arc
							(start -0.2794 0.1778)
							(mid -0.249642 0.249642)
							(end -0.1778 0.2794)
						)
						(arc
							(start 0.1778 0.2794)
							(mid 0.249642 0.249642)
							(end 0.2794 0.1778)
						)
						(arc
							(start 0.2794 -0.1778)
							(mid 0.249642 -0.249642)
							(end 0.1778 -0.2794)
						)
					)
					(width 0)
					(fill yes)
				)
			)
		)
	)
	(footprint ""
		(layer "F.Cu")
		(at 149.4282 -124.5616 -90)
		(property "Reference" "C676"
			(at 0 0 270)
			(layer "F.SilkS")
			(hide yes)
			(effects
				(font
					(size 1.27 1.27)
				)
			)
		)
		(property "Value" "SC68P50V2JN-2-GP"
			(at 1.1811 -2.7051 270)
			(unlocked yes)
			(layer "F.Fab")
			(hide yes)
			(effects
				(font
					(size 1.016 1.016)
					(thickness 0.1524)
				)
			)
		)
		(property "Device Type" "C402H22"
			(at 1.1811 -4.2291 270)
			(unlocked yes)
			(layer "F.Fab")
			(hide yes)
			(effects
				(font
					(size 1.016 1.016)
					(thickness 0.1524)
				)
			)
		)
		(duplicate_pad_numbers_are_jumpers no)
		(fp_rect
			(start -0.4318 0.9525)
			(end 0.4318 -0.9525)
			(stroke
				(width 0)
				(type default)
			)
			(fill no)
			(layer "F.CrtYd")
		)
		(fp_rect
			(start -0.4318 0.9525)
			(end 0.4318 -0.9525)
			(stroke
				(width 0)
				(type default)
			)
			(fill no)
			(layer "F.Fab")
		)
		(pad "1" smd custom
			(at 0 -0.4445 270)
			(size 0.1524 0.1524)
			(layers "F.Cu" "F.Mask" "F.Paste")
			(net "P1V5_E_VFB")
			(options
				(clearance outline)
				(anchor circle)
			)
			(primitives
				(gr_poly
					(pts
						(arc
							(start 0.3048 -0.2032)
							(mid 0.275042 -0.275042)
							(end 0.2032 -0.3048)
						)
						(arc
							(start -0.2032 -0.3048)
							(mid -0.275042 -0.275042)
							(end -0.3048 -0.2032)
						)
						(arc
							(start -0.3048 0.2032)
							(mid -0.275042 0.275042)
							(end -0.2032 0.3048)
						)
						(arc
							(start 0.2032 0.3048)
							(mid 0.275042 0.275042)
							(end 0.3048 0.2032)
						)
					)
					(width 0)
					(fill yes)
				)
			)
		)
		(pad "2" smd custom
			(at 0 0.4445 270)
			(size 0.1524 0.1524)
			(layers "F.Cu" "F.Mask" "F.Paste")
			(net "P1V5_E_VFB_R")
			(options
				(clearance outline)
				(anchor circle)
			)
			(primitives
				(gr_poly
					(pts
						(arc
							(start 0.3048 -0.2032)
							(mid 0.275042 -0.275042)
							(end 0.2032 -0.3048)
						)
						(arc
							(start -0.2032 -0.3048)
							(mid -0.275042 -0.275042)
							(end -0.3048 -0.2032)
						)
						(arc
							(start -0.3048 0.2032)
							(mid -0.275042 0.275042)
							(end -0.2032 0.3048)
						)
						(arc
							(start 0.2032 0.3048)
							(mid 0.275042 0.275042)
							(end 0.3048 0.2032)
						)
					)
					(width 0)
					(fill yes)
				)
			)
		)
	)
	(footprint ""
		(layer "F.Cu")
		(at 43.1292 -37.338)
		(property "Reference" "R440"
			(at 0 0 0)
			(layer "F.SilkS")
			(hide yes)
			(effects
				(font
					(size 1.27 1.27)
				)
			)
		)
		(property "Value" "2D2R3-1-U-GP"
			(at -0.0254 -2.5146 0)
			(unlocked yes)
			(layer "F.Fab")
			(hide yes)
			(effects
				(font
					(size 1.016 1.016)
					(thickness 0.1524)
				)
			)
		)
		(property "Device Type" "R603H22"
			(at -0.0254 -4.0386 0)
			(unlocked yes)
			(layer "F.Fab")
			(hide yes)
			(effects
				(font
					(size 1.016 1.016)
					(thickness 0.1524)
				)
			)
		)
		(duplicate_pad_numbers_are_jumpers no)
		(fp_line
			(start -0.4826 0)
			(end -0.2032 0)
			(stroke
				(width 0.2032)
				(type default)
			)
			(layer "F.SilkS")
		)
		(fp_line
			(start 0.2032 0)
			(end 0.4826 0)
			(stroke
				(width 0.2032)
				(type default)
			)
			(layer "F.SilkS")
		)
		(fp_rect
			(start -0.5842 1.3335)
			(end 0.5842 -1.3335)
			(stroke
				(width 0)
				(type default)
			)
			(fill no)
			(layer "F.CrtYd")
		)
		(fp_rect
			(start -0.5842 1.3335)
			(end 0.5842 -1.3335)
			(stroke
				(width 0)
				(type default)
			)
			(fill no)
			(layer "F.Fab")
		)
		(pad "1" smd custom
			(at 0 -0.762)
			(size 0.2159 0.2159)
			(layers "F.Cu" "F.Mask" "F.Paste")
			(net "P0V9_BST_R")
			(options
				(clearance outline)
				(anchor circle)
			)
			(primitives
				(gr_poly
					(pts
						(arc
							(start -0.3302 -0.4318)
							(mid -0.402042 -0.402042)
							(end -0.4318 -0.3302)
						)
						(arc
							(start -0.4318 0.3302)
							(mid -0.402042 0.402042)
							(end -0.3302 0.4318)
						)
						(arc
							(start 0.3302 0.4318)
							(mid 0.402042 0.402042)
							(end 0.4318 0.3302)
						)
						(arc
							(start 0.4318 -0.3302)
							(mid 0.402042 -0.402042)
							(end 0.3302 -0.4318)
						)
					)
					(width 0)
					(fill yes)
				)
			)
		)
		(pad "2" smd custom
			(at 0 0.762)
			(size 0.2159 0.2159)
			(layers "F.Cu" "F.Mask" "F.Paste")
			(net "P0V9_SW")
			(options
				(clearance outline)
				(anchor circle)
			)
			(primitives
				(gr_poly
					(pts
						(arc
							(start -0.3302 -0.4318)
							(mid -0.402042 -0.402042)
							(end -0.4318 -0.3302)
						)
						(arc
							(start -0.4318 0.3302)
							(mid -0.402042 0.402042)
							(end -0.3302 0.4318)
						)
						(arc
							(start 0.3302 0.4318)
							(mid 0.402042 0.402042)
							(end 0.4318 0.3302)
						)
						(arc
							(start 0.4318 -0.3302)
							(mid 0.402042 -0.402042)
							(end 0.3302 -0.4318)
						)
					)
					(width 0)
					(fill yes)
				)
			)
		)
	)
	(footprint ""
		(layer "F.Cu")
		(at 170.8912 -113.1316)
		(property "Reference" "C603"
			(at 0 0 0)
			(layer "F.SilkS")
			(hide yes)
			(effects
				(font
					(size 1.27 1.27)
				)
			)
		)
		(property "Value" "SC1U16V3KX-5GP"
			(at 0 -2.8194 0)
			(unlocked yes)
			(layer "F.Fab")
			(hide yes)
			(effects
				(font
					(size 1.016 1.016)
					(thickness 0.1524)
				)
			)
		)
		(property "Device Type" "C603H36"
			(at 0 -4.3434 0)
			(unlocked yes)
			(layer "F.Fab")
			(hide yes)
			(effects
				(font
					(size 1.016 1.016)
					(thickness 0.1524)
				)
			)
		)
		(duplicate_pad_numbers_are_jumpers no)
		(fp_line
			(start 0.508 0)
			(end -0.508 0)
			(stroke
				(width 0.2032)
				(type default)
			)
			(layer "F.SilkS")
		)
		(fp_rect
			(start -0.5842 1.3335)
			(end 0.5842 -1.3335)
			(stroke
				(width 0)
				(type default)
			)
			(fill no)
			(layer "F.CrtYd")
		)
		(fp_rect
			(start -0.5842 1.3335)
			(end 0.5842 -1.3335)
			(stroke
				(width 0)
				(type default)
			)
			(fill no)
			(layer "F.Fab")
		)
		(pad "1" smd custom
			(at 0 -0.762)
			(size 0.2159 0.2159)
			(layers "F.Cu" "F.Mask" "F.Paste")
			(net "P1V8_E_BIAS")
			(options
				(clearance outline)
				(anchor circle)
			)
			(primitives
				(gr_poly
					(pts
						(arc
							(start -0.3302 -0.4318)
							(mid -0.402042 -0.402042)
							(end -0.4318 -0.3302)
						)
						(arc
							(start -0.4318 0.3302)
							(mid -0.402042 0.402042)
							(end -0.3302 0.4318)
						)
						(arc
							(start 0.3302 0.4318)
							(mid 0.402042 0.402042)
							(end 0.4318 0.3302)
						)
						(arc
							(start 0.4318 -0.3302)
							(mid 0.402042 -0.402042)
							(end 0.3302 -0.4318)
						)
					)
					(width 0)
					(fill yes)
				)
			)
		)
		(pad "2" smd custom
			(at 0 0.762)
			(size 0.2159 0.2159)
			(layers "F.Cu" "F.Mask" "F.Paste")
			(net "GND")
			(options
				(clearance outline)
				(anchor circle)
			)
			(primitives
				(gr_poly
					(pts
						(arc
							(start -0.3302 -0.4318)
							(mid -0.402042 -0.402042)
							(end -0.4318 -0.3302)
						)
						(arc
							(start -0.4318 0.3302)
							(mid -0.402042 0.402042)
							(end -0.3302 0.4318)
						)
						(arc
							(start 0.3302 0.4318)
							(mid 0.402042 0.402042)
							(end 0.4318 0.3302)
						)
						(arc
							(start 0.4318 -0.3302)
							(mid 0.402042 -0.402042)
							(end 0.3302 -0.4318)
						)
					)
					(width 0)
					(fill yes)
				)
			)
		)
	)
	(footprint ""
		(layer "F.Cu")
		(at 69.181472 -96.0628 -90)
		(property "Reference" "R504"
			(at 0 0 270)
			(layer "F.SilkS")
			(hide yes)
			(effects
				(font
					(size 1.27 1.27)
				)
			)
		)
		(property "Value" "51KR2F-L-GP"
			(at 0.064008 -3.993896 270)
			(unlocked yes)
			(layer "F.Fab")
			(hide yes)
			(effects
				(font
					(size 1.016 1.016)
					(thickness 0.1524)
				)
			)
		)
		(property "Device Type" "R402H16"
			(at 0.064008 -5.517896 270)
			(unlocked yes)
			(layer "F.Fab")
			(hide yes)
			(effects
				(font
					(size 1.016 1.016)
					(thickness 0.1524)
				)
			)
		)
		(duplicate_pad_numbers_are_jumpers no)
		(fp_line
			(start -0.508 -0.9398)
			(end -0.508 0.9398)
			(stroke
				(width 0.1524)
				(type default)
			)
			(layer "F.SilkS")
		)
		(fp_line
			(start 0.508 -0.9398)
			(end -0.508 -0.9398)
			(stroke
				(width 0.1524)
				(type default)
			)
			(layer "F.SilkS")
		)
		(fp_rect
			(start -0.508 0.9398)
			(end 0.508 -0.9398)
			(stroke
				(width 0)
				(type default)
			)
			(fill no)
			(layer "F.CrtYd")
		)
		(fp_rect
			(start -0.508 0.9398)
			(end 0.508 -0.9398)
			(stroke
				(width 0)
				(type default)
			)
			(fill no)
			(layer "F.Fab")
		)
		(pad "1" smd custom
			(at 0 -0.4445 270)
			(size 0.1397 0.1397)
			(layers "F.Cu" "F.Mask" "F.Paste")
			(net "AGND_P3V3")
			(options
				(clearance outline)
				(anchor circle)
			)
			(primitives
				(gr_poly
					(pts
						(arc
							(start -0.1778 -0.2794)
							(mid -0.249642 -0.249642)
							(end -0.2794 -0.1778)
						)
						(arc
							(start -0.2794 0.1778)
							(mid -0.249642 0.249642)
							(end -0.1778 0.2794)
						)
						(arc
							(start 0.1778 0.2794)
							(mid 0.249642 0.249642)
							(end 0.2794 0.1778)
						)
						(arc
							(start 0.2794 -0.1778)
							(mid 0.249642 -0.249642)
							(end 0.1778 -0.2794)
						)
					)
					(width 0)
					(fill yes)
				)
			)
		)
		(pad "2" smd custom
			(at 0 0.4445 270)
			(size 0.1397 0.1397)
			(layers "F.Cu" "F.Mask" "F.Paste")
			(net "P3V3_TRIP")
			(options
				(clearance outline)
				(anchor circle)
			)
			(primitives
				(gr_poly
					(pts
						(arc
							(start -0.1778 -0.2794)
							(mid -0.249642 -0.249642)
							(end -0.2794 -0.1778)
						)
						(arc
							(start -0.2794 0.1778)
							(mid -0.249642 0.249642)
							(end -0.1778 0.2794)
						)
						(arc
							(start 0.1778 0.2794)
							(mid 0.249642 0.249642)
							(end 0.2794 0.1778)
						)
						(arc
							(start 0.2794 -0.1778)
							(mid 0.249642 -0.249642)
							(end 0.1778 -0.2794)
						)
					)
					(width 0)
					(fill yes)
				)
			)
		)
	)
	(footprint ""
		(layer "F.Cu")
		(at 61.7982 -91.1098 180)
		(property "Reference" "L28"
			(at 0 0 180)
			(layer "F.SilkS")
			(hide yes)
			(effects
				(font
					(size 1.27 1.27)
				)
			)
		)
		(property "Value" "BLM21PG220SN1DGP"
			(at 0.0254 -5.6896 180)
			(unlocked yes)
			(layer "F.Fab")
			(hide yes)
			(effects
				(font
					(size 1.016 1.016)
					(thickness 0.1524)
				)
			)
		)
		(property "Device Type" "L20125H42"
			(at 0.0254 -7.5946 180)
			(unlocked yes)
			(layer "F.Fab")
			(hide yes)
			(effects
				(font
					(size 1.016 1.016)
					(thickness 0.1524)
				)
			)
		)
		(duplicate_pad_numbers_are_jumpers no)
		(fp_line
			(start 0.9144 1.7018)
			(end 0.9144 -1.7018)
			(stroke
				(width 0.1524)
				(type default)
			)
			(layer "F.SilkS")
		)
		(fp_line
			(start 0.9144 -1.7018)
			(end -0.9144 -1.7018)
			(stroke
				(width 0.1524)
				(type default)
			)
			(layer "F.SilkS")
		)
		(fp_line
			(start -0.9144 1.7018)
			(end 0.9144 1.7018)
			(stroke
				(width 0.1524)
				(type default)
			)
			(layer "F.SilkS")
		)
		(fp_line
			(start -0.9144 -1.7018)
			(end -0.9144 1.7018)
			(stroke
				(width 0.1524)
				(type default)
			)
			(layer "F.SilkS")
		)
		(fp_rect
			(start -1.0033 1.778)
			(end 1.0033 -1.778)
			(stroke
				(width 0)
				(type default)
			)
			(fill no)
			(layer "F.CrtYd")
		)
		(fp_poly
			(pts
				(xy -1.0033 -1.778) (xy 1.0033 -1.778) (xy 1.0033 1.778) (xy -1.0033 1.778)
			)
			(stroke
				(width 0)
				(type default)
			)
			(fill no)
			(layer "F.Fab")
		)
		(pad "1" smd rect
			(at 0 -0.9652 180)
			(size 1.397 1.143)
			(layers "F.Cu" "F.Mask" "F.Paste")
			(net "P12V_STBY_SCC")
		)
		(pad "2" smd rect
			(at 0 0.9652 180)
			(size 1.397 1.143)
			(layers "F.Cu" "F.Mask" "F.Paste")
			(net "P12V_STBY_VIN_U10")
		)
	)
	(footprint ""
		(layer "F.Cu")
		(at 70.612 -57.023 90)
		(property "Reference" "R166"
			(at 0 0 90)
			(layer "F.SilkS")
			(hide yes)
			(effects
				(font
					(size 1.27 1.27)
				)
			)
		)
		(property "Value" "D51R3F-2-GP"
			(at -0.0254 -2.5146 90)
			(unlocked yes)
			(layer "F.Fab")
			(hide yes)
			(effects
				(font
					(size 1.016 1.016)
					(thickness 0.1524)
				)
			)
		)
		(property "Device Type" "R603H22"
			(at -0.0254 -4.0386 90)
			(unlocked yes)
			(layer "F.Fab")
			(hide yes)
			(effects
				(font
					(size 1.016 1.016)
					(thickness 0.1524)
				)
			)
		)
		(duplicate_pad_numbers_are_jumpers no)
		(fp_line
			(start 0.2032 0)
			(end 0.4826 0)
			(stroke
				(width 0.2032)
				(type default)
			)
			(layer "F.SilkS")
		)
		(fp_line
			(start -0.4826 0)
			(end -0.2032 0)
			(stroke
				(width 0.2032)
				(type default)
			)
			(layer "F.SilkS")
		)
		(fp_rect
			(start -0.5842 1.3335)
			(end 0.5842 -1.3335)
			(stroke
				(width 0)
				(type default)
			)
			(fill no)
			(layer "F.CrtYd")
		)
		(fp_rect
			(start -0.5842 1.3335)
			(end 0.5842 -1.3335)
			(stroke
				(width 0)
				(type default)
			)
			(fill no)
			(layer "F.Fab")
		)
		(pad "1" smd custom
			(at 0 -0.762 90)
			(size 0.2159 0.2159)
			(layers "F.Cu" "F.Mask" "F.Paste")
			(net "P0V9")
			(options
				(clearance outline)
				(anchor circle)
			)
			(primitives
				(gr_poly
					(pts
						(arc
							(start -0.3302 -0.4318)
							(mid -0.402042 -0.402042)
							(end -0.4318 -0.3302)
						)
						(arc
							(start -0.4318 0.3302)
							(mid -0.402042 0.402042)
							(end -0.3302 0.4318)
						)
						(arc
							(start 0.3302 0.4318)
							(mid 0.402042 0.402042)
							(end 0.4318 0.3302)
						)
						(arc
							(start 0.4318 -0.3302)
							(mid 0.402042 -0.402042)
							(end 0.3302 -0.4318)
						)
					)
					(width 0)
					(fill yes)
				)
			)
		)
		(pad "2" smd custom
			(at 0 0.762 90)
			(size 0.2159 0.2159)
			(layers "F.Cu" "F.Mask" "F.Paste")
			(net "GB_VDDA")
			(options
				(clearance outline)
				(anchor circle)
			)
			(primitives
				(gr_poly
					(pts
						(arc
							(start -0.3302 -0.4318)
							(mid -0.402042 -0.402042)
							(end -0.4318 -0.3302)
						)
						(arc
							(start -0.4318 0.3302)
							(mid -0.402042 0.402042)
							(end -0.3302 0.4318)
						)
						(arc
							(start 0.3302 0.4318)
							(mid 0.402042 0.402042)
							(end 0.4318 0.3302)
						)
						(arc
							(start 0.4318 -0.3302)
							(mid 0.402042 -0.402042)
							(end 0.3302 -0.4318)
						)
					)
					(width 0)
					(fill yes)
				)
			)
		)
	)
	(footprint ""
		(layer "F.Cu")
		(at 175.70069 -112.063784 90)
		(property "Reference" "C601"
			(at 0 0 90)
			(layer "F.SilkS")
			(hide yes)
			(effects
				(font
					(size 1.27 1.27)
				)
			)
		)
		(property "Value" "SCD1U16V2KX-3GP"
			(at 1.1811 -2.7051 90)
			(unlocked yes)
			(layer "F.Fab")
			(hide yes)
			(effects
				(font
					(size 1.016 1.016)
					(thickness 0.1524)
				)
			)
		)
		(property "Device Type" "C402H22"
			(at 1.1811 -4.2291 90)
			(unlocked yes)
			(layer "F.Fab")
			(hide yes)
			(effects
				(font
					(size 1.016 1.016)
					(thickness 0.1524)
				)
			)
		)
		(duplicate_pad_numbers_are_jumpers no)
		(fp_rect
			(start -0.4318 0.9525)
			(end 0.4318 -0.9525)
			(stroke
				(width 0)
				(type default)
			)
			(fill no)
			(layer "F.CrtYd")
		)
		(fp_rect
			(start -0.4318 0.9525)
			(end 0.4318 -0.9525)
			(stroke
				(width 0)
				(type default)
			)
			(fill no)
			(layer "F.Fab")
		)
		(pad "1" smd custom
			(at 0 -0.4445 90)
			(size 0.1524 0.1524)
			(layers "F.Cu" "F.Mask" "F.Paste")
			(net "P1V8_E_EN")
			(options
				(clearance outline)
				(anchor circle)
			)
			(primitives
				(gr_poly
					(pts
						(arc
							(start 0.3048 -0.2032)
							(mid 0.275042 -0.275042)
							(end 0.2032 -0.3048)
						)
						(arc
							(start -0.2032 -0.3048)
							(mid -0.275042 -0.275042)
							(end -0.3048 -0.2032)
						)
						(arc
							(start -0.3048 0.2032)
							(mid -0.275042 0.275042)
							(end -0.2032 0.3048)
						)
						(arc
							(start 0.2032 0.3048)
							(mid 0.275042 0.275042)
							(end 0.3048 0.2032)
						)
					)
					(width 0)
					(fill yes)
				)
			)
		)
		(pad "2" smd custom
			(at 0 0.4445 90)
			(size 0.1524 0.1524)
			(layers "F.Cu" "F.Mask" "F.Paste")
			(net "GND")
			(options
				(clearance outline)
				(anchor circle)
			)
			(primitives
				(gr_poly
					(pts
						(arc
							(start 0.3048 -0.2032)
							(mid 0.275042 -0.275042)
							(end 0.2032 -0.3048)
						)
						(arc
							(start -0.2032 -0.3048)
							(mid -0.275042 -0.275042)
							(end -0.3048 -0.2032)
						)
						(arc
							(start -0.3048 0.2032)
							(mid -0.275042 0.275042)
							(end -0.2032 0.3048)
						)
						(arc
							(start 0.2032 0.3048)
							(mid 0.275042 0.275042)
							(end 0.3048 0.2032)
						)
					)
					(width 0)
					(fill yes)
				)
			)
		)
	)
	(footprint ""
		(layer "F.Cu")
		(at 178.407314 -23.56104 90)
		(property "Reference" "VIA7"
			(at 0 0 90)
			(layer "F.SilkS")
			(hide yes)
			(effects
				(font
					(size 1.27 1.27)
				)
			)
		)
		(property "Value" "85OHM-8L-1D6MM-L16L18-GP"
			(at 4.064 0.6096 90)
			(unlocked yes)
			(layer "F.Fab")
			(hide yes)
			(effects
				(font
					(size 1.016 1.016)
					(thickness 0.1524)
				)
			)
		)
		(property "Device Type" "VIA-PCIE-4P-368076"
			(at 4.064 -0.9144 90)
			(unlocked yes)
			(layer "F.Fab")
			(hide yes)
			(effects
				(font
					(size 1.016 1.016)
					(thickness 0.1524)
				)
			)
		)
		(duplicate_pad_numbers_are_jumpers no)
		(fp_rect
			(start -1.8415 0.381)
			(end 1.8415 -0.381)
			(stroke
				(width 0)
				(type default)
			)
			(fill no)
			(layer "F.CrtYd")
		)
		(fp_rect
			(start -1.8415 0.381)
			(end 1.8415 -0.381)
			(stroke
				(width 0)
				(type default)
			)
			(fill no)
			(layer "F.Fab")
		)
		(pad "1" thru_hole circle
			(at -1.4605 0 90)
			(size 0.508 0.508)
			(drill 0.254)
			(layers "*.Cu" "*.Mask")
			(remove_unused_layers no)
			(net "GND")
			(clearance 0.127)
			(thermal_gap 0.127)
		)
		(pad "2" thru_hole circle
			(at -0.4445 0 90)
			(size 0.508 0.508)
			(drill 0.254)
			(layers "*.Cu" "*.Mask")
			(remove_unused_layers no)
			(net "PCIE_COMP_TO_SCC_6_DP")
			(clearance 0.127)
			(thermal_gap 0.127)
		)
		(pad "3" thru_hole circle
			(at 0.4445 0 90)
			(size 0.508 0.508)
			(drill 0.254)
			(layers "*.Cu" "*.Mask")
			(remove_unused_layers no)
			(net "PCIE_COMP_TO_SCC_6_DN")
			(clearance 0.127)
			(thermal_gap 0.127)
		)
		(pad "4" thru_hole circle
			(at 1.4605 0 90)
			(size 0.508 0.508)
			(drill 0.254)
			(layers "*.Cu" "*.Mask")
			(remove_unused_layers no)
			(net "GND")
			(clearance 0.127)
			(thermal_gap 0.127)
		)
	)
	(footprint ""
		(layer "F.Cu")
		(at 74.4728 -81.7118 90)
		(property "Reference" "R583"
			(at 0 0 90)
			(layer "F.SilkS")
			(hide yes)
			(effects
				(font
					(size 1.27 1.27)
				)
			)
		)
		(property "Value" "0R2J-2-GP"
			(at 0.064008 -3.993896 90)
			(unlocked yes)
			(layer "F.Fab")
			(hide yes)
			(effects
				(font
					(size 1.016 1.016)
					(thickness 0.1524)
				)
			)
		)
		(property "Device Type" "R402H16"
			(at 0.064008 -5.517896 90)
			(unlocked yes)
			(layer "F.Fab")
			(hide yes)
			(effects
				(font
					(size 1.016 1.016)
					(thickness 0.1524)
				)
			)
		)
		(duplicate_pad_numbers_are_jumpers no)
		(fp_line
			(start 0.508 -0.9398)
			(end -0.508 -0.9398)
			(stroke
				(width 0.1524)
				(type default)
			)
			(layer "F.SilkS")
		)
		(fp_line
			(start -0.508 -0.9398)
			(end -0.508 0.9398)
			(stroke
				(width 0.1524)
				(type default)
			)
			(layer "F.SilkS")
		)
		(fp_rect
			(start -0.508 0.9398)
			(end 0.508 -0.9398)
			(stroke
				(width 0)
				(type default)
			)
			(fill no)
			(layer "F.CrtYd")
		)
		(fp_rect
			(start -0.508 0.9398)
			(end 0.508 -0.9398)
			(stroke
				(width 0)
				(type default)
			)
			(fill no)
			(layer "F.Fab")
		)
		(pad "1" smd custom
			(at 0 -0.4445 90)
			(size 0.1397 0.1397)
			(layers "F.Cu" "F.Mask" "F.Paste")
			(net "P1V8_E")
			(options
				(clearance outline)
				(anchor circle)
			)
			(primitives
				(gr_poly
					(pts
						(arc
							(start -0.1778 -0.2794)
							(mid -0.249642 -0.249642)
							(end -0.2794 -0.1778)
						)
						(arc
							(start -0.2794 0.1778)
							(mid -0.249642 0.249642)
							(end -0.1778 0.2794)
						)
						(arc
							(start 0.1778 0.2794)
							(mid 0.249642 0.249642)
							(end 0.2794 0.1778)
						)
						(arc
							(start 0.2794 -0.1778)
							(mid 0.249642 -0.249642)
							(end 0.1778 -0.2794)
						)
					)
					(width 0)
					(fill yes)
				)
			)
		)
		(pad "2" smd custom
			(at 0 0.4445 90)
			(size 0.1397 0.1397)
			(layers "F.Cu" "F.Mask" "F.Paste")
			(net "U118_VCC")
			(options
				(clearance outline)
				(anchor circle)
			)
			(primitives
				(gr_poly
					(pts
						(arc
							(start -0.1778 -0.2794)
							(mid -0.249642 -0.249642)
							(end -0.2794 -0.1778)
						)
						(arc
							(start -0.2794 0.1778)
							(mid -0.249642 0.249642)
							(end -0.1778 0.2794)
						)
						(arc
							(start 0.1778 0.2794)
							(mid 0.249642 0.249642)
							(end 0.2794 0.1778)
						)
						(arc
							(start 0.2794 -0.1778)
							(mid 0.249642 -0.249642)
							(end 0.1778 -0.2794)
						)
					)
					(width 0)
					(fill yes)
				)
			)
		)
	)
	(footprint ""
		(layer "F.Cu")
		(at 192.401952 -76.037694)
		(property "Reference" "C535"
			(at 0 0 0)
			(layer "F.SilkS")
			(hide yes)
			(effects
				(font
					(size 1.27 1.27)
				)
			)
		)
		(property "Value" "SCD1U16V2KX-3GP"
			(at 1.1811 -2.7051 0)
			(unlocked yes)
			(layer "F.Fab")
			(hide yes)
			(effects
				(font
					(size 1.016 1.016)
					(thickness 0.1524)
				)
			)
		)
		(property "Device Type" "C402H22"
			(at 1.1811 -4.2291 0)
			(unlocked yes)
			(layer "F.Fab")
			(hide yes)
			(effects
				(font
					(size 1.016 1.016)
					(thickness 0.1524)
				)
			)
		)
		(duplicate_pad_numbers_are_jumpers no)
		(fp_rect
			(start -0.4318 0.9525)
			(end 0.4318 -0.9525)
			(stroke
				(width 0)
				(type default)
			)
			(fill no)
			(layer "F.CrtYd")
		)
		(fp_rect
			(start -0.4318 0.9525)
			(end 0.4318 -0.9525)
			(stroke
				(width 0)
				(type default)
			)
			(fill no)
			(layer "F.Fab")
		)
		(pad "1" smd custom
			(at 0 -0.4445)
			(size 0.1524 0.1524)
			(layers "F.Cu" "F.Mask" "F.Paste")
			(net "GND")
			(options
				(clearance outline)
				(anchor circle)
			)
			(primitives
				(gr_poly
					(pts
						(arc
							(start 0.3048 -0.2032)
							(mid 0.275042 -0.275042)
							(end 0.2032 -0.3048)
						)
						(arc
							(start -0.2032 -0.3048)
							(mid -0.275042 -0.275042)
							(end -0.3048 -0.2032)
						)
						(arc
							(start -0.3048 0.2032)
							(mid -0.275042 0.275042)
							(end -0.2032 0.3048)
						)
						(arc
							(start 0.2032 0.3048)
							(mid 0.275042 0.275042)
							(end 0.3048 0.2032)
						)
					)
					(width 0)
					(fill yes)
				)
			)
		)
		(pad "2" smd custom
			(at 0 0.4445)
			(size 0.1524 0.1524)
			(layers "F.Cu" "F.Mask" "F.Paste")
			(net "P3V3")
			(options
				(clearance outline)
				(anchor circle)
			)
			(primitives
				(gr_poly
					(pts
						(arc
							(start 0.3048 -0.2032)
							(mid 0.275042 -0.275042)
							(end 0.2032 -0.3048)
						)
						(arc
							(start -0.2032 -0.3048)
							(mid -0.275042 -0.275042)
							(end -0.3048 -0.2032)
						)
						(arc
							(start -0.3048 0.2032)
							(mid -0.275042 0.275042)
							(end -0.2032 0.3048)
						)
						(arc
							(start 0.2032 0.3048)
							(mid 0.275042 0.275042)
							(end 0.3048 0.2032)
						)
					)
					(width 0)
					(fill yes)
				)
			)
		)
	)
	(footprint ""
		(layer "F.Cu")
		(at 70.485 -60.833 90)
		(property "Reference" "L12"
			(at 0 0 90)
			(layer "F.SilkS")
			(hide yes)
			(effects
				(font
					(size 1.27 1.27)
				)
			)
		)
		(property "Value" "MPZ2012S300AT-GP"
			(at 0 -4.2418 90)
			(unlocked yes)
			(layer "F.Fab")
			(hide yes)
			(effects
				(font
					(size 1.016 1.016)
					(thickness 0.1524)
				)
			)
		)
		(property "Device Type" "L805H42"
			(at 0 -5.7912 90)
			(unlocked yes)
			(layer "F.Fab")
			(hide yes)
			(effects
				(font
					(size 1.016 1.016)
					(thickness 0.1524)
				)
			)
		)
		(duplicate_pad_numbers_are_jumpers no)
		(fp_line
			(start 0.889 -1.7018)
			(end 0.889 1.7018)
			(stroke
				(width 0.1524)
				(type default)
			)
			(layer "F.SilkS")
		)
		(fp_line
			(start -0.889 -1.7018)
			(end 0.889 -1.7018)
			(stroke
				(width 0.1524)
				(type default)
			)
			(layer "F.SilkS")
		)
		(fp_line
			(start 0.889 1.7018)
			(end -0.889 1.7018)
			(stroke
				(width 0.1524)
				(type default)
			)
			(layer "F.SilkS")
		)
		(fp_line
			(start -0.889 1.7018)
			(end -0.889 -1.7018)
			(stroke
				(width 0.1524)
				(type default)
			)
			(layer "F.SilkS")
		)
		(fp_rect
			(start -0.9652 1.778)
			(end 0.9652 -1.778)
			(stroke
				(width 0)
				(type default)
			)
			(fill no)
			(layer "F.CrtYd")
		)
		(fp_rect
			(start -0.9652 1.778)
			(end 0.9652 -1.778)
			(stroke
				(width 0)
				(type default)
			)
			(fill no)
			(layer "F.Fab")
		)
		(pad "1" smd rect
			(at 0 -0.9652 90)
			(size 1.397 1.143)
			(layers "F.Cu" "F.Mask" "F.Paste")
			(net "P0V9")
		)
		(pad "2" smd rect
			(at 0 0.9652 90)
			(size 1.397 1.143)
			(layers "F.Cu" "F.Mask" "F.Paste")
			(net "GB_VDDA")
		)
	)
	(footprint ""
		(layer "F.Cu")
		(at 134.52221 -85.262466 -90)
		(property "Reference" "R62"
			(at 0 0 270)
			(layer "F.SilkS")
			(hide yes)
			(effects
				(font
					(size 1.27 1.27)
				)
			)
		)
		(property "Value" "1KR2F-3-GP"
			(at 0.064008 -3.993896 270)
			(unlocked yes)
			(layer "F.Fab")
			(hide yes)
			(effects
				(font
					(size 1.016 1.016)
					(thickness 0.1524)
				)
			)
		)
		(property "Device Type" "R402H16"
			(at 0.064008 -5.517896 270)
			(unlocked yes)
			(layer "F.Fab")
			(hide yes)
			(effects
				(font
					(size 1.016 1.016)
					(thickness 0.1524)
				)
			)
		)
		(duplicate_pad_numbers_are_jumpers no)
		(fp_line
			(start -0.508 -0.9398)
			(end -0.508 0.9398)
			(stroke
				(width 0.1524)
				(type default)
			)
			(layer "F.SilkS")
		)
		(fp_line
			(start 0.508 -0.9398)
			(end -0.508 -0.9398)
			(stroke
				(width 0.1524)
				(type default)
			)
			(layer "F.SilkS")
		)
		(fp_rect
			(start -0.508 0.9398)
			(end 0.508 -0.9398)
			(stroke
				(width 0)
				(type default)
			)
			(fill no)
			(layer "F.CrtYd")
		)
		(fp_rect
			(start -0.508 0.9398)
			(end 0.508 -0.9398)
			(stroke
				(width 0)
				(type default)
			)
			(fill no)
			(layer "F.Fab")
		)
		(pad "1" smd custom
			(at 0 -0.4445 270)
			(size 0.1397 0.1397)
			(layers "F.Cu" "F.Mask" "F.Paste")
			(net "P1V8_E")
			(options
				(clearance outline)
				(anchor circle)
			)
			(primitives
				(gr_poly
					(pts
						(arc
							(start -0.1778 -0.2794)
							(mid -0.249642 -0.249642)
							(end -0.2794 -0.1778)
						)
						(arc
							(start -0.2794 0.1778)
							(mid -0.249642 0.249642)
							(end -0.1778 0.2794)
						)
						(arc
							(start 0.1778 0.2794)
							(mid 0.249642 0.249642)
							(end 0.2794 0.1778)
						)
						(arc
							(start 0.2794 -0.1778)
							(mid 0.249642 -0.249642)
							(end 0.1778 -0.2794)
						)
					)
					(width 0)
					(fill yes)
				)
			)
		)
		(pad "2" smd custom
			(at 0 0.4445 270)
			(size 0.1397 0.1397)
			(layers "F.Cu" "F.Mask" "F.Paste")
			(net "I2C_EXP_IOC_SCL8")
			(options
				(clearance outline)
				(anchor circle)
			)
			(primitives
				(gr_poly
					(pts
						(arc
							(start -0.1778 -0.2794)
							(mid -0.249642 -0.249642)
							(end -0.2794 -0.1778)
						)
						(arc
							(start -0.2794 0.1778)
							(mid -0.249642 0.249642)
							(end -0.1778 0.2794)
						)
						(arc
							(start 0.1778 0.2794)
							(mid 0.249642 0.249642)
							(end 0.2794 0.1778)
						)
						(arc
							(start 0.2794 -0.1778)
							(mid 0.249642 -0.249642)
							(end 0.1778 -0.2794)
						)
					)
					(width 0)
					(fill yes)
				)
			)
		)
	)
	(footprint ""
		(layer "F.Cu")
		(at 63.700914 -17.126458 180)
		(property "Reference" "R75"
			(at 0 0 180)
			(layer "F.SilkS")
			(hide yes)
			(effects
				(font
					(size 1.27 1.27)
				)
			)
		)
		(property "Value" "0R2J-2-GP"
			(at 0.064008 -3.993896 180)
			(unlocked yes)
			(layer "F.Fab")
			(hide yes)
			(effects
				(font
					(size 1.016 1.016)
					(thickness 0.1524)
				)
			)
		)
		(property "Device Type" "R402H16"
			(at 0.064008 -5.517896 180)
			(unlocked yes)
			(layer "F.Fab")
			(hide yes)
			(effects
				(font
					(size 1.016 1.016)
					(thickness 0.1524)
				)
			)
		)
		(duplicate_pad_numbers_are_jumpers no)
		(fp_line
			(start 0.508 -0.9398)
			(end -0.508 -0.9398)
			(stroke
				(width 0.1524)
				(type default)
			)
			(layer "F.SilkS")
		)
		(fp_line
			(start -0.508 -0.9398)
			(end -0.508 0.9398)
			(stroke
				(width 0.1524)
				(type default)
			)
			(layer "F.SilkS")
		)
		(fp_rect
			(start -0.508 0.9398)
			(end 0.508 -0.9398)
			(stroke
				(width 0)
				(type default)
			)
			(fill no)
			(layer "F.CrtYd")
		)
		(fp_rect
			(start -0.508 0.9398)
			(end 0.508 -0.9398)
			(stroke
				(width 0)
				(type default)
			)
			(fill no)
			(layer "F.Fab")
		)
		(pad "1" smd custom
			(at 0 -0.4445 180)
			(size 0.1397 0.1397)
			(layers "F.Cu" "F.Mask" "F.Paste")
			(net "LS_EN_U14")
			(options
				(clearance outline)
				(anchor circle)
			)
			(primitives
				(gr_poly
					(pts
						(arc
							(start -0.1778 -0.2794)
							(mid -0.249642 -0.249642)
							(end -0.2794 -0.1778)
						)
						(arc
							(start -0.2794 0.1778)
							(mid -0.249642 0.249642)
							(end -0.1778 0.2794)
						)
						(arc
							(start 0.1778 0.2794)
							(mid 0.249642 0.249642)
							(end 0.2794 0.1778)
						)
						(arc
							(start 0.2794 -0.1778)
							(mid 0.249642 -0.249642)
							(end 0.1778 -0.2794)
						)
					)
					(width 0)
					(fill yes)
				)
			)
		)
		(pad "2" smd custom
			(at 0 0.4445 180)
			(size 0.1397 0.1397)
			(layers "F.Cu" "F.Mask" "F.Paste")
			(net "LS_EN_N")
			(options
				(clearance outline)
				(anchor circle)
			)
			(primitives
				(gr_poly
					(pts
						(arc
							(start -0.1778 -0.2794)
							(mid -0.249642 -0.249642)
							(end -0.2794 -0.1778)
						)
						(arc
							(start -0.2794 0.1778)
							(mid -0.249642 0.249642)
							(end -0.1778 0.2794)
						)
						(arc
							(start 0.1778 0.2794)
							(mid 0.249642 0.249642)
							(end 0.2794 0.1778)
						)
						(arc
							(start 0.2794 -0.1778)
							(mid 0.249642 -0.249642)
							(end 0.1778 -0.2794)
						)
					)
					(width 0)
					(fill yes)
				)
			)
		)
	)
	(footprint ""
		(layer "F.Cu")
		(at 36.999926 -5.029962)
		(property "Reference" "CN1"
			(at 0 0 0)
			(layer "F.SilkS")
			(hide yes)
			(effects
				(font
					(size 1.27 1.27)
				)
			)
		)
		(property "Value" "AMP-CONN12-2R-2-GP"
			(at -22.010116 -12.120118 0)
			(unlocked yes)
			(layer "F.Fab")
			(hide yes)
			(effects
				(font
					(size 1.016 1.016)
					(thickness 0.1524)
				)
			)
		)
		(property "Device Type" "PREFIT-12P-162281H396"
			(at -22.010116 -13.644118 0)
			(unlocked yes)
			(layer "F.Fab")
			(hide yes)
			(effects
				(font
					(size 1.016 1.016)
					(thickness 0.1524)
				)
			)
		)
		(duplicate_pad_numbers_are_jumpers no)
		(fp_line
			(start -11.2522 -11.1506)
			(end -11.2522 5.029962)
			(stroke
				(width 0.1524)
				(type default)
			)
			(layer "F.SilkS")
		)
		(fp_line
			(start -11.2522 5.029962)
			(end 5.4356 5.029962)
			(stroke
				(width 0.1524)
				(type default)
			)
			(layer "F.SilkS")
		)
		(fp_line
			(start 5.4356 -11.1506)
			(end -11.2522 -11.1506)
			(stroke
				(width 0.1524)
				(type default)
			)
			(layer "F.SilkS")
		)
		(fp_line
			(start 5.4356 5.029962)
			(end 5.4356 -11.1506)
			(stroke
				(width 0.1524)
				(type default)
			)
			(layer "F.SilkS")
		)
		(fp_poly
			(pts
				(arc
					(start 0.259588 2.049272)
					(mid 0.005588 2.303272)
					(end -0.248412 2.049272)
				)
				(arc
					(start -0.248412 1.287272)
					(mid 0.005588 1.033272)
					(end 0.259588 1.287272)
				)
			)
			(stroke
				(width 0)
				(type default)
			)
			(fill yes)
			(layer "F.SilkS")
		)
		(fp_poly
			(pts
				(arc
					(start 3.510788 2.049272)
					(mid 3.256788 2.303272)
					(end 3.002788 2.049272)
				)
				(arc
					(start 3.002788 1.287272)
					(mid 3.256788 1.033272)
					(end 3.510788 1.287272)
				)
			)
			(stroke
				(width 0)
				(type default)
			)
			(fill yes)
			(layer "F.SilkS")
		)
		(fp_poly
			(pts
				(xy -11.2522 5.029962) (xy -11.2522 -11.1506) (xy -5.3086 -11.1506) (xy -5.3086 -9.312656) (xy -0.8128 -9.312656)
				(xy -0.8128 -4.9784)
				(arc
					(start -5.98551 -4.9784)
					(mid -9.0527 -4.788153)
					(end -5.984748 -4.9657)
				)
				(xy -0.8128 -4.9657) (xy -0.8128 0.6477)
				(arc
					(start -6.185662 0.6477)
					(mid -8.862964 1.994161)
					(end -6.179312 0.6604)
				)
				(xy -0.8128 0.6604) (xy -0.8128 0.8128) (xy -0.4445 0.8128) (xy -0.4445 2.4257) (xy 3.683 2.4257)
				(xy 3.683 0.8128) (xy 4.012692 0.8128) (xy 4.012692 -9.312656) (xy 5.4356 -9.312656) (xy 5.4356 5.029962)
			)
			(stroke
				(width 0)
				(type default)
			)
			(fill yes)
			(layer "F.SilkS")
		)
		(fp_rect
			(start -5.6134 5.6134)
			(end 8.8138 -14.1224)
			(stroke
				(width 0)
				(type default)
			)
			(fill no)
			(layer "B.CrtYd")
		)
		(fp_rect
			(start -10.9982 17.1958)
			(end 5.1816 -10.8966)
			(stroke
				(width 0)
				(type default)
			)
			(fill no)
			(layer "F.CrtYd")
		)
		(fp_poly
			(pts
				(xy -16.002 22.1996) (xy -16.002 -15.9004) (xy 10.1854 -15.9004) (xy 10.1854 -0.00635) (xy 5.6896 -0.00635)
				(xy 5.6896 -11.4046) (xy -11.5062 -11.4046) (xy -11.5062 17.7038) (xy 5.6896 17.7038) (xy 5.6896 0.00635)
				(xy 10.1854 0.00635) (xy 10.1854 22.1996)
			)
			(stroke
				(width 0)
				(type default)
			)
			(fill no)
			(layer "F.CrtYd")
		)
		(fp_poly
			(pts
				(xy -11.5062 17.7038) (xy -11.5062 -11.4046) (xy 5.6896 -11.4046) (xy 5.6896 -0.00635) (xy 5.1816 -0.00635)
				(xy 5.1816 -10.8966) (xy -10.9982 -10.8966) (xy -10.9982 17.1958) (xy 5.1816 17.1958) (xy 5.1816 0.00635)
				(xy 5.6896 0.00635) (xy 5.6896 17.7038)
			)
			(stroke
				(width 0)
				(type default)
			)
			(fill no)
			(layer "F.CrtYd")
		)
		(fp_rect
			(start -10.6172 10.6172)
			(end 13.8176 -19.1262)
			(stroke
				(width 0)
				(type default)
			)
			(fill no)
			(layer "B.Fab")
		)
		(fp_rect
			(start -5.6134 5.6134)
			(end 8.8138 -14.1224)
			(stroke
				(width 0)
				(type default)
			)
			(fill no)
			(layer "B.Fab")
		)
		(fp_rect
			(start -21.0058 27.2034)
			(end 15.1892 -20.9042)
			(stroke
				(width 0)
				(type default)
			)
			(fill no)
			(layer "F.Fab")
		)
		(fp_rect
			(start -16.002 22.1996)
			(end 10.1854 -15.9004)
			(stroke
				(width 0)
				(type default)
			)
			(fill no)
			(layer "F.Fab")
		)
		(fp_rect
			(start -11.5062 17.7038)
			(end 5.6896 -11.4046)
			(stroke
				(width 0)
				(type default)
			)
			(fill no)
			(layer "F.Fab")
		)
		(fp_text user "Press fit"
			(at -5.0546 -10.1854 0)
			(unlocked yes)
			(layer "F.SilkS")
			(effects
				(font
					(size 1.016 1.016)
					(thickness 0.1524)
				)
				(justify left)
			)
		)
		(fp_text user "Slit"
			(at -4.868926 6.985762 0)
			(unlocked yes)
			(layer "F.SilkS")
			(effects
				(font
					(size 1.016 1.016)
					(thickness 0.1524)
				)
				(justify left)
			)
		)
		(fp_text user "Can not place BGA,CSP,Wave Solder Component"
			(at -28.482798 9.450578 0)
			(unlocked yes)
			(layer "B.Fab")
			(effects
				(font
					(size 1.016 1.016)
					(thickness 0.1524)
				)
				(justify left)
			)
		)
		(fp_text user "Can not place BGA,CSP,Wave Solder Component"
			(at -27.338528 25.206452 0)
			(unlocked yes)
			(layer "F.Fab")
			(effects
				(font
					(size 1.016 1.016)
					(thickness 0.1524)
				)
				(justify left)
			)
		)
		(fp_text user "High Limt 2mm"
			(at -10.438638 20.365212 0)
			(unlocked yes)
			(layer "F.Fab")
			(effects
				(font
					(size 1.016 1.016)
					(thickness 0.1524)
				)
				(justify left)
			)
		)
		(pad "" np_thru_hole circle
			(at -7.519924 -4.895088)
			(size 0.254 0.254)
			(drill 2.4638)
			(layers "*.Cu" "*.Mask")
			(clearance 1.4605)
			(thermal_gap 1.4605)
		)
		(pad "" np_thru_hole circle
			(at -7.519924 1.329944)
			(size 0.254 0.254)
			(drill 2.3876)
			(layers "*.Cu" "*.Mask")
			(clearance 1.4224)
			(thermal_gap 1.4224)
		)
		(pad "A1" thru_hole circle
			(at 0 0)
			(size 1.2192 1.2192)
			(drill 0.739902)
			(layers "*.Cu" "*.Mask")
			(remove_unused_layers no)
			(net "P12V_MAIN")
			(clearance 0.127)
			(thermal_gap 0.127)
		)
		(pad "A2" thru_hole oval
			(at 0 -1.49987)
			(size 1.2192 4.2164)
			(drill 0.739902)
			(layers "*.Cu" "*.Mask")
			(remove_unused_layers no)
			(net "P12V_MAIN")
			(clearance 0.127)
			(thermal_gap 0.127)
			(padstack
				(mode front_inner_back)
				(layer "Inner"
					(shape circle)
					(size 1.2192 1.2192)
					(clearance 0.127)
				)
				(layer "B.Cu"
					(shape circle)
					(size 1.2192 1.2192)
					(clearance 0.127)
				)
			)
		)
		(pad "A3" thru_hole circle
			(at 0 -2.999994)
			(size 1.2192 1.2192)
			(drill 0.739902)
			(layers "*.Cu" "*.Mask")
			(remove_unused_layers no)
			(net "P12V_MAIN")
			(clearance 0.127)
			(thermal_gap 0.127)
		)
		(pad "A4" thru_hole circle
			(at 0 -5.499862)
			(size 1.2192 1.2192)
			(drill 0.739902)
			(layers "*.Cu" "*.Mask")
			(remove_unused_layers no)
			(net "P12V_MAIN")
			(clearance 0.127)
			(thermal_gap 0.127)
		)
		(pad "A5" thru_hole oval
			(at 0 -6.999986)
			(size 1.2192 4.2164)
			(drill 0.739902)
			(layers "*.Cu" "*.Mask")
			(remove_unused_layers no)
			(net "P12V_MAIN")
			(clearance 0.127)
			(thermal_gap 0.127)
			(padstack
				(mode front_inner_back)
				(layer "Inner"
					(shape circle)
					(size 1.2192 1.2192)
					(clearance 0.127)
				)
				(layer "B.Cu"
					(shape circle)
					(size 1.2192 1.2192)
					(clearance 0.127)
				)
			)
		)
		(pad "A6" thru_hole circle
			(at 0 -8.499856)
			(size 1.2192 1.2192)
			(drill 0.739902)
			(layers "*.Cu" "*.Mask")
			(remove_unused_layers no)
			(net "P12V_MAIN")
			(clearance 0.127)
			(thermal_gap 0.127)
		)
		(pad "B1" thru_hole circle
			(at 3.199892 0)
			(size 1.2192 1.2192)
			(drill 0.739902)
			(layers "*.Cu" "*.Mask")
			(remove_unused_layers no)
			(net "GND")
			(clearance 0.127)
			(thermal_gap 0.127)
		)
		(pad "B2" thru_hole oval
			(at 3.199892 -1.49987)
			(size 1.2192 4.2164)
			(drill 0.739902)
			(layers "*.Cu" "*.Mask")
			(remove_unused_layers no)
			(net "GND")
			(clearance 0.127)
			(thermal_gap 0.127)
			(padstack
				(mode front_inner_back)
				(layer "Inner"
					(shape circle)
					(size 1.2192 1.2192)
					(clearance 0.127)
				)
				(layer "B.Cu"
					(shape circle)
					(size 1.2192 1.2192)
					(clearance 0.127)
				)
			)
		)
		(pad "B3" thru_hole circle
			(at 3.199892 -2.999994)
			(size 1.2192 1.2192)
			(drill 0.739902)
			(layers "*.Cu" "*.Mask")
			(remove_unused_layers no)
			(net "GND")
			(clearance 0.127)
			(thermal_gap 0.127)
		)
		(pad "B4" thru_hole circle
			(at 3.199892 -5.499862)
			(size 1.2192 1.2192)
			(drill 0.739902)
			(layers "*.Cu" "*.Mask")
			(remove_unused_layers no)
			(net "GND")
			(clearance 0.127)
			(thermal_gap 0.127)
		)
		(pad "B5" thru_hole oval
			(at 3.199892 -6.999986)
			(size 1.2192 4.2164)
			(drill 0.739902)
			(layers "*.Cu" "*.Mask")
			(remove_unused_layers no)
			(net "GND")
			(clearance 0.127)
			(thermal_gap 0.127)
			(padstack
				(mode front_inner_back)
				(layer "Inner"
					(shape circle)
					(size 1.2192 1.2192)
					(clearance 0.127)
				)
				(layer "B.Cu"
					(shape circle)
					(size 1.2192 1.2192)
					(clearance 0.127)
				)
			)
		)
		(pad "B6" thru_hole circle
			(at 3.199892 -8.499856)
			(size 1.2192 1.2192)
			(drill 0.739902)
			(layers "*.Cu" "*.Mask")
			(remove_unused_layers no)
			(net "GND")
			(clearance 0.127)
			(thermal_gap 0.127)
		)
		(zone
			(layer "F.Cu")
			(hatch none 0.5)
			(connect_pads
				(clearance 0)
			)
			(min_thickness 0.25)
			(keepout
				(tracks allowed)
				(vias not_allowed)
				(pads allowed)
				(copperpour not_allowed)
				(footprints allowed)
			)
			(placement
				(enabled no)
				(sheetname "")
			)
			(fill
				(thermal_gap 0.5)
				(thermal_bridge_width 0.5)
				(island_removal_mode 0)
			)
			(polygon
				(pts
					(xy 26.159968 0) (xy 32.759904 0) (xy 32.759904 -15.929864) (xy 26.159968 -15.929864)
				)
			)
		)
		(zone
			(layer "F.Cu")
			(hatch none 0.5)
			(connect_pads
				(clearance 0)
			)
			(min_thickness 0.25)
			(keepout
				(tracks not_allowed)
				(vias allowed)
				(pads allowed)
				(copperpour not_allowed)
				(footprints allowed)
			)
			(placement
				(enabled no)
				(sheetname "")
			)
			(fill
				(thermal_gap 0.5)
				(thermal_bridge_width 0.5)
				(island_removal_mode 0)
			)
			(polygon
				(pts
					(xy 26.159968 0) (xy 32.759904 0) (xy 32.759904 -15.929864) (xy 26.159968 -15.929864)
				)
			)
		)
		(zone
			(layer "F.Cu")
			(hatch none 0.5)
			(connect_pads
				(clearance 0)
			)
			(min_thickness 0.25)
			(keepout
				(tracks allowed)
				(vias not_allowed)
				(pads allowed)
				(copperpour not_allowed)
				(footprints allowed)
			)
			(placement
				(enabled no)
				(sheetname "")
			)
			(fill
				(thermal_gap 0.5)
				(thermal_bridge_width 0.5)
				(island_removal_mode 0)
			)
			(polygon
				(pts
					(xy 36.150042 -14.379956) (xy 36.150042 -4.180078) (xy 41.049956 -4.180078) (xy 41.049956 -14.379956)
				)
			)
		)
		(zone
			(layer "F.Cu")
			(hatch none 0.5)
			(connect_pads
				(clearance 0)
			)
			(min_thickness 0.25)
			(keepout
				(tracks not_allowed)
				(vias allowed)
				(pads allowed)
				(copperpour not_allowed)
				(footprints allowed)
			)
			(placement
				(enabled no)
				(sheetname "")
			)
			(fill
				(thermal_gap 0.5)
				(thermal_bridge_width 0.5)
				(island_removal_mode 0)
			)
			(polygon
				(pts
					(xy 36.150042 -4.180078) (xy 41.049956 -4.180078) (xy 41.049956 -14.379956) (xy 36.150042 -14.379956)
				)
			)
		)
		(zone
			(layers "F.Cu" "B.Cu" "In1.Cu" "In2.Cu" "In3.Cu" "In4.Cu" "In5.Cu" "In6.Cu")
			(hatch none 0.5)
			(connect_pads
				(clearance 0)
			)
			(min_thickness 0.25)
			(keepout
				(tracks not_allowed)
				(vias allowed)
				(pads allowed)
				(copperpour not_allowed)
				(footprints allowed)
			)
			(placement
				(enabled no)
				(sheetname "")
			)
			(fill
				(thermal_gap 0.5)
				(thermal_bridge_width 0.5)
				(island_removal_mode 0)
			)
			(polygon
				(pts
					(arc
						(start 30.978602 -3.700018)
						(mid 27.981402 -3.700018)
						(end 30.978602 -3.700018)
					)
				)
			)
		)
		(zone
			(layers "F.Cu" "B.Cu" "In1.Cu" "In2.Cu" "In3.Cu" "In4.Cu" "In5.Cu" "In6.Cu")
			(hatch none 0.5)
			(connect_pads
				(clearance 0)
			)
			(min_thickness 0.25)
			(keepout
				(tracks not_allowed)
				(vias allowed)
				(pads allowed)
				(copperpour not_allowed)
				(footprints allowed)
			)
			(placement
				(enabled no)
				(sheetname "")
			)
			(fill
				(thermal_gap 0.5)
				(thermal_bridge_width 0.5)
				(island_removal_mode 0)
			)
			(polygon
				(pts
					(arc
						(start 31.016702 -9.92505)
						(mid 27.943302 -9.92505)
						(end 31.016702 -9.92505)
					)
				)
			)
		)
	)
	(footprint ""
		(layer "F.Cu")
		(at 68.9864 -72.6948)
		(property "Reference" "R427"
			(at 0 0 0)
			(layer "F.SilkS")
			(hide yes)
			(effects
				(font
					(size 1.27 1.27)
				)
			)
		)
		(property "Value" "200KR2F-L-GP"
			(at 0.064008 -3.993896 0)
			(unlocked yes)
			(layer "F.Fab")
			(hide yes)
			(effects
				(font
					(size 1.016 1.016)
					(thickness 0.1524)
				)
			)
		)
		(property "Device Type" "R402H16"
			(at 0.064008 -5.517896 0)
			(unlocked yes)
			(layer "F.Fab")
			(hide yes)
			(effects
				(font
					(size 1.016 1.016)
					(thickness 0.1524)
				)
			)
		)
		(duplicate_pad_numbers_are_jumpers no)
		(fp_line
			(start -0.508 -0.9398)
			(end -0.508 0.9398)
			(stroke
				(width 0.1524)
				(type default)
			)
			(layer "F.SilkS")
		)
		(fp_line
			(start 0.508 -0.9398)
			(end -0.508 -0.9398)
			(stroke
				(width 0.1524)
				(type default)
			)
			(layer "F.SilkS")
		)
		(fp_rect
			(start -0.508 0.9398)
			(end 0.508 -0.9398)
			(stroke
				(width 0)
				(type default)
			)
			(fill no)
			(layer "F.CrtYd")
		)
		(fp_rect
			(start -0.508 0.9398)
			(end 0.508 -0.9398)
			(stroke
				(width 0)
				(type default)
			)
			(fill no)
			(layer "F.Fab")
		)
		(pad "1" smd custom
			(at 0 -0.4445)
			(size 0.1397 0.1397)
			(layers "F.Cu" "F.Mask" "F.Paste")
			(net "VREF6")
			(options
				(clearance outline)
				(anchor circle)
			)
			(primitives
				(gr_poly
					(pts
						(arc
							(start -0.1778 -0.2794)
							(mid -0.249642 -0.249642)
							(end -0.2794 -0.1778)
						)
						(arc
							(start -0.2794 0.1778)
							(mid -0.249642 0.249642)
							(end -0.1778 0.2794)
						)
						(arc
							(start 0.1778 0.2794)
							(mid 0.249642 0.249642)
							(end 0.2794 0.1778)
						)
						(arc
							(start 0.2794 -0.1778)
							(mid 0.249642 -0.249642)
							(end 0.1778 -0.2794)
						)
					)
					(width 0)
					(fill yes)
				)
			)
		)
		(pad "2" smd custom
			(at 0 0.4445)
			(size 0.1397 0.1397)
			(layers "F.Cu" "F.Mask" "F.Paste")
			(net "P3V3")
			(options
				(clearance outline)
				(anchor circle)
			)
			(primitives
				(gr_poly
					(pts
						(arc
							(start -0.1778 -0.2794)
							(mid -0.249642 -0.249642)
							(end -0.2794 -0.1778)
						)
						(arc
							(start -0.2794 0.1778)
							(mid -0.249642 0.249642)
							(end -0.1778 0.2794)
						)
						(arc
							(start 0.1778 0.2794)
							(mid 0.249642 0.249642)
							(end 0.2794 0.1778)
						)
						(arc
							(start 0.2794 -0.1778)
							(mid 0.249642 -0.249642)
							(end 0.1778 -0.2794)
						)
					)
					(width 0)
					(fill yes)
				)
			)
		)
	)
	(footprint ""
		(layer "F.Cu")
		(at 56.89473 -17.396714)
		(property "Reference" "C741"
			(at 0 0 0)
			(layer "F.SilkS")
			(hide yes)
			(effects
				(font
					(size 1.27 1.27)
				)
			)
		)
		(property "Value" "SCD1U16V2KX-3GP"
			(at 1.1811 -2.7051 0)
			(unlocked yes)
			(layer "F.Fab")
			(hide yes)
			(effects
				(font
					(size 1.016 1.016)
					(thickness 0.1524)
				)
			)
		)
		(property "Device Type" "C402H22"
			(at 1.1811 -4.2291 0)
			(unlocked yes)
			(layer "F.Fab")
			(hide yes)
			(effects
				(font
					(size 1.016 1.016)
					(thickness 0.1524)
				)
			)
		)
		(duplicate_pad_numbers_are_jumpers no)
		(fp_rect
			(start -0.4318 0.9525)
			(end 0.4318 -0.9525)
			(stroke
				(width 0)
				(type default)
			)
			(fill no)
			(layer "F.CrtYd")
		)
		(fp_rect
			(start -0.4318 0.9525)
			(end 0.4318 -0.9525)
			(stroke
				(width 0)
				(type default)
			)
			(fill no)
			(layer "F.Fab")
		)
		(pad "1" smd custom
			(at 0 -0.4445)
			(size 0.1524 0.1524)
			(layers "F.Cu" "F.Mask" "F.Paste")
			(net "U47_OE")
			(options
				(clearance outline)
				(anchor circle)
			)
			(primitives
				(gr_poly
					(pts
						(arc
							(start 0.3048 -0.2032)
							(mid 0.275042 -0.275042)
							(end 0.2032 -0.3048)
						)
						(arc
							(start -0.2032 -0.3048)
							(mid -0.275042 -0.275042)
							(end -0.3048 -0.2032)
						)
						(arc
							(start -0.3048 0.2032)
							(mid -0.275042 0.275042)
							(end -0.2032 0.3048)
						)
						(arc
							(start 0.2032 0.3048)
							(mid 0.275042 0.275042)
							(end 0.3048 0.2032)
						)
					)
					(width 0)
					(fill yes)
				)
			)
		)
		(pad "2" smd custom
			(at 0 0.4445)
			(size 0.1524 0.1524)
			(layers "F.Cu" "F.Mask" "F.Paste")
			(net "GND")
			(options
				(clearance outline)
				(anchor circle)
			)
			(primitives
				(gr_poly
					(pts
						(arc
							(start 0.3048 -0.2032)
							(mid 0.275042 -0.275042)
							(end 0.2032 -0.3048)
						)
						(arc
							(start -0.2032 -0.3048)
							(mid -0.275042 -0.275042)
							(end -0.3048 -0.2032)
						)
						(arc
							(start -0.3048 0.2032)
							(mid -0.275042 0.275042)
							(end -0.2032 0.3048)
						)
						(arc
							(start 0.2032 0.3048)
							(mid 0.275042 0.275042)
							(end 0.3048 0.2032)
						)
					)
					(width 0)
					(fill yes)
				)
			)
		)
	)
	(footprint ""
		(layer "F.Cu")
		(at 108.6358 -86.9442 180)
		(property "Reference" "R120"
			(at 0 0 180)
			(layer "F.SilkS")
			(hide yes)
			(effects
				(font
					(size 1.27 1.27)
				)
			)
		)
		(property "Value" "10KR2F-2-GP"
			(at 0.064008 -3.993896 180)
			(unlocked yes)
			(layer "F.Fab")
			(hide yes)
			(effects
				(font
					(size 1.016 1.016)
					(thickness 0.1524)
				)
			)
		)
		(property "Device Type" "R402H16"
			(at 0.064008 -5.517896 180)
			(unlocked yes)
			(layer "F.Fab")
			(hide yes)
			(effects
				(font
					(size 1.016 1.016)
					(thickness 0.1524)
				)
			)
		)
		(duplicate_pad_numbers_are_jumpers no)
		(fp_line
			(start 0.508 -0.9398)
			(end -0.508 -0.9398)
			(stroke
				(width 0.1524)
				(type default)
			)
			(layer "F.SilkS")
		)
		(fp_line
			(start -0.508 -0.9398)
			(end -0.508 0.9398)
			(stroke
				(width 0.1524)
				(type default)
			)
			(layer "F.SilkS")
		)
		(fp_rect
			(start -0.508 0.9398)
			(end 0.508 -0.9398)
			(stroke
				(width 0)
				(type default)
			)
			(fill no)
			(layer "F.CrtYd")
		)
		(fp_rect
			(start -0.508 0.9398)
			(end 0.508 -0.9398)
			(stroke
				(width 0)
				(type default)
			)
			(fill no)
			(layer "F.Fab")
		)
		(pad "1" smd custom
			(at 0 -0.4445 180)
			(size 0.1397 0.1397)
			(layers "F.Cu" "F.Mask" "F.Paste")
			(net "SOFT_RESET_N")
			(options
				(clearance outline)
				(anchor circle)
			)
			(primitives
				(gr_poly
					(pts
						(arc
							(start -0.1778 -0.2794)
							(mid -0.249642 -0.249642)
							(end -0.2794 -0.1778)
						)
						(arc
							(start -0.2794 0.1778)
							(mid -0.249642 0.249642)
							(end -0.1778 0.2794)
						)
						(arc
							(start 0.1778 0.2794)
							(mid 0.249642 0.249642)
							(end 0.2794 0.1778)
						)
						(arc
							(start 0.2794 -0.1778)
							(mid 0.249642 -0.249642)
							(end 0.1778 -0.2794)
						)
					)
					(width 0)
					(fill yes)
				)
			)
		)
		(pad "2" smd custom
			(at 0 0.4445 180)
			(size 0.1397 0.1397)
			(layers "F.Cu" "F.Mask" "F.Paste")
			(net "P1V8_E")
			(options
				(clearance outline)
				(anchor circle)
			)
			(primitives
				(gr_poly
					(pts
						(arc
							(start -0.1778 -0.2794)
							(mid -0.249642 -0.249642)
							(end -0.2794 -0.1778)
						)
						(arc
							(start -0.2794 0.1778)
							(mid -0.249642 0.249642)
							(end -0.1778 0.2794)
						)
						(arc
							(start 0.1778 0.2794)
							(mid 0.249642 0.249642)
							(end 0.2794 0.1778)
						)
						(arc
							(start 0.2794 -0.1778)
							(mid 0.249642 -0.249642)
							(end 0.1778 -0.2794)
						)
					)
					(width 0)
					(fill yes)
				)
			)
		)
	)
	(footprint ""
		(layer "F.Cu")
		(at 19.4564 -32.3342 180)
		(property "Reference" "D37"
			(at 0 0 180)
			(layer "F.SilkS")
			(hide yes)
			(effects
				(font
					(size 1.27 1.27)
				)
			)
		)
		(property "Value" "SMF15A-GP"
			(at -2.0955 1.2192 180)
			(unlocked yes)
			(layer "F.Fab")
			(hide yes)
			(effects
				(font
					(size 1.016 1.016)
					(thickness 0.1524)
				)
			)
		)
		(property "Device Type" "SOD123AK-2H43"
			(at -2.0955 -0.3048 180)
			(unlocked yes)
			(layer "F.Fab")
			(hide yes)
			(effects
				(font
					(size 1.016 1.016)
					(thickness 0.1524)
				)
			)
		)
		(duplicate_pad_numbers_are_jumpers no)
		(fp_line
			(start 1.1557 2.921)
			(end -1.1557 2.921)
			(stroke
				(width 0.508)
				(type default)
			)
			(layer "F.SilkS")
		)
		(fp_line
			(start 1.1557 2.7686)
			(end 1.1557 -2.7686)
			(stroke
				(width 0.1524)
				(type default)
			)
			(layer "F.SilkS")
		)
		(fp_line
			(start 1.1557 -2.7686)
			(end -1.1557 -2.7686)
			(stroke
				(width 0.1524)
				(type default)
			)
			(layer "F.SilkS")
		)
		(fp_line
			(start -1.1557 2.7686)
			(end 1.1557 2.7686)
			(stroke
				(width 0.1524)
				(type default)
			)
			(layer "F.SilkS")
		)
		(fp_line
			(start -1.1557 -2.7686)
			(end -1.1557 2.7686)
			(stroke
				(width 0.1524)
				(type default)
			)
			(layer "F.SilkS")
		)
		(fp_poly
			(pts
				(xy -0.4572 1.8669) (xy -0.4572 1.397) (xy -0.9017 1.397) (xy -0.9017 -1.397) (xy -0.4572 -1.397)
				(xy -0.4572 -1.8669) (xy 0.4572 -1.8669) (xy 0.4572 -1.397) (xy 0.9017 -1.397) (xy 0.9017 1.397)
				(xy 0.4572 1.397) (xy 0.4572 1.8669)
			)
			(stroke
				(width 0)
				(type default)
			)
			(fill no)
			(layer "F.CrtYd")
		)
		(fp_poly
			(pts
				(xy -1.4097 2.8448) (xy -1.4097 -2.8448) (xy 1.4097 -2.8448) (xy 1.4097 1.3716) (xy 0.9017 1.3716)
				(xy 0.9017 -1.397) (xy 0.4572 -1.397) (xy 0.4572 -1.8669) (xy -0.4572 -1.8669) (xy -0.4572 -1.397)
				(xy -0.9017 -1.397) (xy -0.9017 1.397) (xy -0.4572 1.397) (xy -0.4572 1.8669) (xy 0.4572 1.8669)
				(xy 0.4572 1.397) (xy 0.9017 1.397) (xy 0.9017 1.3843) (xy 1.4097 1.3843) (xy 1.4097 2.8448)
			)
			(stroke
				(width 0)
				(type default)
			)
			(fill no)
			(layer "F.CrtYd")
		)
		(fp_rect
			(start -1.4097 2.8448)
			(end 1.4097 -2.8448)
			(stroke
				(width 0)
				(type default)
			)
			(fill no)
			(layer "F.Fab")
		)
		(pad "A" smd rect
			(at 0 -1.75768 180)
			(size 1.143 1.4986)
			(layers "F.Cu" "F.Mask" "F.Paste")
			(net "GND")
		)
		(pad "K" smd rect
			(at 0 1.75768 180)
			(size 1.143 1.4986)
			(layers "F.Cu" "F.Mask" "F.Paste")
			(net "P12V_MAIN")
		)
	)
	(footprint ""
		(layer "F.Cu")
		(at 12.8778 -85.7504 -90)
		(property "Reference" "C558"
			(at 0 0 270)
			(layer "F.SilkS")
			(hide yes)
			(effects
				(font
					(size 1.27 1.27)
				)
			)
		)
		(property "Value" "SCD1U16V2KX-3GP"
			(at 1.1811 -2.7051 270)
			(unlocked yes)
			(layer "F.Fab")
			(hide yes)
			(effects
				(font
					(size 1.016 1.016)
					(thickness 0.1524)
				)
			)
		)
		(property "Device Type" "C402H22"
			(at 1.1811 -4.2291 270)
			(unlocked yes)
			(layer "F.Fab")
			(hide yes)
			(effects
				(font
					(size 1.016 1.016)
					(thickness 0.1524)
				)
			)
		)
		(duplicate_pad_numbers_are_jumpers no)
		(fp_rect
			(start -0.4318 0.9525)
			(end 0.4318 -0.9525)
			(stroke
				(width 0)
				(type default)
			)
			(fill no)
			(layer "F.CrtYd")
		)
		(fp_rect
			(start -0.4318 0.9525)
			(end 0.4318 -0.9525)
			(stroke
				(width 0)
				(type default)
			)
			(fill no)
			(layer "F.Fab")
		)
		(pad "1" smd custom
			(at 0 -0.4445 270)
			(size 0.1524 0.1524)
			(layers "F.Cu" "F.Mask" "F.Paste")
			(net "P1V8_E")
			(options
				(clearance outline)
				(anchor circle)
			)
			(primitives
				(gr_poly
					(pts
						(arc
							(start 0.3048 -0.2032)
							(mid 0.275042 -0.275042)
							(end 0.2032 -0.3048)
						)
						(arc
							(start -0.2032 -0.3048)
							(mid -0.275042 -0.275042)
							(end -0.3048 -0.2032)
						)
						(arc
							(start -0.3048 0.2032)
							(mid -0.275042 0.275042)
							(end -0.2032 0.3048)
						)
						(arc
							(start 0.2032 0.3048)
							(mid 0.275042 0.275042)
							(end 0.3048 0.2032)
						)
					)
					(width 0)
					(fill yes)
				)
			)
		)
		(pad "2" smd custom
			(at 0 0.4445 270)
			(size 0.1524 0.1524)
			(layers "F.Cu" "F.Mask" "F.Paste")
			(net "GND")
			(options
				(clearance outline)
				(anchor circle)
			)
			(primitives
				(gr_poly
					(pts
						(arc
							(start 0.3048 -0.2032)
							(mid 0.275042 -0.275042)
							(end 0.2032 -0.3048)
						)
						(arc
							(start -0.2032 -0.3048)
							(mid -0.275042 -0.275042)
							(end -0.3048 -0.2032)
						)
						(arc
							(start -0.3048 0.2032)
							(mid -0.275042 0.275042)
							(end -0.2032 0.3048)
						)
						(arc
							(start 0.2032 0.3048)
							(mid 0.275042 0.275042)
							(end 0.3048 0.2032)
						)
					)
					(width 0)
					(fill yes)
				)
			)
		)
	)
	(footprint ""
		(layer "F.Cu")
		(at 29.99994 -120.000014 180)
		(property "Reference" "DB1"
			(at 0 0 180)
			(layer "F.SilkS")
			(hide yes)
			(effects
				(font
					(size 1.27 1.27)
				)
			)
		)
		(property "Value" "JWT-CONN14A-GP"
			(at 7.4549 -7.2898 180)
			(unlocked yes)
			(layer "F.Fab")
			(hide yes)
			(effects
				(font
					(size 1.016 1.016)
					(thickness 0.1524)
				)
			)
		)
		(property "Device Type" "A2005WR0-2CX7PBS"
			(at 7.4549 -8.8138 180)
			(unlocked yes)
			(layer "F.Fab")
			(hide yes)
			(effects
				(font
					(size 1.016 1.016)
					(thickness 0.1524)
				)
			)
		)
		(duplicate_pad_numbers_are_jumpers no)
		(fp_line
			(start 8.5852 3.7592)
			(end 8.5852 -3.7592)
			(stroke
				(width 0.1524)
				(type default)
			)
			(layer "F.SilkS")
		)
		(fp_line
			(start 8.5852 -1.016)
			(end 8.128 -1.016)
			(stroke
				(width 0.1524)
				(type default)
			)
			(layer "F.SilkS")
		)
		(fp_line
			(start 8.5852 -3.7592)
			(end -8.5852 -3.7592)
			(stroke
				(width 0.1524)
				(type default)
			)
			(layer "F.SilkS")
		)
		(fp_line
			(start 8.128 0)
			(end 8.5852 0)
			(stroke
				(width 0.1524)
				(type default)
			)
			(layer "F.SilkS")
		)
		(fp_line
			(start 8.128 -1.016)
			(end 8.128 0)
			(stroke
				(width 0.1524)
				(type default)
			)
			(layer "F.SilkS")
		)
		(fp_line
			(start -5.8039 3.8608)
			(end -6.1849 3.8608)
			(stroke
				(width 0.3302)
				(type default)
			)
			(layer "F.SilkS")
		)
		(fp_line
			(start -8.128 0)
			(end -8.5852 0)
			(stroke
				(width 0.1524)
				(type default)
			)
			(layer "F.SilkS")
		)
		(fp_line
			(start -8.128 -1.016)
			(end -8.128 0)
			(stroke
				(width 0.1524)
				(type default)
			)
			(layer "F.SilkS")
		)
		(fp_line
			(start -8.5852 3.7592)
			(end 8.5852 3.7592)
			(stroke
				(width 0.1524)
				(type default)
			)
			(layer "F.SilkS")
		)
		(fp_line
			(start -8.5852 -1.016)
			(end -8.128 -1.016)
			(stroke
				(width 0.1524)
				(type default)
			)
			(layer "F.SilkS")
		)
		(fp_line
			(start -8.5852 -3.7592)
			(end -8.5852 3.7592)
			(stroke
				(width 0.1524)
				(type default)
			)
			(layer "F.SilkS")
		)
		(fp_poly
			(pts
				(xy -5.987288 3.81) (xy -6.495288 4.318) (xy -5.479288 4.318)
			)
			(stroke
				(width 0)
				(type default)
			)
			(fill yes)
			(layer "F.SilkS")
		)
		(fp_poly
			(pts
				(xy -4.16179 0.550164) (xy 4.161028 0.550164) (xy 4.161028 -0.550164) (xy -4.16179 -0.550164)
			)
			(stroke
				(width 0)
				(type default)
			)
			(fill yes)
			(layer "F.SilkS")
		)
		(fp_rect
			(start -8.3312 2.9972)
			(end 8.3312 -2.9972)
			(stroke
				(width 0)
				(type default)
			)
			(fill no)
			(layer "F.CrtYd")
		)
		(fp_poly
			(pts
				(xy 8.8392 -2.9972) (xy -8.3312 -2.9972) (xy -8.3312 2.9972) (xy 8.3312 2.9972) (xy 8.3312 -2.9845)
				(xy 8.8392 -2.9845) (xy 8.8392 4.0132) (xy -8.8392 4.0132) (xy -8.8392 -4.0132) (xy 8.8392 -4.0132)
			)
			(stroke
				(width 0)
				(type default)
			)
			(fill no)
			(layer "F.CrtYd")
		)
		(fp_rect
			(start -8.8392 4.0132)
			(end 8.8392 -4.0132)
			(stroke
				(width 0)
				(type default)
			)
			(fill no)
			(layer "F.Fab")
		)
		(pad "" np_thru_hole circle
			(at -4.99999 0 180)
			(size 0.254 0.254)
			(drill 1.0668)
			(layers "*.Cu" "*.Mask")
			(clearance 0.762)
			(thermal_gap 0.762)
		)
		(pad "" np_thru_hole circle
			(at 4.99999 0 180)
			(size 0.254 0.254)
			(drill 1.0668)
			(layers "*.Cu" "*.Mask")
			(clearance 0.762)
			(thermal_gap 0.762)
		)
		(pad "1" smd rect
			(at -5.999988 2.124964 180)
			(size 0.9906 2.7432)
			(layers "F.Cu" "F.Mask" "F.Paste")
			(net "DEBUG_LOW_HEX_0")
		)
		(pad "2" smd rect
			(at -5.999988 -2.124964 180)
			(size 0.9906 2.7432)
			(layers "F.Cu" "F.Mask" "F.Paste")
			(net "DEBUG_LOW_HEX_1")
		)
		(pad "3" smd rect
			(at -3.999992 2.124964 180)
			(size 0.9906 2.7432)
			(layers "F.Cu" "F.Mask" "F.Paste")
			(net "DEBUG_LOW_HEX_2")
		)
		(pad "4" smd rect
			(at -3.999992 -2.124964 180)
			(size 0.9906 2.7432)
			(layers "F.Cu" "F.Mask" "F.Paste")
			(net "DEBUG_LOW_HEX_3")
		)
		(pad "5" smd rect
			(at -1.999996 2.124964 180)
			(size 0.9906 2.7432)
			(layers "F.Cu" "F.Mask" "F.Paste")
			(net "DEBUG_HIGH_HEX_0")
		)
		(pad "6" smd rect
			(at -1.999996 -2.124964 180)
			(size 0.9906 2.7432)
			(layers "F.Cu" "F.Mask" "F.Paste")
			(net "DEBUG_HIGH_HEX_1")
		)
		(pad "7" smd rect
			(at 0 2.124964 180)
			(size 0.9906 2.7432)
			(layers "F.Cu" "F.Mask" "F.Paste")
			(net "DEBUG_HIGH_HEX_2")
		)
		(pad "8" smd rect
			(at 0 -2.124964 180)
			(size 0.9906 2.7432)
			(layers "F.Cu" "F.Mask" "F.Paste")
			(net "DEBUG_HIGH_HEX_3")
		)
		(pad "9" smd rect
			(at 1.999996 2.124964 180)
			(size 0.9906 2.7432)
			(layers "F.Cu" "F.Mask" "F.Paste")
			(net "Net_66")
		)
		(pad "10" smd rect
			(at 1.999996 -2.124964 180)
			(size 0.9906 2.7432)
			(layers "F.Cu" "F.Mask" "F.Paste")
			(net "Net_65")
		)
		(pad "11" smd rect
			(at 3.999992 2.124964 180)
			(size 0.9906 2.7432)
			(layers "F.Cu" "F.Mask" "F.Paste")
			(net "Net_64")
		)
		(pad "12" smd rect
			(at 3.999992 -2.124964 180)
			(size 0.9906 2.7432)
			(layers "F.Cu" "F.Mask" "F.Paste")
			(net "Net_63")
		)
		(pad "13" smd rect
			(at 5.999988 2.124964 180)
			(size 0.9906 2.7432)
			(layers "F.Cu" "F.Mask" "F.Paste")
			(net "GND")
		)
		(pad "14" smd rect
			(at 5.999988 -2.124964 180)
			(size 0.9906 2.7432)
			(layers "F.Cu" "F.Mask" "F.Paste")
			(net "P5V")
		)
		(zone
			(layer "F.Cu")
			(hatch none 0.5)
			(connect_pads
				(clearance 0)
			)
			(min_thickness 0.25)
			(keepout
				(tracks not_allowed)
				(vias allowed)
				(pads allowed)
				(copperpour not_allowed)
				(footprints allowed)
			)
			(placement
				(enabled no)
				(sheetname "")
			)
			(fill
				(thermal_gap 0.5)
				(thermal_bridge_width 0.5)
				(island_removal_mode 0)
			)
			(polygon
				(pts
					(xy 36.495228 -120.753378) (xy 23.504652 -120.753378) (xy 23.504652 -119.24665) (xy 36.495228 -119.24665)
				)
			)
		)
		(zone
			(layer "F.Cu")
			(hatch none 0.5)
			(connect_pads
				(clearance 0)
			)
			(min_thickness 0.25)
			(keepout
				(tracks allowed)
				(vias not_allowed)
				(pads allowed)
				(copperpour not_allowed)
				(footprints allowed)
			)
			(placement
				(enabled no)
				(sheetname "")
			)
			(fill
				(thermal_gap 0.5)
				(thermal_bridge_width 0.5)
				(island_removal_mode 0)
			)
			(polygon
				(pts
					(xy 36.495228 -120.753378) (xy 23.504652 -120.753378) (xy 23.504652 -119.24665) (xy 36.495228 -119.24665)
				)
			)
		)
		(zone
			(layer "F.Cu")
			(hatch none 0.5)
			(connect_pads
				(clearance 0)
			)
			(min_thickness 0.25)
			(keepout
				(tracks allowed)
				(vias not_allowed)
				(pads allowed)
				(copperpour not_allowed)
				(footprints allowed)
			)
			(placement
				(enabled no)
				(sheetname "")
			)
			(fill
				(thermal_gap 0.5)
				(thermal_bridge_width 0.5)
				(island_removal_mode 0)
			)
			(polygon
				(pts
					(xy 36.495228 -120.245378) (xy 36.495228 -120.753378) (xy 23.504652 -120.753378) (xy 23.504906 -120.245378)
				)
			)
		)
		(zone
			(layer "F.Cu")
			(hatch none 0.5)
			(connect_pads
				(clearance 0)
			)
			(min_thickness 0.25)
			(keepout
				(tracks allowed)
				(vias not_allowed)
				(pads allowed)
				(copperpour not_allowed)
				(footprints allowed)
			)
			(placement
				(enabled no)
				(sheetname "")
			)
			(fill
				(thermal_gap 0.5)
				(thermal_bridge_width 0.5)
				(island_removal_mode 0)
			)
			(polygon
				(pts
					(xy 36.495228 -119.24665) (xy 36.495228 -119.75465) (xy 23.504652 -119.75465) (xy 23.504652 -119.24665)
				)
			)
		)
		(zone
			(layers "F.Cu" "B.Cu" "In1.Cu" "In2.Cu" "In3.Cu" "In4.Cu" "In5.Cu" "In6.Cu")
			(hatch none 0.5)
			(connect_pads
				(clearance 0)
			)
			(min_thickness 0.25)
			(keepout
				(tracks not_allowed)
				(vias allowed)
				(pads allowed)
				(copperpour not_allowed)
				(footprints allowed)
			)
			(placement
				(enabled no)
				(sheetname "")
			)
			(fill
				(thermal_gap 0.5)
				(thermal_bridge_width 0.5)
				(island_removal_mode 0)
			)
			(polygon
				(pts
					(arc
						(start 25.83815 -120.000014)
						(mid 24.16175 -120.000014)
						(end 25.83815 -120.000014)
					)
				)
			)
		)
		(zone
			(layers "F.Cu" "B.Cu" "In1.Cu" "In2.Cu" "In3.Cu" "In4.Cu" "In5.Cu" "In6.Cu")
			(hatch none 0.5)
			(connect_pads
				(clearance 0)
			)
			(min_thickness 0.25)
			(keepout
				(tracks not_allowed)
				(vias allowed)
				(pads allowed)
				(copperpour not_allowed)
				(footprints allowed)
			)
			(placement
				(enabled no)
				(sheetname "")
			)
			(fill
				(thermal_gap 0.5)
				(thermal_bridge_width 0.5)
				(island_removal_mode 0)
			)
			(polygon
				(pts
					(arc
						(start 35.83813 -120.000014)
						(mid 34.16173 -120.000014)
						(end 35.83813 -120.000014)
					)
				)
			)
		)
	)
	(footprint ""
		(layer "F.Cu")
		(at 154.84348 -98.3361 -90)
		(property "Reference" "U21"
			(at 0 0 270)
			(layer "F.SilkS")
			(hide yes)
			(effects
				(font
					(size 1.27 1.27)
				)
			)
		)
		(property "Value" "TXS0102DCUR-1-GP"
			(at 0 -11.1252 270)
			(unlocked yes)
			(layer "F.Fab")
			(hide yes)
			(effects
				(font
					(size 1.016 1.016)
					(thickness 0.1524)
				)
			)
		)
		(property "Device Type" "SSOIC8-4H36"
			(at 0 -12.6492 270)
			(unlocked yes)
			(layer "F.Fab")
			(hide yes)
			(effects
				(font
					(size 1.016 1.016)
					(thickness 0.1524)
				)
			)
		)
		(duplicate_pad_numbers_are_jumpers no)
		(fp_line
			(start -1.2573 2.1844)
			(end -1.2573 -2.1844)
			(stroke
				(width 0.1524)
				(type default)
			)
			(layer "F.SilkS")
		)
		(fp_line
			(start 1.2573 2.1844)
			(end -1.2573 2.1844)
			(stroke
				(width 0.1524)
				(type default)
			)
			(layer "F.SilkS")
		)
		(fp_line
			(start -1.2954 0.4572)
			(end -1.2954 2.159)
			(stroke
				(width 0.4064)
				(type default)
			)
			(layer "F.SilkS")
		)
		(fp_line
			(start -1.2065 0.2667)
			(end -1.27 0.2667)
			(stroke
				(width 0.1524)
				(type default)
			)
			(layer "F.SilkS")
		)
		(fp_line
			(start -0.9017 -0.0381)
			(end -1.2065 0.2667)
			(stroke
				(width 0.1524)
				(type default)
			)
			(layer "F.SilkS")
		)
		(fp_line
			(start -1.2573 -0.3556)
			(end -1.2192 -0.3556)
			(stroke
				(width 0.1524)
				(type default)
			)
			(layer "F.SilkS")
		)
		(fp_line
			(start -1.2192 -0.3556)
			(end -0.9017 -0.0381)
			(stroke
				(width 0.1524)
				(type default)
			)
			(layer "F.SilkS")
		)
		(fp_line
			(start -1.2573 -2.1844)
			(end 1.2573 -2.1844)
			(stroke
				(width 0.1524)
				(type default)
			)
			(layer "F.SilkS")
		)
		(fp_line
			(start 1.2573 -2.1844)
			(end 1.2573 2.1844)
			(stroke
				(width 0.1524)
				(type default)
			)
			(layer "F.SilkS")
		)
		(fp_poly
			(pts
				(xy -1.5113 2.4384) (xy 1.5113 2.4384) (xy 1.5113 -2.4384) (xy -1.5113 -2.4384)
			)
			(stroke
				(width 0)
				(type default)
			)
			(fill no)
			(layer "F.CrtYd")
		)
		(fp_poly
			(pts
				(xy -1.5113 -2.4384) (xy 1.5113 -2.4384) (xy 1.5113 2.4384) (xy -1.5113 2.4384)
			)
			(stroke
				(width 0)
				(type default)
			)
			(fill no)
			(layer "F.Fab")
		)
		(pad "1" smd rect
			(at -0.75057 1.1684 270)
			(size 0.3048 1.524)
			(layers "F.Cu" "F.Mask" "F.Paste")
			(net "SAS_R_SDBRX")
		)
		(pad "2" smd rect
			(at -0.25019 1.1684 270)
			(size 0.3048 1.524)
			(layers "F.Cu" "F.Mask" "F.Paste")
			(net "GND")
		)
		(pad "3" smd rect
			(at 0.25019 1.1684 270)
			(size 0.3048 1.524)
			(layers "F.Cu" "F.Mask" "F.Paste")
			(net "P1V8_E")
		)
		(pad "4" smd rect
			(at 0.75057 1.1684 270)
			(size 0.3048 1.524)
			(layers "F.Cu" "F.Mask" "F.Paste")
			(net "SDB_RX_R")
		)
		(pad "5" smd rect
			(at 0.75057 -1.1684 270)
			(size 0.3048 1.524)
			(layers "F.Cu" "F.Mask" "F.Paste")
			(net "SDB_TX_R")
		)
		(pad "6" smd rect
			(at 0.25019 -1.1684 270)
			(size 0.3048 1.524)
			(layers "F.Cu" "F.Mask" "F.Paste")
			(net "SDB_UART_EN")
		)
		(pad "7" smd rect
			(at -0.25019 -1.1684 270)
			(size 0.3048 1.524)
			(layers "F.Cu" "F.Mask" "F.Paste")
			(net "P3V3")
		)
		(pad "8" smd rect
			(at -0.75057 -1.1684 270)
			(size 0.3048 1.524)
			(layers "F.Cu" "F.Mask" "F.Paste")
			(net "SAS_R_SDBTX")
		)
	)
	(footprint ""
		(layer "F.Cu")
		(at 159.52978 -118.98122 90)
		(property "Reference" "R31"
			(at 0 0 90)
			(layer "F.SilkS")
			(hide yes)
			(effects
				(font
					(size 1.27 1.27)
				)
			)
		)
		(property "Value" "475KR2F-GP"
			(at 0.064008 -3.993896 90)
			(unlocked yes)
			(layer "F.Fab")
			(hide yes)
			(effects
				(font
					(size 1.016 1.016)
					(thickness 0.1524)
				)
			)
		)
		(property "Device Type" "R402H16"
			(at 0.064008 -5.517896 90)
			(unlocked yes)
			(layer "F.Fab")
			(hide yes)
			(effects
				(font
					(size 1.016 1.016)
					(thickness 0.1524)
				)
			)
		)
		(duplicate_pad_numbers_are_jumpers no)
		(fp_line
			(start 0.508 -0.9398)
			(end -0.508 -0.9398)
			(stroke
				(width 0.1524)
				(type default)
			)
			(layer "F.SilkS")
		)
		(fp_line
			(start -0.508 -0.9398)
			(end -0.508 0.9398)
			(stroke
				(width 0.1524)
				(type default)
			)
			(layer "F.SilkS")
		)
		(fp_rect
			(start -0.508 0.9398)
			(end 0.508 -0.9398)
			(stroke
				(width 0)
				(type default)
			)
			(fill no)
			(layer "F.CrtYd")
		)
		(fp_rect
			(start -0.508 0.9398)
			(end 0.508 -0.9398)
			(stroke
				(width 0)
				(type default)
			)
			(fill no)
			(layer "F.Fab")
		)
		(pad "1" smd custom
			(at 0 -0.4445 90)
			(size 0.1397 0.1397)
			(layers "F.Cu" "F.Mask" "F.Paste")
			(net "P1V5_E_MODE")
			(options
				(clearance outline)
				(anchor circle)
			)
			(primitives
				(gr_poly
					(pts
						(arc
							(start -0.1778 -0.2794)
							(mid -0.249642 -0.249642)
							(end -0.2794 -0.1778)
						)
						(arc
							(start -0.2794 0.1778)
							(mid -0.249642 0.249642)
							(end -0.1778 0.2794)
						)
						(arc
							(start 0.1778 0.2794)
							(mid 0.249642 0.249642)
							(end 0.2794 0.1778)
						)
						(arc
							(start 0.2794 -0.1778)
							(mid 0.249642 -0.249642)
							(end 0.1778 -0.2794)
						)
					)
					(width 0)
					(fill yes)
				)
			)
		)
		(pad "2" smd custom
			(at 0 0.4445 90)
			(size 0.1397 0.1397)
			(layers "F.Cu" "F.Mask" "F.Paste")
			(net "P1V5_E_PG")
			(options
				(clearance outline)
				(anchor circle)
			)
			(primitives
				(gr_poly
					(pts
						(arc
							(start -0.1778 -0.2794)
							(mid -0.249642 -0.249642)
							(end -0.2794 -0.1778)
						)
						(arc
							(start -0.2794 0.1778)
							(mid -0.249642 0.249642)
							(end -0.1778 0.2794)
						)
						(arc
							(start 0.1778 0.2794)
							(mid 0.249642 0.249642)
							(end 0.2794 0.1778)
						)
						(arc
							(start 0.2794 -0.1778)
							(mid 0.249642 -0.249642)
							(end 0.1778 -0.2794)
						)
					)
					(width 0)
					(fill yes)
				)
			)
		)
	)
	(footprint ""
		(layer "F.Cu")
		(at 146.37131 -46.469554 102)
		(property "Reference" "C340"
			(at 0 0 102)
			(layer "F.SilkS")
			(hide yes)
			(effects
				(font
					(size 1.27 1.27)
				)
			)
		)
		(property "Value" "SCD01U16V1KX-GP"
			(at -2.832296 -1.73983 102)
			(unlocked yes)
			(layer "F.Fab")
			(hide yes)
			(effects
				(font
					(size 1.016 1.016)
					(thickness 0.1524)
				)
			)
		)
		(property "Device Type" "C0201H13"
			(at -2.832174 -3.263834 102)
			(unlocked yes)
			(layer "F.Fab")
			(hide yes)
			(effects
				(font
					(size 1.016 1.016)
					(thickness 0.1524)
				)
			)
		)
		(duplicate_pad_numbers_are_jumpers no)
		(fp_poly
			(pts
				(xy -0.279454 -0.647706) (xy 0.279346 -0.647706) (xy 0.279346 0.647694) (xy -0.279454 0.647694)
			)
			(stroke
				(width 0)
				(type default)
			)
			(fill no)
			(layer "F.CrtYd")
		)
		(fp_poly
			(pts
				(xy -0.279454 -0.647706) (xy 0.279346 -0.647706) (xy 0.279346 0.647694) (xy -0.279454 0.647694)
			)
			(stroke
				(width 0)
				(type default)
			)
			(fill no)
			(layer "F.Fab")
		)
		(pad "1" smd custom
			(at -0.000001 -0.2794 102)
			(size 0.0762 0.0762)
			(layers "F.Cu" "F.Mask" "F.Paste")
			(net "PHY_SCC_TO_IOC_45_DN")
			(options
				(clearance outline)
				(anchor circle)
			)
			(primitives
				(gr_poly
					(pts
						(arc
							(start 0.1524 -0.127)
							(mid 0.137521 -0.162921)
							(end 0.1016 -0.1778)
						)
						(arc
							(start -0.1016 -0.1778)
							(mid -0.137521 -0.162921)
							(end -0.1524 -0.127)
						)
						(arc
							(start -0.1524 0.127)
							(mid -0.137521 0.162921)
							(end -0.1016 0.1778)
						)
						(arc
							(start 0.1016 0.1778)
							(mid 0.137521 0.162921)
							(end 0.1524 0.127)
						)
					)
					(width 0)
					(fill yes)
				)
			)
		)
		(pad "2" smd custom
			(at 0.000001 0.2794 102)
			(size 0.0762 0.0762)
			(layers "F.Cu" "F.Mask" "F.Paste")
			(net "PHY_SCC_TO_IOC_C_45_DN")
			(options
				(clearance outline)
				(anchor circle)
			)
			(primitives
				(gr_poly
					(pts
						(arc
							(start 0.1524 -0.127)
							(mid 0.137521 -0.162921)
							(end 0.1016 -0.1778)
						)
						(arc
							(start -0.1016 -0.1778)
							(mid -0.137521 -0.162921)
							(end -0.1524 -0.127)
						)
						(arc
							(start -0.1524 0.127)
							(mid -0.137521 0.162921)
							(end -0.1016 0.1778)
						)
						(arc
							(start 0.1016 0.1778)
							(mid 0.137521 0.162921)
							(end 0.1524 0.127)
						)
					)
					(width 0)
					(fill yes)
				)
			)
		)
	)
	(footprint ""
		(layer "F.Cu")
		(at 148.473668 -50.973736 -78)
		(property "Reference" "VIA23"
			(at 0 0 282)
			(layer "F.SilkS")
			(hide yes)
			(effects
				(font
					(size 1.27 1.27)
				)
			)
		)
		(property "Value" "100OHM-8L-1D6MM-L13-GP"
			(at 3.289333 0.050849 282)
			(unlocked yes)
			(layer "F.Fab")
			(hide yes)
			(effects
				(font
					(size 1.016 1.016)
					(thickness 0.1524)
				)
			)
		)
		(property "Device Type" "VIA-PCIE-4P-409091"
			(at 3.289456 -1.473155 282)
			(unlocked yes)
			(layer "F.Fab")
			(hide yes)
			(effects
				(font
					(size 1.016 1.016)
					(thickness 0.1524)
				)
			)
		)
		(duplicate_pad_numbers_are_jumpers no)
		(fp_poly
			(pts
				(xy -2.044719 -0.457296) (xy 2.04468 -0.457296) (xy 2.044681 0.457104) (xy -2.044719 0.457104)
			)
			(stroke
				(width 0)
				(type default)
			)
			(fill no)
			(layer "F.CrtYd")
		)
		(fp_poly
			(pts
				(xy -2.044719 -0.457296) (xy 2.04468 -0.457296) (xy 2.044681 0.457104) (xy -2.044719 0.457104)
			)
			(stroke
				(width 0)
				(type default)
			)
			(fill no)
			(layer "F.Fab")
		)
		(pad "1" thru_hole circle
			(at -1.5875 0 282)
			(size 0.508 0.508)
			(drill 0.254)
			(layers "*.Cu" "*.Mask")
			(remove_unused_layers no)
			(net "GND")
			(clearance 0.2032)
			(thermal_gap 0.2032)
		)
		(pad "2" thru_hole circle
			(at -0.5715 0.000001 282)
			(size 0.508 0.508)
			(drill 0.254)
			(layers "*.Cu" "*.Mask")
			(remove_unused_layers no)
			(net "PHY_SCC_TO_IOC_C_46_DP")
			(clearance 0.2032)
			(thermal_gap 0.2032)
		)
		(pad "3" thru_hole circle
			(at 0.5715 -0.000001 282)
			(size 0.508 0.508)
			(drill 0.254)
			(layers "*.Cu" "*.Mask")
			(remove_unused_layers no)
			(net "PHY_SCC_TO_IOC_C_46_DN")
			(clearance 0.2032)
			(thermal_gap 0.2032)
		)
		(pad "4" thru_hole circle
			(at 1.5875 0 282)
			(size 0.508 0.508)
			(drill 0.254)
			(layers "*.Cu" "*.Mask")
			(remove_unused_layers no)
			(net "GND")
			(clearance 0.2032)
			(thermal_gap 0.2032)
		)
	)
	(footprint ""
		(layer "F.Cu")
		(at 7.2898 -74.2188 -90)
		(property "Reference" "R360"
			(at 0 0 270)
			(layer "F.SilkS")
			(hide yes)
			(effects
				(font
					(size 1.27 1.27)
				)
			)
		)
		(property "Value" "4K7R2F-GP"
			(at 0.064008 -3.993896 270)
			(unlocked yes)
			(layer "F.Fab")
			(hide yes)
			(effects
				(font
					(size 1.016 1.016)
					(thickness 0.1524)
				)
			)
		)
		(property "Device Type" "R402H16"
			(at 0.064008 -5.517896 270)
			(unlocked yes)
			(layer "F.Fab")
			(hide yes)
			(effects
				(font
					(size 1.016 1.016)
					(thickness 0.1524)
				)
			)
		)
		(duplicate_pad_numbers_are_jumpers no)
		(fp_line
			(start -0.508 -0.9398)
			(end -0.508 0.9398)
			(stroke
				(width 0.1524)
				(type default)
			)
			(layer "F.SilkS")
		)
		(fp_line
			(start 0.508 -0.9398)
			(end -0.508 -0.9398)
			(stroke
				(width 0.1524)
				(type default)
			)
			(layer "F.SilkS")
		)
		(fp_rect
			(start -0.508 0.9398)
			(end 0.508 -0.9398)
			(stroke
				(width 0)
				(type default)
			)
			(fill no)
			(layer "F.CrtYd")
		)
		(fp_rect
			(start -0.508 0.9398)
			(end 0.508 -0.9398)
			(stroke
				(width 0)
				(type default)
			)
			(fill no)
			(layer "F.Fab")
		)
		(pad "1" smd custom
			(at 0 -0.4445 270)
			(size 0.1397 0.1397)
			(layers "F.Cu" "F.Mask" "F.Paste")
			(net "FRU_EEPROM_A0")
			(options
				(clearance outline)
				(anchor circle)
			)
			(primitives
				(gr_poly
					(pts
						(arc
							(start -0.1778 -0.2794)
							(mid -0.249642 -0.249642)
							(end -0.2794 -0.1778)
						)
						(arc
							(start -0.2794 0.1778)
							(mid -0.249642 0.249642)
							(end -0.1778 0.2794)
						)
						(arc
							(start 0.1778 0.2794)
							(mid 0.249642 0.249642)
							(end 0.2794 0.1778)
						)
						(arc
							(start 0.2794 -0.1778)
							(mid 0.249642 -0.249642)
							(end 0.1778 -0.2794)
						)
					)
					(width 0)
					(fill yes)
				)
			)
		)
		(pad "2" smd custom
			(at 0 0.4445 270)
			(size 0.1397 0.1397)
			(layers "F.Cu" "F.Mask" "F.Paste")
			(net "GND")
			(options
				(clearance outline)
				(anchor circle)
			)
			(primitives
				(gr_poly
					(pts
						(arc
							(start -0.1778 -0.2794)
							(mid -0.249642 -0.249642)
							(end -0.2794 -0.1778)
						)
						(arc
							(start -0.2794 0.1778)
							(mid -0.249642 0.249642)
							(end -0.1778 0.2794)
						)
						(arc
							(start 0.1778 0.2794)
							(mid 0.249642 0.249642)
							(end 0.2794 0.1778)
						)
						(arc
							(start 0.2794 -0.1778)
							(mid 0.249642 -0.249642)
							(end 0.1778 -0.2794)
						)
					)
					(width 0)
					(fill yes)
				)
			)
		)
	)
	(footprint ""
		(layer "F.Cu")
		(at 153.5176 -115.8494 90)
		(property "Reference" "U11"
			(at 0 0 90)
			(layer "F.SilkS")
			(hide yes)
			(effects
				(font
					(size 1.27 1.27)
				)
			)
		)
		(property "Value" "TPS53318DQPR-GP"
			(at -5.022088 -6.851904 90)
			(unlocked yes)
			(layer "F.Fab")
			(hide yes)
			(effects
				(font
					(size 1.016 1.016)
					(thickness 0.1524)
				)
			)
		)
		(property "Device Type" "DFN22G6050-G6133H60"
			(at -5.022088 -8.375904 90)
			(unlocked yes)
			(layer "F.Fab")
			(hide yes)
			(effects
				(font
					(size 1.016 1.016)
					(thickness 0.1524)
				)
			)
		)
		(duplicate_pad_numbers_are_jumpers no)
		(fp_line
			(start -2.2352 -3.5179)
			(end -3.5052 -3.5179)
			(stroke
				(width 0.1524)
				(type default)
			)
			(layer "F.SilkS")
		)
		(fp_line
			(start -3.5052 -3.5179)
			(end -3.5052 -2.2479)
			(stroke
				(width 0.1524)
				(type default)
			)
			(layer "F.SilkS")
		)
		(fp_line
			(start 0.500126 -3.262122)
			(end 0.500126 -3.770122)
			(stroke
				(width 0.1524)
				(type default)
			)
			(layer "F.SilkS")
		)
		(fp_line
			(start -1.999996 -3.262122)
			(end -1.999996 -4.024122)
			(stroke
				(width 0.1524)
				(type default)
			)
			(layer "F.SilkS")
		)
		(fp_line
			(start -3.5052 2.2479)
			(end -3.5052 3.5179)
			(stroke
				(width 0.1524)
				(type default)
			)
			(layer "F.SilkS")
		)
		(fp_line
			(start 1.500124 3.262122)
			(end 1.500124 4.024122)
			(stroke
				(width 0.1524)
				(type default)
			)
			(layer "F.SilkS")
		)
		(fp_line
			(start -0.999998 3.262122)
			(end -0.999998 3.770122)
			(stroke
				(width 0.1524)
				(type default)
			)
			(layer "F.SilkS")
		)
		(fp_line
			(start 3.5052 3.5179)
			(end 3.5052 2.2479)
			(stroke
				(width 0.1524)
				(type default)
			)
			(layer "F.SilkS")
		)
		(fp_line
			(start 2.2352 3.5179)
			(end 3.5052 3.5179)
			(stroke
				(width 0.1524)
				(type default)
			)
			(layer "F.SilkS")
		)
		(fp_line
			(start -3.5052 3.5179)
			(end -2.2352 3.5179)
			(stroke
				(width 0.1524)
				(type default)
			)
			(layer "F.SilkS")
		)
		(fp_poly
			(pts
				(xy 3.5052 -3.5179) (xy 2.4765 -3.5179) (xy 3.5052 -2.4892)
			)
			(stroke
				(width 0)
				(type default)
			)
			(fill yes)
			(layer "F.SilkS")
		)
		(fp_rect
			(start -2.9972 2.5019)
			(end 2.9972 -2.5019)
			(stroke
				(width 0)
				(type default)
			)
			(fill no)
			(layer "F.CrtYd")
		)
		(fp_poly
			(pts
				(xy 3.556 -2.5019) (xy -2.9972 -2.5019) (xy -2.9972 2.5019) (xy 2.9972 2.5019) (xy 2.9972 -2.4892)
				(xy 3.556 -2.4892) (xy 3.556 3.5179) (xy -3.556 3.5179) (xy -3.556 -3.5179) (xy 3.556 -3.5179)
			)
			(stroke
				(width 0)
				(type default)
			)
			(fill no)
			(layer "F.CrtYd")
		)
		(fp_rect
			(start -3.556 3.5179)
			(end 3.556 -3.5179)
			(stroke
				(width 0)
				(type default)
			)
			(fill no)
			(layer "F.Fab")
		)
		(pad "1" smd rect
			(at 2.500122 -2.449322 90)
			(size 0.3048 1.1176)
			(layers "F.Cu" "F.Mask" "F.Paste")
			(net "P1V5_E_VFB")
		)
		(pad "2" smd rect
			(at 1.999996 -2.449322 90)
			(size 0.3048 1.1176)
			(layers "F.Cu" "F.Mask" "F.Paste")
			(net "P1V5_E_EN")
		)
		(pad "3" smd rect
			(at 1.500124 -2.449322 90)
			(size 0.3048 1.1176)
			(layers "F.Cu" "F.Mask" "F.Paste")
			(net "P1V5_E_PG")
		)
		(pad "4" smd rect
			(at 0.999998 -2.449322 90)
			(size 0.3048 1.1176)
			(layers "F.Cu" "F.Mask" "F.Paste")
			(net "P1V5_E_VBST")
		)
		(pad "5" smd rect
			(at 0.500126 -2.449322 90)
			(size 0.3048 1.1176)
			(layers "F.Cu" "F.Mask" "F.Paste")
			(net "P1V5_E_ROVP")
		)
		(pad "6" smd rect
			(at 0 -2.449322 90)
			(size 0.3048 1.1176)
			(layers "F.Cu" "F.Mask" "F.Paste")
			(net "P1V5_E_LL")
		)
		(pad "7" smd rect
			(at -0.500126 -2.449322 90)
			(size 0.3048 1.1176)
			(layers "F.Cu" "F.Mask" "F.Paste")
			(net "P1V5_E_LL")
		)
		(pad "8" smd rect
			(at -0.999998 -2.449322 90)
			(size 0.3048 1.1176)
			(layers "F.Cu" "F.Mask" "F.Paste")
			(net "P1V5_E_LL")
		)
		(pad "9" smd rect
			(at -1.500124 -2.449322 90)
			(size 0.3048 1.1176)
			(layers "F.Cu" "F.Mask" "F.Paste")
			(net "P1V5_E_LL")
		)
		(pad "10" smd rect
			(at -1.999996 -2.449322 90)
			(size 0.3048 1.1176)
			(layers "F.Cu" "F.Mask" "F.Paste")
			(net "P1V5_E_LL")
		)
		(pad "11" smd rect
			(at -2.500122 -2.449322 90)
			(size 0.3048 1.1176)
			(layers "F.Cu" "F.Mask" "F.Paste")
			(net "P1V5_E_LL")
		)
		(pad "12" smd rect
			(at -2.500122 2.449322 90)
			(size 0.3048 1.1176)
			(layers "F.Cu" "F.Mask" "F.Paste")
			(net "P12V_STBY_VIN_U11")
		)
		(pad "13" smd rect
			(at -1.999996 2.449322 90)
			(size 0.3048 1.1176)
			(layers "F.Cu" "F.Mask" "F.Paste")
			(net "P12V_STBY_VIN_U11")
		)
		(pad "14" smd rect
			(at -1.500124 2.449322 90)
			(size 0.3048 1.1176)
			(layers "F.Cu" "F.Mask" "F.Paste")
			(net "P12V_STBY_VIN_U11")
		)
		(pad "15" smd rect
			(at -0.999998 2.449322 90)
			(size 0.3048 1.1176)
			(layers "F.Cu" "F.Mask" "F.Paste")
			(net "P12V_STBY_VIN_U11")
		)
		(pad "16" smd rect
			(at -0.500126 2.449322 90)
			(size 0.3048 1.1176)
			(layers "F.Cu" "F.Mask" "F.Paste")
			(net "P12V_STBY_VIN_U11")
		)
		(pad "17" smd rect
			(at 0 2.449322 90)
			(size 0.3048 1.1176)
			(layers "F.Cu" "F.Mask" "F.Paste")
			(net "P12V_STBY_VIN_U11")
		)
		(pad "18" smd rect
			(at 0.500126 2.449322 90)
			(size 0.3048 1.1176)
			(layers "F.Cu" "F.Mask" "F.Paste")
			(net "P1V5_E_VREG")
		)
		(pad "19" smd rect
			(at 0.999998 2.449322 90)
			(size 0.3048 1.1176)
			(layers "F.Cu" "F.Mask" "F.Paste")
			(net "P12V_STBY_VDD_U11")
		)
		(pad "20" smd rect
			(at 1.500124 2.449322 90)
			(size 0.3048 1.1176)
			(layers "F.Cu" "F.Mask" "F.Paste")
			(net "P1V5_E_MODE")
		)
		(pad "21" smd rect
			(at 1.999996 2.449322 90)
			(size 0.3048 1.1176)
			(layers "F.Cu" "F.Mask" "F.Paste")
			(net "P1V5_E_TRIP")
		)
		(pad "22" smd rect
			(at 2.500122 2.449322 90)
			(size 0.3048 1.1176)
			(layers "F.Cu" "F.Mask" "F.Paste")
			(net "P1V5_E_RF")
		)
		(pad "23" smd custom
			(at 0 0 90)
			(size 0.83185 0.83185)
			(layers "F.Cu" "F.Mask" "F.Paste")
			(net "GND")
			(options
				(clearance outline)
				(anchor circle)
			)
			(primitives
				(gr_poly
					(pts
						(xy -2.7813 1.6637) (xy -2.7813 1.2954) (xy -3.048 1.2954) (xy -3.048 0.9525) (xy -2.7813 0.9525)
						(xy -2.7813 -0.9525) (xy -3.048 -0.9525) (xy -3.048 -1.2954) (xy -2.7813 -1.2954) (xy -2.7813 -1.6637)
						(xy 2.7813 -1.6637) (xy 2.7813 -1.2954) (xy 3.048 -1.2954) (xy 3.048 -0.9525) (xy 2.7813 -0.9525)
						(xy 2.7813 0.9525) (xy 3.048 0.9525) (xy 3.048 1.2954) (xy 2.7813 1.2954) (xy 2.7813 1.6637)
					)
					(width 0)
					(fill yes)
				)
			)
		)
	)
	(footprint ""
		(layer "F.Cu")
		(at 128.00203 -44.732448 180)
		(property "Reference" "C45"
			(at 0 0 180)
			(layer "F.SilkS")
			(hide yes)
			(effects
				(font
					(size 1.27 1.27)
				)
			)
		)
		(property "Value" "SCD01U16V1KX-GP"
			(at -2.8321 -1.7399 180)
			(unlocked yes)
			(layer "F.Fab")
			(hide yes)
			(effects
				(font
					(size 1.016 1.016)
					(thickness 0.1524)
				)
			)
		)
		(property "Device Type" "C0201H13"
			(at -2.8321 -3.2639 180)
			(unlocked yes)
			(layer "F.Fab")
			(hide yes)
			(effects
				(font
					(size 1.016 1.016)
					(thickness 0.1524)
				)
			)
		)
		(duplicate_pad_numbers_are_jumpers no)
		(fp_rect
			(start -0.2794 0.6477)
			(end 0.2794 -0.6477)
			(stroke
				(width 0)
				(type default)
			)
			(fill no)
			(layer "F.CrtYd")
		)
		(fp_rect
			(start -0.2794 0.6477)
			(end 0.2794 -0.6477)
			(stroke
				(width 0)
				(type default)
			)
			(fill no)
			(layer "F.Fab")
		)
		(pad "1" smd custom
			(at 0 -0.2794 180)
			(size 0.0762 0.0762)
			(layers "F.Cu" "F.Mask" "F.Paste")
			(net "PHY_IOC_TO_SCC_41_DP")
			(options
				(clearance outline)
				(anchor circle)
			)
			(primitives
				(gr_poly
					(pts
						(arc
							(start 0.1524 -0.127)
							(mid 0.137521 -0.162921)
							(end 0.1016 -0.1778)
						)
						(arc
							(start -0.1016 -0.1778)
							(mid -0.137521 -0.162921)
							(end -0.1524 -0.127)
						)
						(arc
							(start -0.1524 0.127)
							(mid -0.137521 0.162921)
							(end -0.1016 0.1778)
						)
						(arc
							(start 0.1016 0.1778)
							(mid 0.137521 0.162921)
							(end 0.1524 0.127)
						)
					)
					(width 0)
					(fill yes)
				)
			)
		)
		(pad "2" smd custom
			(at 0 0.2794 180)
			(size 0.0762 0.0762)
			(layers "F.Cu" "F.Mask" "F.Paste")
			(net "PHY_IOC_TO_SCC_C_41_DP")
			(options
				(clearance outline)
				(anchor circle)
			)
			(primitives
				(gr_poly
					(pts
						(arc
							(start 0.1524 -0.127)
							(mid 0.137521 -0.162921)
							(end 0.1016 -0.1778)
						)
						(arc
							(start -0.1016 -0.1778)
							(mid -0.137521 -0.162921)
							(end -0.1524 -0.127)
						)
						(arc
							(start -0.1524 0.127)
							(mid -0.137521 0.162921)
							(end -0.1016 0.1778)
						)
						(arc
							(start 0.1016 0.1778)
							(mid 0.137521 0.162921)
							(end 0.1524 0.127)
						)
					)
					(width 0)
					(fill yes)
				)
			)
		)
	)
	(footprint ""
		(layer "F.Cu")
		(at 70.485 -62.484 90)
		(property "Reference" "R162"
			(at 0 0 90)
			(layer "F.SilkS")
			(hide yes)
			(effects
				(font
					(size 1.27 1.27)
				)
			)
		)
		(property "Value" "D51R3F-2-GP"
			(at -0.0254 -2.5146 90)
			(unlocked yes)
			(layer "F.Fab")
			(hide yes)
			(effects
				(font
					(size 1.016 1.016)
					(thickness 0.1524)
				)
			)
		)
		(property "Device Type" "R603H22"
			(at -0.0254 -4.0386 90)
			(unlocked yes)
			(layer "F.Fab")
			(hide yes)
			(effects
				(font
					(size 1.016 1.016)
					(thickness 0.1524)
				)
			)
		)
		(duplicate_pad_numbers_are_jumpers no)
		(fp_line
			(start 0.2032 0)
			(end 0.4826 0)
			(stroke
				(width 0.2032)
				(type default)
			)
			(layer "F.SilkS")
		)
		(fp_line
			(start -0.4826 0)
			(end -0.2032 0)
			(stroke
				(width 0.2032)
				(type default)
			)
			(layer "F.SilkS")
		)
		(fp_rect
			(start -0.5842 1.3335)
			(end 0.5842 -1.3335)
			(stroke
				(width 0)
				(type default)
			)
			(fill no)
			(layer "F.CrtYd")
		)
		(fp_rect
			(start -0.5842 1.3335)
			(end 0.5842 -1.3335)
			(stroke
				(width 0)
				(type default)
			)
			(fill no)
			(layer "F.Fab")
		)
		(pad "1" smd custom
			(at 0 -0.762 90)
			(size 0.2159 0.2159)
			(layers "F.Cu" "F.Mask" "F.Paste")
			(net "P0V9")
			(options
				(clearance outline)
				(anchor circle)
			)
			(primitives
				(gr_poly
					(pts
						(arc
							(start -0.3302 -0.4318)
							(mid -0.402042 -0.402042)
							(end -0.4318 -0.3302)
						)
						(arc
							(start -0.4318 0.3302)
							(mid -0.402042 0.402042)
							(end -0.3302 0.4318)
						)
						(arc
							(start 0.3302 0.4318)
							(mid 0.402042 0.402042)
							(end 0.4318 0.3302)
						)
						(arc
							(start 0.4318 -0.3302)
							(mid 0.402042 -0.402042)
							(end 0.3302 -0.4318)
						)
					)
					(width 0)
					(fill yes)
				)
			)
		)
		(pad "2" smd custom
			(at 0 0.762 90)
			(size 0.2159 0.2159)
			(layers "F.Cu" "F.Mask" "F.Paste")
			(net "GB_VDDA")
			(options
				(clearance outline)
				(anchor circle)
			)
			(primitives
				(gr_poly
					(pts
						(arc
							(start -0.3302 -0.4318)
							(mid -0.402042 -0.402042)
							(end -0.4318 -0.3302)
						)
						(arc
							(start -0.4318 0.3302)
							(mid -0.402042 0.402042)
							(end -0.3302 0.4318)
						)
						(arc
							(start 0.3302 0.4318)
							(mid 0.402042 0.402042)
							(end 0.4318 0.3302)
						)
						(arc
							(start 0.4318 -0.3302)
							(mid 0.402042 -0.402042)
							(end 0.3302 -0.4318)
						)
					)
					(width 0)
					(fill yes)
				)
			)
		)
	)
	(footprint ""
		(layer "F.Cu")
		(at 91.0082 -84.836 90)
		(property "Reference" "C112"
			(at 0 0 90)
			(layer "F.SilkS")
			(hide yes)
			(effects
				(font
					(size 1.27 1.27)
				)
			)
		)
		(property "Value" "SCD1U16V2KX-3GP"
			(at 1.1811 -2.7051 90)
			(unlocked yes)
			(layer "F.Fab")
			(hide yes)
			(effects
				(font
					(size 1.016 1.016)
					(thickness 0.1524)
				)
			)
		)
		(property "Device Type" "C402H22"
			(at 1.1811 -4.2291 90)
			(unlocked yes)
			(layer "F.Fab")
			(hide yes)
			(effects
				(font
					(size 1.016 1.016)
					(thickness 0.1524)
				)
			)
		)
		(duplicate_pad_numbers_are_jumpers no)
		(fp_rect
			(start -0.4318 0.9525)
			(end 0.4318 -0.9525)
			(stroke
				(width 0)
				(type default)
			)
			(fill no)
			(layer "F.CrtYd")
		)
		(fp_rect
			(start -0.4318 0.9525)
			(end 0.4318 -0.9525)
			(stroke
				(width 0)
				(type default)
			)
			(fill no)
			(layer "F.Fab")
		)
		(pad "1" smd custom
			(at 0 -0.4445 90)
			(size 0.1524 0.1524)
			(layers "F.Cu" "F.Mask" "F.Paste")
			(net "P3V3")
			(options
				(clearance outline)
				(anchor circle)
			)
			(primitives
				(gr_poly
					(pts
						(arc
							(start 0.3048 -0.2032)
							(mid 0.275042 -0.275042)
							(end 0.2032 -0.3048)
						)
						(arc
							(start -0.2032 -0.3048)
							(mid -0.275042 -0.275042)
							(end -0.3048 -0.2032)
						)
						(arc
							(start -0.3048 0.2032)
							(mid -0.275042 0.275042)
							(end -0.2032 0.3048)
						)
						(arc
							(start 0.2032 0.3048)
							(mid 0.275042 0.275042)
							(end 0.3048 0.2032)
						)
					)
					(width 0)
					(fill yes)
				)
			)
		)
		(pad "2" smd custom
			(at 0 0.4445 90)
			(size 0.1524 0.1524)
			(layers "F.Cu" "F.Mask" "F.Paste")
			(net "GND")
			(options
				(clearance outline)
				(anchor circle)
			)
			(primitives
				(gr_poly
					(pts
						(arc
							(start 0.3048 -0.2032)
							(mid 0.275042 -0.275042)
							(end 0.2032 -0.3048)
						)
						(arc
							(start -0.2032 -0.3048)
							(mid -0.275042 -0.275042)
							(end -0.3048 -0.2032)
						)
						(arc
							(start -0.3048 0.2032)
							(mid -0.275042 0.275042)
							(end -0.2032 0.3048)
						)
						(arc
							(start 0.2032 0.3048)
							(mid 0.275042 0.275042)
							(end 0.3048 0.2032)
						)
					)
					(width 0)
					(fill yes)
				)
			)
		)
	)
	(footprint ""
		(layer "F.Cu")
		(at 94.615 -87.503 -90)
		(property "Reference" "R306"
			(at 0 0 270)
			(layer "F.SilkS")
			(hide yes)
			(effects
				(font
					(size 1.27 1.27)
				)
			)
		)
		(property "Value" "10KR2F-2-GP"
			(at 0.064008 -3.993896 270)
			(unlocked yes)
			(layer "F.Fab")
			(hide yes)
			(effects
				(font
					(size 1.016 1.016)
					(thickness 0.1524)
				)
			)
		)
		(property "Device Type" "R402H16"
			(at 0.064008 -5.517896 270)
			(unlocked yes)
			(layer "F.Fab")
			(hide yes)
			(effects
				(font
					(size 1.016 1.016)
					(thickness 0.1524)
				)
			)
		)
		(duplicate_pad_numbers_are_jumpers no)
		(fp_line
			(start -0.508 -0.9398)
			(end -0.508 0.9398)
			(stroke
				(width 0.1524)
				(type default)
			)
			(layer "F.SilkS")
		)
		(fp_line
			(start 0.508 -0.9398)
			(end -0.508 -0.9398)
			(stroke
				(width 0.1524)
				(type default)
			)
			(layer "F.SilkS")
		)
		(fp_rect
			(start -0.508 0.9398)
			(end 0.508 -0.9398)
			(stroke
				(width 0)
				(type default)
			)
			(fill no)
			(layer "F.CrtYd")
		)
		(fp_rect
			(start -0.508 0.9398)
			(end 0.508 -0.9398)
			(stroke
				(width 0)
				(type default)
			)
			(fill no)
			(layer "F.Fab")
		)
		(pad "1" smd custom
			(at 0 -0.4445 270)
			(size 0.1397 0.1397)
			(layers "F.Cu" "F.Mask" "F.Paste")
			(net "BMC_RMT_HEARTBEAT_LS")
			(options
				(clearance outline)
				(anchor circle)
			)
			(primitives
				(gr_poly
					(pts
						(arc
							(start -0.1778 -0.2794)
							(mid -0.249642 -0.249642)
							(end -0.2794 -0.1778)
						)
						(arc
							(start -0.2794 0.1778)
							(mid -0.249642 0.249642)
							(end -0.1778 0.2794)
						)
						(arc
							(start 0.1778 0.2794)
							(mid 0.249642 0.249642)
							(end 0.2794 0.1778)
						)
						(arc
							(start 0.2794 -0.1778)
							(mid 0.249642 -0.249642)
							(end 0.1778 -0.2794)
						)
					)
					(width 0)
					(fill yes)
				)
			)
		)
		(pad "2" smd custom
			(at 0 0.4445 270)
			(size 0.1397 0.1397)
			(layers "F.Cu" "F.Mask" "F.Paste")
			(net "GND")
			(options
				(clearance outline)
				(anchor circle)
			)
			(primitives
				(gr_poly
					(pts
						(arc
							(start -0.1778 -0.2794)
							(mid -0.249642 -0.249642)
							(end -0.2794 -0.1778)
						)
						(arc
							(start -0.2794 0.1778)
							(mid -0.249642 0.249642)
							(end -0.1778 0.2794)
						)
						(arc
							(start 0.1778 0.2794)
							(mid 0.249642 0.249642)
							(end 0.2794 0.1778)
						)
						(arc
							(start 0.2794 -0.1778)
							(mid 0.249642 -0.249642)
							(end 0.1778 -0.2794)
						)
					)
					(width 0)
					(fill yes)
				)
			)
		)
	)
	(footprint ""
		(layer "F.Cu")
		(at 20.6502 -46.99)
		(property "Reference" "C649"
			(at 0 0 0)
			(layer "F.SilkS")
			(hide yes)
			(effects
				(font
					(size 1.27 1.27)
				)
			)
		)
		(property "Value" "SC1U16V3KX-5GP"
			(at 0 -2.8194 0)
			(unlocked yes)
			(layer "F.Fab")
			(hide yes)
			(effects
				(font
					(size 1.016 1.016)
					(thickness 0.1524)
				)
			)
		)
		(property "Device Type" "C603H36"
			(at 0 -4.3434 0)
			(unlocked yes)
			(layer "F.Fab")
			(hide yes)
			(effects
				(font
					(size 1.016 1.016)
					(thickness 0.1524)
				)
			)
		)
		(duplicate_pad_numbers_are_jumpers no)
		(fp_line
			(start 0.508 0)
			(end -0.508 0)
			(stroke
				(width 0.2032)
				(type default)
			)
			(layer "F.SilkS")
		)
		(fp_rect
			(start -0.5842 1.3335)
			(end 0.5842 -1.3335)
			(stroke
				(width 0)
				(type default)
			)
			(fill no)
			(layer "F.CrtYd")
		)
		(fp_rect
			(start -0.5842 1.3335)
			(end 0.5842 -1.3335)
			(stroke
				(width 0)
				(type default)
			)
			(fill no)
			(layer "F.Fab")
		)
		(pad "1" smd custom
			(at 0 -0.762)
			(size 0.2159 0.2159)
			(layers "F.Cu" "F.Mask" "F.Paste")
			(net "MB0_CM_OV_R")
			(options
				(clearance outline)
				(anchor circle)
			)
			(primitives
				(gr_poly
					(pts
						(arc
							(start -0.3302 -0.4318)
							(mid -0.402042 -0.402042)
							(end -0.4318 -0.3302)
						)
						(arc
							(start -0.4318 0.3302)
							(mid -0.402042 0.402042)
							(end -0.3302 0.4318)
						)
						(arc
							(start 0.3302 0.4318)
							(mid 0.402042 0.402042)
							(end 0.4318 0.3302)
						)
						(arc
							(start 0.4318 -0.3302)
							(mid 0.402042 -0.402042)
							(end 0.3302 -0.4318)
						)
					)
					(width 0)
					(fill yes)
				)
			)
		)
		(pad "2" smd custom
			(at 0 0.762)
			(size 0.2159 0.2159)
			(layers "F.Cu" "F.Mask" "F.Paste")
			(net "AGND_CURRENT_MON")
			(options
				(clearance outline)
				(anchor circle)
			)
			(primitives
				(gr_poly
					(pts
						(arc
							(start -0.3302 -0.4318)
							(mid -0.402042 -0.402042)
							(end -0.4318 -0.3302)
						)
						(arc
							(start -0.4318 0.3302)
							(mid -0.402042 0.402042)
							(end -0.3302 0.4318)
						)
						(arc
							(start 0.3302 0.4318)
							(mid 0.402042 0.402042)
							(end 0.4318 0.3302)
						)
						(arc
							(start 0.4318 -0.3302)
							(mid 0.402042 -0.402042)
							(end 0.3302 -0.4318)
						)
					)
					(width 0)
					(fill yes)
				)
			)
		)
	)
	(footprint ""
		(layer "F.Cu")
		(at 83.994244 -112.65154 90)
		(property "Reference" "R555"
			(at 0 0 90)
			(layer "F.SilkS")
			(hide yes)
			(effects
				(font
					(size 1.27 1.27)
				)
			)
		)
		(property "Value" "10KR2F-2-GP"
			(at 0.064008 -3.993896 90)
			(unlocked yes)
			(layer "F.Fab")
			(hide yes)
			(effects
				(font
					(size 1.016 1.016)
					(thickness 0.1524)
				)
			)
		)
		(property "Device Type" "R402H16"
			(at 0.064008 -5.517896 90)
			(unlocked yes)
			(layer "F.Fab")
			(hide yes)
			(effects
				(font
					(size 1.016 1.016)
					(thickness 0.1524)
				)
			)
		)
		(duplicate_pad_numbers_are_jumpers no)
		(fp_line
			(start 0.508 -0.9398)
			(end -0.508 -0.9398)
			(stroke
				(width 0.1524)
				(type default)
			)
			(layer "F.SilkS")
		)
		(fp_line
			(start -0.508 -0.9398)
			(end -0.508 0.9398)
			(stroke
				(width 0.1524)
				(type default)
			)
			(layer "F.SilkS")
		)
		(fp_rect
			(start -0.508 0.9398)
			(end 0.508 -0.9398)
			(stroke
				(width 0)
				(type default)
			)
			(fill no)
			(layer "F.CrtYd")
		)
		(fp_rect
			(start -0.508 0.9398)
			(end 0.508 -0.9398)
			(stroke
				(width 0)
				(type default)
			)
			(fill no)
			(layer "F.Fab")
		)
		(pad "1" smd custom
			(at 0 -0.4445 90)
			(size 0.1397 0.1397)
			(layers "F.Cu" "F.Mask" "F.Paste")
			(net "P3V3")
			(options
				(clearance outline)
				(anchor circle)
			)
			(primitives
				(gr_poly
					(pts
						(arc
							(start -0.1778 -0.2794)
							(mid -0.249642 -0.249642)
							(end -0.2794 -0.1778)
						)
						(arc
							(start -0.2794 0.1778)
							(mid -0.249642 0.249642)
							(end -0.1778 0.2794)
						)
						(arc
							(start 0.1778 0.2794)
							(mid 0.249642 0.249642)
							(end 0.2794 0.1778)
						)
						(arc
							(start 0.2794 -0.1778)
							(mid 0.249642 -0.249642)
							(end 0.1778 -0.2794)
						)
					)
					(width 0)
					(fill yes)
				)
			)
		)
		(pad "2" smd custom
			(at 0 0.4445 90)
			(size 0.1397 0.1397)
			(layers "F.Cu" "F.Mask" "F.Paste")
			(net "U48_OE")
			(options
				(clearance outline)
				(anchor circle)
			)
			(primitives
				(gr_poly
					(pts
						(arc
							(start -0.1778 -0.2794)
							(mid -0.249642 -0.249642)
							(end -0.2794 -0.1778)
						)
						(arc
							(start -0.2794 0.1778)
							(mid -0.249642 0.249642)
							(end -0.1778 0.2794)
						)
						(arc
							(start 0.1778 0.2794)
							(mid 0.249642 0.249642)
							(end 0.2794 0.1778)
						)
						(arc
							(start 0.2794 -0.1778)
							(mid 0.249642 -0.249642)
							(end 0.1778 -0.2794)
						)
					)
					(width 0)
					(fill yes)
				)
			)
		)
	)
	(footprint ""
		(layer "F.Cu")
		(at 22.83333 -94.850204 180)
		(property "Reference" "C570"
			(at 0 0 180)
			(layer "F.SilkS")
			(hide yes)
			(effects
				(font
					(size 1.27 1.27)
				)
			)
		)
		(property "Value" "SCD1U16V2KX-3GP"
			(at 1.1811 -2.7051 180)
			(unlocked yes)
			(layer "F.Fab")
			(hide yes)
			(effects
				(font
					(size 1.016 1.016)
					(thickness 0.1524)
				)
			)
		)
		(property "Device Type" "C402H22"
			(at 1.1811 -4.2291 180)
			(unlocked yes)
			(layer "F.Fab")
			(hide yes)
			(effects
				(font
					(size 1.016 1.016)
					(thickness 0.1524)
				)
			)
		)
		(duplicate_pad_numbers_are_jumpers no)
		(fp_rect
			(start -0.4318 0.9525)
			(end 0.4318 -0.9525)
			(stroke
				(width 0)
				(type default)
			)
			(fill no)
			(layer "F.CrtYd")
		)
		(fp_rect
			(start -0.4318 0.9525)
			(end 0.4318 -0.9525)
			(stroke
				(width 0)
				(type default)
			)
			(fill no)
			(layer "F.Fab")
		)
		(pad "1" smd custom
			(at 0 -0.4445 180)
			(size 0.1524 0.1524)
			(layers "F.Cu" "F.Mask" "F.Paste")
			(net "VREF1")
			(options
				(clearance outline)
				(anchor circle)
			)
			(primitives
				(gr_poly
					(pts
						(arc
							(start 0.3048 -0.2032)
							(mid 0.275042 -0.275042)
							(end 0.2032 -0.3048)
						)
						(arc
							(start -0.2032 -0.3048)
							(mid -0.275042 -0.275042)
							(end -0.3048 -0.2032)
						)
						(arc
							(start -0.3048 0.2032)
							(mid -0.275042 0.275042)
							(end -0.2032 0.3048)
						)
						(arc
							(start 0.2032 0.3048)
							(mid 0.275042 0.275042)
							(end 0.3048 0.2032)
						)
					)
					(width 0)
					(fill yes)
				)
			)
		)
		(pad "2" smd custom
			(at 0 0.4445 180)
			(size 0.1524 0.1524)
			(layers "F.Cu" "F.Mask" "F.Paste")
			(net "GND")
			(options
				(clearance outline)
				(anchor circle)
			)
			(primitives
				(gr_poly
					(pts
						(arc
							(start 0.3048 -0.2032)
							(mid 0.275042 -0.275042)
							(end 0.2032 -0.3048)
						)
						(arc
							(start -0.2032 -0.3048)
							(mid -0.275042 -0.275042)
							(end -0.3048 -0.2032)
						)
						(arc
							(start -0.3048 0.2032)
							(mid -0.275042 0.275042)
							(end -0.2032 0.3048)
						)
						(arc
							(start 0.2032 0.3048)
							(mid 0.275042 0.275042)
							(end 0.3048 0.2032)
						)
					)
					(width 0)
					(fill yes)
				)
			)
		)
	)
	(footprint ""
		(layer "F.Cu")
		(at 169.6466 -113.0046 180)
		(property "Reference" "R95"
			(at 0 0 180)
			(layer "F.SilkS")
			(hide yes)
			(effects
				(font
					(size 1.27 1.27)
				)
			)
		)
		(property "Value" "0R2J-2-GP"
			(at 0.064008 -3.993896 180)
			(unlocked yes)
			(layer "F.Fab")
			(hide yes)
			(effects
				(font
					(size 1.016 1.016)
					(thickness 0.1524)
				)
			)
		)
		(property "Device Type" "R402H16"
			(at 0.064008 -5.517896 180)
			(unlocked yes)
			(layer "F.Fab")
			(hide yes)
			(effects
				(font
					(size 1.016 1.016)
					(thickness 0.1524)
				)
			)
		)
		(duplicate_pad_numbers_are_jumpers no)
		(fp_line
			(start 0.508 -0.9398)
			(end -0.508 -0.9398)
			(stroke
				(width 0.1524)
				(type default)
			)
			(layer "F.SilkS")
		)
		(fp_line
			(start -0.508 -0.9398)
			(end -0.508 0.9398)
			(stroke
				(width 0.1524)
				(type default)
			)
			(layer "F.SilkS")
		)
		(fp_rect
			(start -0.508 0.9398)
			(end 0.508 -0.9398)
			(stroke
				(width 0)
				(type default)
			)
			(fill no)
			(layer "F.CrtYd")
		)
		(fp_rect
			(start -0.508 0.9398)
			(end 0.508 -0.9398)
			(stroke
				(width 0)
				(type default)
			)
			(fill no)
			(layer "F.Fab")
		)
		(pad "1" smd custom
			(at 0 -0.4445 180)
			(size 0.1397 0.1397)
			(layers "F.Cu" "F.Mask" "F.Paste")
			(net "P5V")
			(options
				(clearance outline)
				(anchor circle)
			)
			(primitives
				(gr_poly
					(pts
						(arc
							(start -0.1778 -0.2794)
							(mid -0.249642 -0.249642)
							(end -0.2794 -0.1778)
						)
						(arc
							(start -0.2794 0.1778)
							(mid -0.249642 0.249642)
							(end -0.1778 0.2794)
						)
						(arc
							(start 0.1778 0.2794)
							(mid 0.249642 0.249642)
							(end 0.2794 0.1778)
						)
						(arc
							(start 0.2794 -0.1778)
							(mid 0.249642 -0.249642)
							(end 0.1778 -0.2794)
						)
					)
					(width 0)
					(fill yes)
				)
			)
		)
		(pad "2" smd custom
			(at 0 0.4445 180)
			(size 0.1397 0.1397)
			(layers "F.Cu" "F.Mask" "F.Paste")
			(net "P1V8_E_BIAS")
			(options
				(clearance outline)
				(anchor circle)
			)
			(primitives
				(gr_poly
					(pts
						(arc
							(start -0.1778 -0.2794)
							(mid -0.249642 -0.249642)
							(end -0.2794 -0.1778)
						)
						(arc
							(start -0.2794 0.1778)
							(mid -0.249642 0.249642)
							(end -0.1778 0.2794)
						)
						(arc
							(start 0.1778 0.2794)
							(mid 0.249642 0.249642)
							(end 0.2794 0.1778)
						)
						(arc
							(start 0.2794 -0.1778)
							(mid 0.249642 -0.249642)
							(end 0.1778 -0.2794)
						)
					)
					(width 0)
					(fill yes)
				)
			)
		)
	)
	(footprint ""
		(layer "F.Cu")
		(at 136.248902 -75.91552 90)
		(property "Reference" "C683"
			(at 0 0 90)
			(layer "F.SilkS")
			(hide yes)
			(effects
				(font
					(size 1.27 1.27)
				)
			)
		)
		(property "Value" "SCD01U16V1KX-GP"
			(at -2.8321 -1.7399 90)
			(unlocked yes)
			(layer "F.Fab")
			(hide yes)
			(effects
				(font
					(size 1.016 1.016)
					(thickness 0.1524)
				)
			)
		)
		(property "Device Type" "C0201H13"
			(at -2.8321 -3.2639 90)
			(unlocked yes)
			(layer "F.Fab")
			(hide yes)
			(effects
				(font
					(size 1.016 1.016)
					(thickness 0.1524)
				)
			)
		)
		(duplicate_pad_numbers_are_jumpers no)
		(fp_rect
			(start -0.2794 0.6477)
			(end 0.2794 -0.6477)
			(stroke
				(width 0)
				(type default)
			)
			(fill no)
			(layer "F.CrtYd")
		)
		(fp_rect
			(start -0.2794 0.6477)
			(end 0.2794 -0.6477)
			(stroke
				(width 0)
				(type default)
			)
			(fill no)
			(layer "F.Fab")
		)
		(pad "1" smd custom
			(at 0 -0.2794 90)
			(size 0.0762 0.0762)
			(layers "F.Cu" "F.Mask" "F.Paste")
			(net "PHY_EXP_TO_CONN_C_8_DN")
			(options
				(clearance outline)
				(anchor circle)
			)
			(primitives
				(gr_poly
					(pts
						(arc
							(start 0.1524 -0.127)
							(mid 0.137521 -0.162921)
							(end 0.1016 -0.1778)
						)
						(arc
							(start -0.1016 -0.1778)
							(mid -0.137521 -0.162921)
							(end -0.1524 -0.127)
						)
						(arc
							(start -0.1524 0.127)
							(mid -0.137521 0.162921)
							(end -0.1016 0.1778)
						)
						(arc
							(start 0.1016 0.1778)
							(mid 0.137521 0.162921)
							(end 0.1524 0.127)
						)
					)
					(width 0)
					(fill yes)
				)
			)
		)
		(pad "2" smd custom
			(at 0 0.2794 90)
			(size 0.0762 0.0762)
			(layers "F.Cu" "F.Mask" "F.Paste")
			(net "PHY_EXP_TO_CONN_8_DN")
			(options
				(clearance outline)
				(anchor circle)
			)
			(primitives
				(gr_poly
					(pts
						(arc
							(start 0.1524 -0.127)
							(mid 0.137521 -0.162921)
							(end 0.1016 -0.1778)
						)
						(arc
							(start -0.1016 -0.1778)
							(mid -0.137521 -0.162921)
							(end -0.1524 -0.127)
						)
						(arc
							(start -0.1524 0.127)
							(mid -0.137521 0.162921)
							(end -0.1016 0.1778)
						)
						(arc
							(start 0.1016 0.1778)
							(mid 0.137521 0.162921)
							(end 0.1524 0.127)
						)
					)
					(width 0)
					(fill yes)
				)
			)
		)
	)
	(footprint ""
		(layer "F.Cu")
		(at 160.274 -86.741 90)
		(property "Reference" "C518"
			(at 0 0 90)
			(layer "F.SilkS")
			(hide yes)
			(effects
				(font
					(size 1.27 1.27)
				)
			)
		)
		(property "Value" "SC1U16V2KX-7-GP"
			(at 1.7526 -1.6002 90)
			(unlocked yes)
			(layer "F.Fab")
			(hide yes)
			(effects
				(font
					(size 1.016 1.016)
					(thickness 0.1524)
				)
			)
		)
		(property "Device Type" "C402-TO0D2H24"
			(at 1.7526 -3.1242 90)
			(unlocked yes)
			(layer "F.Fab")
			(hide yes)
			(effects
				(font
					(size 1.016 1.016)
					(thickness 0.1524)
				)
			)
		)
		(duplicate_pad_numbers_are_jumpers no)
		(fp_rect
			(start -0.4826 0.889)
			(end 0.4826 -0.889)
			(stroke
				(width 0)
				(type default)
			)
			(fill no)
			(layer "F.CrtYd")
		)
		(fp_rect
			(start -0.4826 0.889)
			(end 0.4826 -0.889)
			(stroke
				(width 0)
				(type default)
			)
			(fill no)
			(layer "F.Fab")
		)
		(pad "1" smd custom
			(at 0 -0.4572 90)
			(size 0.1524 0.1524)
			(layers "F.Cu" "F.Mask" "F.Paste")
			(net "P3V3")
			(options
				(clearance outline)
				(anchor circle)
			)
			(primitives
				(gr_poly
					(pts
						(arc
							(start -0.254 0.3048)
							(mid -0.325842 0.275042)
							(end -0.3556 0.2032)
						)
						(arc
							(start -0.3556 -0.2032)
							(mid -0.325842 -0.275042)
							(end -0.254 -0.3048)
						)
						(arc
							(start 0.254 -0.3048)
							(mid 0.325842 -0.275042)
							(end 0.3556 -0.2032)
						)
						(arc
							(start 0.3556 0.2032)
							(mid 0.325842 0.275042)
							(end 0.254 0.3048)
						)
					)
					(width 0)
					(fill yes)
				)
			)
		)
		(pad "2" smd custom
			(at 0 0.4572 90)
			(size 0.1524 0.1524)
			(layers "F.Cu" "F.Mask" "F.Paste")
			(net "GND")
			(options
				(clearance outline)
				(anchor circle)
			)
			(primitives
				(gr_poly
					(pts
						(arc
							(start -0.254 0.3048)
							(mid -0.325842 0.275042)
							(end -0.3556 0.2032)
						)
						(arc
							(start -0.3556 -0.2032)
							(mid -0.325842 -0.275042)
							(end -0.254 -0.3048)
						)
						(arc
							(start 0.254 -0.3048)
							(mid 0.325842 -0.275042)
							(end 0.3556 -0.2032)
						)
						(arc
							(start 0.3556 0.2032)
							(mid 0.325842 0.275042)
							(end 0.254 0.3048)
						)
					)
					(width 0)
					(fill yes)
				)
			)
		)
	)
	(footprint ""
		(layer "F.Cu")
		(at 73.533 -62.23 180)
		(property "Reference" "C262"
			(at 0 0 180)
			(layer "F.SilkS")
			(hide yes)
			(effects
				(font
					(size 1.27 1.27)
				)
			)
		)
		(property "Value" "SC100U6D3V6MX-GP"
			(at -0.0762 -5.1308 180)
			(unlocked yes)
			(layer "F.Fab")
			(hide yes)
			(effects
				(font
					(size 1.016 1.016)
					(thickness 0.1524)
				)
			)
		)
		(property "Device Type" "C1206H71"
			(at -0.127 -6.6548 180)
			(unlocked yes)
			(layer "F.Fab")
			(hide yes)
			(effects
				(font
					(size 1.016 1.016)
					(thickness 0.1524)
				)
			)
		)
		(duplicate_pad_numbers_are_jumpers no)
		(fp_line
			(start 1.016 2.2352)
			(end -1.016 2.2352)
			(stroke
				(width 0.1524)
				(type default)
			)
			(layer "F.SilkS")
		)
		(fp_line
			(start 1.016 0.8382)
			(end 1.016 2.2352)
			(stroke
				(width 0.1524)
				(type default)
			)
			(layer "F.SilkS")
		)
		(fp_line
			(start 1.016 -2.2352)
			(end 1.016 -0.8382)
			(stroke
				(width 0.1524)
				(type default)
			)
			(layer "F.SilkS")
		)
		(fp_line
			(start -1.016 2.2352)
			(end -1.016 0.8382)
			(stroke
				(width 0.1524)
				(type default)
			)
			(layer "F.SilkS")
		)
		(fp_line
			(start -1.016 -0.8382)
			(end -1.016 -2.2352)
			(stroke
				(width 0.1524)
				(type default)
			)
			(layer "F.SilkS")
		)
		(fp_line
			(start -1.016 -2.2352)
			(end 1.016 -2.2352)
			(stroke
				(width 0.1524)
				(type default)
			)
			(layer "F.SilkS")
		)
		(fp_rect
			(start -1.0922 2.3114)
			(end 1.0922 -2.3114)
			(stroke
				(width 0)
				(type default)
			)
			(fill no)
			(layer "F.CrtYd")
		)
		(fp_poly
			(pts
				(xy 1.0922 -2.3114) (xy 1.0922 2.3114) (xy -1.0922 2.3114) (xy -1.0922 -2.3114)
			)
			(stroke
				(width 0)
				(type default)
			)
			(fill no)
			(layer "F.Fab")
		)
		(pad "1" smd rect
			(at 0 -1.397 180)
			(size 1.651 1.27)
			(layers "F.Cu" "F.Mask" "F.Paste")
			(net "GB_VDDA")
		)
		(pad "2" smd rect
			(at 0 1.397 180)
			(size 1.651 1.27)
			(layers "F.Cu" "F.Mask" "F.Paste")
			(net "GND")
		)
	)
	(footprint ""
		(layer "F.Cu")
		(at 171.54652 -115.86464 180)
		(property "Reference" "R607"
			(at 0 0 180)
			(layer "F.SilkS")
			(hide yes)
			(effects
				(font
					(size 1.27 1.27)
				)
			)
		)
		(property "Value" "1KR2J-1-GP"
			(at 0.064008 -3.993896 180)
			(unlocked yes)
			(layer "F.Fab")
			(hide yes)
			(effects
				(font
					(size 1.016 1.016)
					(thickness 0.1524)
				)
			)
		)
		(property "Device Type" "R402H16"
			(at 0.064008 -5.517896 180)
			(unlocked yes)
			(layer "F.Fab")
			(hide yes)
			(effects
				(font
					(size 1.016 1.016)
					(thickness 0.1524)
				)
			)
		)
		(duplicate_pad_numbers_are_jumpers no)
		(fp_line
			(start 0.508 -0.9398)
			(end -0.508 -0.9398)
			(stroke
				(width 0.1524)
				(type default)
			)
			(layer "F.SilkS")
		)
		(fp_line
			(start -0.508 -0.9398)
			(end -0.508 0.9398)
			(stroke
				(width 0.1524)
				(type default)
			)
			(layer "F.SilkS")
		)
		(fp_rect
			(start -0.508 0.9398)
			(end 0.508 -0.9398)
			(stroke
				(width 0)
				(type default)
			)
			(fill no)
			(layer "F.CrtYd")
		)
		(fp_rect
			(start -0.508 0.9398)
			(end 0.508 -0.9398)
			(stroke
				(width 0)
				(type default)
			)
			(fill no)
			(layer "F.Fab")
		)
		(pad "1" smd custom
			(at 0 -0.4445 180)
			(size 0.1397 0.1397)
			(layers "F.Cu" "F.Mask" "F.Paste")
			(net "P1V8_E_PG")
			(options
				(clearance outline)
				(anchor circle)
			)
			(primitives
				(gr_poly
					(pts
						(arc
							(start -0.1778 -0.2794)
							(mid -0.249642 -0.249642)
							(end -0.2794 -0.1778)
						)
						(arc
							(start -0.2794 0.1778)
							(mid -0.249642 0.249642)
							(end -0.1778 0.2794)
						)
						(arc
							(start 0.1778 0.2794)
							(mid 0.249642 0.249642)
							(end 0.2794 0.1778)
						)
						(arc
							(start 0.2794 -0.1778)
							(mid 0.249642 -0.249642)
							(end 0.1778 -0.2794)
						)
					)
					(width 0)
					(fill yes)
				)
			)
		)
		(pad "2" smd custom
			(at 0 0.4445 180)
			(size 0.1397 0.1397)
			(layers "F.Cu" "F.Mask" "F.Paste")
			(net "P3V3")
			(options
				(clearance outline)
				(anchor circle)
			)
			(primitives
				(gr_poly
					(pts
						(arc
							(start -0.1778 -0.2794)
							(mid -0.249642 -0.249642)
							(end -0.2794 -0.1778)
						)
						(arc
							(start -0.2794 0.1778)
							(mid -0.249642 0.249642)
							(end -0.1778 0.2794)
						)
						(arc
							(start 0.1778 0.2794)
							(mid 0.249642 0.249642)
							(end 0.2794 0.1778)
						)
						(arc
							(start 0.2794 -0.1778)
							(mid 0.249642 -0.249642)
							(end 0.1778 -0.2794)
						)
					)
					(width 0)
					(fill yes)
				)
			)
		)
	)
	(footprint ""
		(layer "F.Cu")
		(at 181.8386 -118.8466 90)
		(property "Reference" "C688"
			(at 0 0 90)
			(layer "F.SilkS")
			(hide yes)
			(effects
				(font
					(size 1.27 1.27)
				)
			)
		)
		(property "Value" "SC10U6D3V5KX-4GP"
			(at -0.0762 -6.1214 90)
			(unlocked yes)
			(layer "F.Fab")
			(hide yes)
			(effects
				(font
					(size 1.016 1.016)
					(thickness 0.1524)
				)
			)
		)
		(property "Device Type" "C805H58"
			(at -0.0762 -8.1534 90)
			(unlocked yes)
			(layer "F.Fab")
			(hide yes)
			(effects
				(font
					(size 1.016 1.016)
					(thickness 0.1524)
				)
			)
		)
		(duplicate_pad_numbers_are_jumpers no)
		(fp_line
			(start 0.635 0)
			(end -0.635 0)
			(stroke
				(width 0.508)
				(type default)
			)
			(layer "F.SilkS")
		)
		(fp_rect
			(start -0.9652 1.778)
			(end 0.9652 -1.778)
			(stroke
				(width 0)
				(type default)
			)
			(fill no)
			(layer "F.CrtYd")
		)
		(fp_poly
			(pts
				(xy -0.9652 -1.778) (xy 0.9652 -1.778) (xy 0.9652 1.778) (xy -0.9652 1.778)
			)
			(stroke
				(width 0)
				(type default)
			)
			(fill no)
			(layer "F.Fab")
		)
		(pad "1" smd rect
			(at 0 -0.9652 90)
			(size 1.397 1.143)
			(layers "F.Cu" "F.Mask" "F.Paste")
			(net "P1V8_E_OUT")
		)
		(pad "2" smd rect
			(at 0 0.9652 90)
			(size 1.397 1.143)
			(layers "F.Cu" "F.Mask" "F.Paste")
			(net "GND")
		)
	)
	(footprint ""
		(layer "F.Cu")
		(at 45.1612 -27.94 90)
		(property "Reference" "R399"
			(at 0 0 90)
			(layer "F.SilkS")
			(hide yes)
			(effects
				(font
					(size 1.27 1.27)
				)
			)
		)
		(property "Value" "8K06R2F-GP"
			(at 0.064008 -3.993896 90)
			(unlocked yes)
			(layer "F.Fab")
			(hide yes)
			(effects
				(font
					(size 1.016 1.016)
					(thickness 0.1524)
				)
			)
		)
		(property "Device Type" "R402H16"
			(at 0.064008 -5.517896 90)
			(unlocked yes)
			(layer "F.Fab")
			(hide yes)
			(effects
				(font
					(size 1.016 1.016)
					(thickness 0.1524)
				)
			)
		)
		(duplicate_pad_numbers_are_jumpers no)
		(fp_line
			(start 0.508 -0.9398)
			(end -0.508 -0.9398)
			(stroke
				(width 0.1524)
				(type default)
			)
			(layer "F.SilkS")
		)
		(fp_line
			(start -0.508 -0.9398)
			(end -0.508 0.9398)
			(stroke
				(width 0.1524)
				(type default)
			)
			(layer "F.SilkS")
		)
		(fp_rect
			(start -0.508 0.9398)
			(end 0.508 -0.9398)
			(stroke
				(width 0)
				(type default)
			)
			(fill no)
			(layer "F.CrtYd")
		)
		(fp_rect
			(start -0.508 0.9398)
			(end 0.508 -0.9398)
			(stroke
				(width 0)
				(type default)
			)
			(fill no)
			(layer "F.Fab")
		)
		(pad "1" smd custom
			(at 0 -0.4445 90)
			(size 0.1397 0.1397)
			(layers "F.Cu" "F.Mask" "F.Paste")
			(net "P0V9_REFIN")
			(options
				(clearance outline)
				(anchor circle)
			)
			(primitives
				(gr_poly
					(pts
						(arc
							(start -0.1778 -0.2794)
							(mid -0.249642 -0.249642)
							(end -0.2794 -0.1778)
						)
						(arc
							(start -0.2794 0.1778)
							(mid -0.249642 0.249642)
							(end -0.1778 0.2794)
						)
						(arc
							(start 0.1778 0.2794)
							(mid 0.249642 0.249642)
							(end 0.2794 0.1778)
						)
						(arc
							(start 0.2794 -0.1778)
							(mid 0.249642 -0.249642)
							(end 0.1778 -0.2794)
						)
					)
					(width 0)
					(fill yes)
				)
			)
		)
		(pad "2" smd custom
			(at 0 0.4445 90)
			(size 0.1397 0.1397)
			(layers "F.Cu" "F.Mask" "F.Paste")
			(net "P0V9_GSNS")
			(options
				(clearance outline)
				(anchor circle)
			)
			(primitives
				(gr_poly
					(pts
						(arc
							(start -0.1778 -0.2794)
							(mid -0.249642 -0.249642)
							(end -0.2794 -0.1778)
						)
						(arc
							(start -0.2794 0.1778)
							(mid -0.249642 0.249642)
							(end -0.1778 0.2794)
						)
						(arc
							(start 0.1778 0.2794)
							(mid 0.249642 0.249642)
							(end 0.2794 0.1778)
						)
						(arc
							(start 0.2794 -0.1778)
							(mid 0.249642 -0.249642)
							(end 0.1778 -0.2794)
						)
					)
					(width 0)
					(fill yes)
				)
			)
		)
	)
	(footprint ""
		(layer "F.Cu")
		(at 7.366 -82.042 90)
		(property "Reference" "R335"
			(at 0 0 90)
			(layer "F.SilkS")
			(hide yes)
			(effects
				(font
					(size 1.27 1.27)
				)
			)
		)
		(property "Value" "4K7R2F-GP"
			(at 0.064008 -3.993896 90)
			(unlocked yes)
			(layer "F.Fab")
			(hide yes)
			(effects
				(font
					(size 1.016 1.016)
					(thickness 0.1524)
				)
			)
		)
		(property "Device Type" "R402H16"
			(at 0.064008 -5.517896 90)
			(unlocked yes)
			(layer "F.Fab")
			(hide yes)
			(effects
				(font
					(size 1.016 1.016)
					(thickness 0.1524)
				)
			)
		)
		(duplicate_pad_numbers_are_jumpers no)
		(fp_line
			(start 0.508 -0.9398)
			(end -0.508 -0.9398)
			(stroke
				(width 0.1524)
				(type default)
			)
			(layer "F.SilkS")
		)
		(fp_line
			(start -0.508 -0.9398)
			(end -0.508 0.9398)
			(stroke
				(width 0.1524)
				(type default)
			)
			(layer "F.SilkS")
		)
		(fp_rect
			(start -0.508 0.9398)
			(end 0.508 -0.9398)
			(stroke
				(width 0)
				(type default)
			)
			(fill no)
			(layer "F.CrtYd")
		)
		(fp_rect
			(start -0.508 0.9398)
			(end 0.508 -0.9398)
			(stroke
				(width 0)
				(type default)
			)
			(fill no)
			(layer "F.Fab")
		)
		(pad "1" smd custom
			(at 0 -0.4445 90)
			(size 0.1397 0.1397)
			(layers "F.Cu" "F.Mask" "F.Paste")
			(net "P3V3")
			(options
				(clearance outline)
				(anchor circle)
			)
			(primitives
				(gr_poly
					(pts
						(arc
							(start -0.1778 -0.2794)
							(mid -0.249642 -0.249642)
							(end -0.2794 -0.1778)
						)
						(arc
							(start -0.2794 0.1778)
							(mid -0.249642 0.249642)
							(end -0.1778 0.2794)
						)
						(arc
							(start 0.1778 0.2794)
							(mid 0.249642 0.249642)
							(end 0.2794 0.1778)
						)
						(arc
							(start 0.2794 -0.1778)
							(mid 0.249642 -0.249642)
							(end 0.1778 -0.2794)
						)
					)
					(width 0)
					(fill yes)
				)
			)
		)
		(pad "2" smd custom
			(at 0 0.4445 90)
			(size 0.1397 0.1397)
			(layers "F.Cu" "F.Mask" "F.Paste")
			(net "EXP_EEPROM_A0")
			(options
				(clearance outline)
				(anchor circle)
			)
			(primitives
				(gr_poly
					(pts
						(arc
							(start -0.1778 -0.2794)
							(mid -0.249642 -0.249642)
							(end -0.2794 -0.1778)
						)
						(arc
							(start -0.2794 0.1778)
							(mid -0.249642 0.249642)
							(end -0.1778 0.2794)
						)
						(arc
							(start 0.1778 0.2794)
							(mid 0.249642 0.249642)
							(end 0.2794 0.1778)
						)
						(arc
							(start 0.2794 -0.1778)
							(mid 0.249642 -0.249642)
							(end 0.1778 -0.2794)
						)
					)
					(width 0)
					(fill yes)
				)
			)
		)
	)
	(footprint ""
		(layer "F.Cu")
		(at 7.366 -79.756 -90)
		(property "Reference" "R345"
			(at 0 0 270)
			(layer "F.SilkS")
			(hide yes)
			(effects
				(font
					(size 1.27 1.27)
				)
			)
		)
		(property "Value" "4K7R2F-GP"
			(at 0.064008 -3.993896 270)
			(unlocked yes)
			(layer "F.Fab")
			(hide yes)
			(effects
				(font
					(size 1.016 1.016)
					(thickness 0.1524)
				)
			)
		)
		(property "Device Type" "R402H16"
			(at 0.064008 -5.517896 270)
			(unlocked yes)
			(layer "F.Fab")
			(hide yes)
			(effects
				(font
					(size 1.016 1.016)
					(thickness 0.1524)
				)
			)
		)
		(duplicate_pad_numbers_are_jumpers no)
		(fp_line
			(start -0.508 -0.9398)
			(end -0.508 0.9398)
			(stroke
				(width 0.1524)
				(type default)
			)
			(layer "F.SilkS")
		)
		(fp_line
			(start 0.508 -0.9398)
			(end -0.508 -0.9398)
			(stroke
				(width 0.1524)
				(type default)
			)
			(layer "F.SilkS")
		)
		(fp_rect
			(start -0.508 0.9398)
			(end 0.508 -0.9398)
			(stroke
				(width 0)
				(type default)
			)
			(fill no)
			(layer "F.CrtYd")
		)
		(fp_rect
			(start -0.508 0.9398)
			(end 0.508 -0.9398)
			(stroke
				(width 0)
				(type default)
			)
			(fill no)
			(layer "F.Fab")
		)
		(pad "1" smd custom
			(at 0 -0.4445 270)
			(size 0.1397 0.1397)
			(layers "F.Cu" "F.Mask" "F.Paste")
			(net "EXP_EEPROM_A1")
			(options
				(clearance outline)
				(anchor circle)
			)
			(primitives
				(gr_poly
					(pts
						(arc
							(start -0.1778 -0.2794)
							(mid -0.249642 -0.249642)
							(end -0.2794 -0.1778)
						)
						(arc
							(start -0.2794 0.1778)
							(mid -0.249642 0.249642)
							(end -0.1778 0.2794)
						)
						(arc
							(start 0.1778 0.2794)
							(mid 0.249642 0.249642)
							(end 0.2794 0.1778)
						)
						(arc
							(start 0.2794 -0.1778)
							(mid 0.249642 -0.249642)
							(end 0.1778 -0.2794)
						)
					)
					(width 0)
					(fill yes)
				)
			)
		)
		(pad "2" smd custom
			(at 0 0.4445 270)
			(size 0.1397 0.1397)
			(layers "F.Cu" "F.Mask" "F.Paste")
			(net "GND")
			(options
				(clearance outline)
				(anchor circle)
			)
			(primitives
				(gr_poly
					(pts
						(arc
							(start -0.1778 -0.2794)
							(mid -0.249642 -0.249642)
							(end -0.2794 -0.1778)
						)
						(arc
							(start -0.2794 0.1778)
							(mid -0.249642 0.249642)
							(end -0.1778 0.2794)
						)
						(arc
							(start 0.1778 0.2794)
							(mid 0.249642 0.249642)
							(end 0.2794 0.1778)
						)
						(arc
							(start 0.2794 -0.1778)
							(mid 0.249642 -0.249642)
							(end 0.1778 -0.2794)
						)
					)
					(width 0)
					(fill yes)
				)
			)
		)
	)
	(footprint ""
		(layer "F.Cu")
		(at 125.2728 -88.3158)
		(property "Reference" "TP44"
			(at 0 0 0)
			(layer "F.SilkS")
			(hide yes)
			(effects
				(font
					(size 1.27 1.27)
				)
			)
		)
		(property "Value" "TPAD28-2-GP"
			(at -0.0127 -1.6637 0)
			(unlocked yes)
			(layer "F.Fab")
			(hide yes)
			(effects
				(font
					(size 1.016 1.016)
					(thickness 0.1524)
				)
			)
		)
		(property "Device Type" "TPAD28"
			(at -0.0127 -3.1877 0)
			(unlocked yes)
			(layer "F.Fab")
			(hide yes)
			(effects
				(font
					(size 1.016 1.016)
					(thickness 0.1524)
				)
			)
		)
		(duplicate_pad_numbers_are_jumpers no)
		(fp_poly
			(pts
				(arc
					(start 0.3556 0)
					(mid -0.3556 0)
					(end 0.3556 0)
				)
			)
			(stroke
				(width 0)
				(type default)
			)
			(fill no)
			(layer "F.CrtYd")
		)
		(fp_poly
			(pts
				(arc
					(start 0.6096 0)
					(mid -0.6096 0)
					(end 0.6096 0)
				)
			)
			(stroke
				(width 0)
				(type default)
			)
			(fill no)
			(layer "F.Fab")
		)
		(pad "1" smd circle
			(at 0 0)
			(size 0.7112 0.7112)
			(layers "F.Cu" "F.Mask" "F.Paste")
			(net "PHY_CLK")
		)
	)
	(footprint ""
		(layer "F.Cu")
		(at 190.2968 -32.0675 -90)
		(property "Reference" "TP76"
			(at 0 0 270)
			(layer "F.SilkS")
			(hide yes)
			(effects
				(font
					(size 1.27 1.27)
				)
			)
		)
		(property "Value" "TPAD28-2-GP"
			(at -0.0127 -1.6637 270)
			(unlocked yes)
			(layer "F.Fab")
			(hide yes)
			(effects
				(font
					(size 1.016 1.016)
					(thickness 0.1524)
				)
			)
		)
		(property "Device Type" "TPAD28"
			(at -0.0127 -3.1877 270)
			(unlocked yes)
			(layer "F.Fab")
			(hide yes)
			(effects
				(font
					(size 1.016 1.016)
					(thickness 0.1524)
				)
			)
		)
		(duplicate_pad_numbers_are_jumpers no)
		(fp_poly
			(pts
				(arc
					(start 0 -0.3556)
					(mid 0 0.3556)
					(end 0 -0.3556)
				)
			)
			(stroke
				(width 0)
				(type default)
			)
			(fill no)
			(layer "F.CrtYd")
		)
		(fp_poly
			(pts
				(arc
					(start 0 -0.6096)
					(mid 0 0.6096)
					(end 0 -0.6096)
				)
			)
			(stroke
				(width 0)
				(type default)
			)
			(fill no)
			(layer "F.Fab")
		)
		(pad "1" smd circle
			(at 0 0 270)
			(size 0.7112 0.7112)
			(layers "F.Cu" "F.Mask" "F.Paste")
			(net "IOC_GPIO_23")
		)
	)
	(footprint ""
		(layer "F.Cu")
		(at 173.4058 -56.7182)
		(property "Reference" "TP138"
			(at 0 0 0)
			(layer "F.SilkS")
			(hide yes)
			(effects
				(font
					(size 1.27 1.27)
				)
			)
		)
		(property "Value" "TPAD28-2-GP"
			(at -0.0127 -1.6637 0)
			(unlocked yes)
			(layer "F.Fab")
			(hide yes)
			(effects
				(font
					(size 1.016 1.016)
					(thickness 0.1524)
				)
			)
		)
		(property "Device Type" "TPAD28"
			(at -0.0127 -3.1877 0)
			(unlocked yes)
			(layer "F.Fab")
			(hide yes)
			(effects
				(font
					(size 1.016 1.016)
					(thickness 0.1524)
				)
			)
		)
		(duplicate_pad_numbers_are_jumpers no)
		(fp_poly
			(pts
				(arc
					(start 0.3556 0)
					(mid -0.3556 0)
					(end 0.3556 0)
				)
			)
			(stroke
				(width 0)
				(type default)
			)
			(fill no)
			(layer "F.CrtYd")
		)
		(fp_poly
			(pts
				(arc
					(start 0.6096 0)
					(mid -0.6096 0)
					(end 0.6096 0)
				)
			)
			(stroke
				(width 0)
				(type default)
			)
			(fill no)
			(layer "F.Fab")
		)
		(pad "1" smd circle
			(at 0 0)
			(size 0.7112 0.7112)
			(layers "F.Cu" "F.Mask" "F.Paste")
			(net "IOC_TRST_N")
		)
	)
	(footprint ""
		(layer "F.Cu")
		(at 54.6862 -72.5678)
		(property "Reference" "R473"
			(at 0 0 0)
			(layer "F.SilkS")
			(hide yes)
			(effects
				(font
					(size 1.27 1.27)
				)
			)
		)
		(property "Value" "0R2J-2-GP"
			(at 0.064008 -3.993896 0)
			(unlocked yes)
			(layer "F.Fab")
			(hide yes)
			(effects
				(font
					(size 1.016 1.016)
					(thickness 0.1524)
				)
			)
		)
		(property "Device Type" "R402H16"
			(at 0.064008 -5.517896 0)
			(unlocked yes)
			(layer "F.Fab")
			(hide yes)
			(effects
				(font
					(size 1.016 1.016)
					(thickness 0.1524)
				)
			)
		)
		(duplicate_pad_numbers_are_jumpers no)
		(fp_line
			(start -0.508 -0.9398)
			(end -0.508 0.9398)
			(stroke
				(width 0.1524)
				(type default)
			)
			(layer "F.SilkS")
		)
		(fp_line
			(start 0.508 -0.9398)
			(end -0.508 -0.9398)
			(stroke
				(width 0.1524)
				(type default)
			)
			(layer "F.SilkS")
		)
		(fp_rect
			(start -0.508 0.9398)
			(end 0.508 -0.9398)
			(stroke
				(width 0)
				(type default)
			)
			(fill no)
			(layer "F.CrtYd")
		)
		(fp_rect
			(start -0.508 0.9398)
			(end 0.508 -0.9398)
			(stroke
				(width 0)
				(type default)
			)
			(fill no)
			(layer "F.Fab")
		)
		(pad "1" smd custom
			(at 0 -0.4445)
			(size 0.1397 0.1397)
			(layers "F.Cu" "F.Mask" "F.Paste")
			(net "LS_EN_U41")
			(options
				(clearance outline)
				(anchor circle)
			)
			(primitives
				(gr_poly
					(pts
						(arc
							(start -0.1778 -0.2794)
							(mid -0.249642 -0.249642)
							(end -0.2794 -0.1778)
						)
						(arc
							(start -0.2794 0.1778)
							(mid -0.249642 0.249642)
							(end -0.1778 0.2794)
						)
						(arc
							(start 0.1778 0.2794)
							(mid 0.249642 0.249642)
							(end 0.2794 0.1778)
						)
						(arc
							(start 0.2794 -0.1778)
							(mid 0.249642 -0.249642)
							(end 0.1778 -0.2794)
						)
					)
					(width 0)
					(fill yes)
				)
			)
		)
		(pad "2" smd custom
			(at 0 0.4445)
			(size 0.1397 0.1397)
			(layers "F.Cu" "F.Mask" "F.Paste")
			(net "VREF7")
			(options
				(clearance outline)
				(anchor circle)
			)
			(primitives
				(gr_poly
					(pts
						(arc
							(start -0.1778 -0.2794)
							(mid -0.249642 -0.249642)
							(end -0.2794 -0.1778)
						)
						(arc
							(start -0.2794 0.1778)
							(mid -0.249642 0.249642)
							(end -0.1778 0.2794)
						)
						(arc
							(start 0.1778 0.2794)
							(mid 0.249642 0.249642)
							(end 0.2794 0.1778)
						)
						(arc
							(start 0.2794 -0.1778)
							(mid 0.249642 -0.249642)
							(end 0.1778 -0.2794)
						)
					)
					(width 0)
					(fill yes)
				)
			)
		)
	)
	(footprint ""
		(layer "F.Cu")
		(at 114.6556 -86.995 180)
		(property "Reference" "R147"
			(at 0 0 180)
			(layer "F.SilkS")
			(hide yes)
			(effects
				(font
					(size 1.27 1.27)
				)
			)
		)
		(property "Value" "4K7R2F-GP"
			(at 0.064008 -3.993896 180)
			(unlocked yes)
			(layer "F.Fab")
			(hide yes)
			(effects
				(font
					(size 1.016 1.016)
					(thickness 0.1524)
				)
			)
		)
		(property "Device Type" "R402H16"
			(at 0.064008 -5.517896 180)
			(unlocked yes)
			(layer "F.Fab")
			(hide yes)
			(effects
				(font
					(size 1.016 1.016)
					(thickness 0.1524)
				)
			)
		)
		(duplicate_pad_numbers_are_jumpers no)
		(fp_line
			(start 0.508 -0.9398)
			(end -0.508 -0.9398)
			(stroke
				(width 0.1524)
				(type default)
			)
			(layer "F.SilkS")
		)
		(fp_line
			(start -0.508 -0.9398)
			(end -0.508 0.9398)
			(stroke
				(width 0.1524)
				(type default)
			)
			(layer "F.SilkS")
		)
		(fp_rect
			(start -0.508 0.9398)
			(end 0.508 -0.9398)
			(stroke
				(width 0)
				(type default)
			)
			(fill no)
			(layer "F.CrtYd")
		)
		(fp_rect
			(start -0.508 0.9398)
			(end 0.508 -0.9398)
			(stroke
				(width 0)
				(type default)
			)
			(fill no)
			(layer "F.Fab")
		)
		(pad "1" smd custom
			(at 0 -0.4445 180)
			(size 0.1397 0.1397)
			(layers "F.Cu" "F.Mask" "F.Paste")
			(net "EXP_XM_ADDR_25")
			(options
				(clearance outline)
				(anchor circle)
			)
			(primitives
				(gr_poly
					(pts
						(arc
							(start -0.1778 -0.2794)
							(mid -0.249642 -0.249642)
							(end -0.2794 -0.1778)
						)
						(arc
							(start -0.2794 0.1778)
							(mid -0.249642 0.249642)
							(end -0.1778 0.2794)
						)
						(arc
							(start 0.1778 0.2794)
							(mid 0.249642 0.249642)
							(end 0.2794 0.1778)
						)
						(arc
							(start 0.2794 -0.1778)
							(mid 0.249642 -0.249642)
							(end 0.1778 -0.2794)
						)
					)
					(width 0)
					(fill yes)
				)
			)
		)
		(pad "2" smd custom
			(at 0 0.4445 180)
			(size 0.1397 0.1397)
			(layers "F.Cu" "F.Mask" "F.Paste")
			(net "GND")
			(options
				(clearance outline)
				(anchor circle)
			)
			(primitives
				(gr_poly
					(pts
						(arc
							(start -0.1778 -0.2794)
							(mid -0.249642 -0.249642)
							(end -0.2794 -0.1778)
						)
						(arc
							(start -0.2794 0.1778)
							(mid -0.249642 0.249642)
							(end -0.1778 0.2794)
						)
						(arc
							(start 0.1778 0.2794)
							(mid 0.249642 0.249642)
							(end 0.2794 0.1778)
						)
						(arc
							(start 0.2794 -0.1778)
							(mid 0.249642 -0.249642)
							(end 0.1778 -0.2794)
						)
					)
					(width 0)
					(fill yes)
				)
			)
		)
	)
	(footprint ""
		(layer "F.Cu")
		(at 7.4422 -42.037 90)
		(property "Reference" "R525"
			(at 0 0 90)
			(layer "F.SilkS")
			(hide yes)
			(effects
				(font
					(size 1.27 1.27)
				)
			)
		)
		(property "Value" "0R2J-2-GP"
			(at 0.064008 -3.993896 90)
			(unlocked yes)
			(layer "F.Fab")
			(hide yes)
			(effects
				(font
					(size 1.016 1.016)
					(thickness 0.1524)
				)
			)
		)
		(property "Device Type" "R402H16"
			(at 0.064008 -5.517896 90)
			(unlocked yes)
			(layer "F.Fab")
			(hide yes)
			(effects
				(font
					(size 1.016 1.016)
					(thickness 0.1524)
				)
			)
		)
		(duplicate_pad_numbers_are_jumpers no)
		(fp_line
			(start 0.508 -0.9398)
			(end -0.508 -0.9398)
			(stroke
				(width 0.1524)
				(type default)
			)
			(layer "F.SilkS")
		)
		(fp_line
			(start -0.508 -0.9398)
			(end -0.508 0.9398)
			(stroke
				(width 0.1524)
				(type default)
			)
			(layer "F.SilkS")
		)
		(fp_rect
			(start -0.508 0.9398)
			(end 0.508 -0.9398)
			(stroke
				(width 0)
				(type default)
			)
			(fill no)
			(layer "F.CrtYd")
		)
		(fp_rect
			(start -0.508 0.9398)
			(end 0.508 -0.9398)
			(stroke
				(width 0)
				(type default)
			)
			(fill no)
			(layer "F.Fab")
		)
		(pad "1" smd custom
			(at 0 -0.4445 90)
			(size 0.1397 0.1397)
			(layers "F.Cu" "F.Mask" "F.Paste")
			(net "MB0_12V_CTRL_GATE1_R")
			(options
				(clearance outline)
				(anchor circle)
			)
			(primitives
				(gr_poly
					(pts
						(arc
							(start -0.1778 -0.2794)
							(mid -0.249642 -0.249642)
							(end -0.2794 -0.1778)
						)
						(arc
							(start -0.2794 0.1778)
							(mid -0.249642 0.249642)
							(end -0.1778 0.2794)
						)
						(arc
							(start 0.1778 0.2794)
							(mid 0.249642 0.249642)
							(end 0.2794 0.1778)
						)
						(arc
							(start 0.2794 -0.1778)
							(mid 0.249642 -0.249642)
							(end 0.1778 -0.2794)
						)
					)
					(width 0)
					(fill yes)
				)
			)
		)
		(pad "2" smd custom
			(at 0 0.4445 90)
			(size 0.1397 0.1397)
			(layers "F.Cu" "F.Mask" "F.Paste")
			(net "MB0_CM_GATE_R")
			(options
				(clearance outline)
				(anchor circle)
			)
			(primitives
				(gr_poly
					(pts
						(arc
							(start -0.1778 -0.2794)
							(mid -0.249642 -0.249642)
							(end -0.2794 -0.1778)
						)
						(arc
							(start -0.2794 0.1778)
							(mid -0.249642 0.249642)
							(end -0.1778 0.2794)
						)
						(arc
							(start 0.1778 0.2794)
							(mid 0.249642 0.249642)
							(end 0.2794 0.1778)
						)
						(arc
							(start 0.2794 -0.1778)
							(mid 0.249642 -0.249642)
							(end 0.1778 -0.2794)
						)
					)
					(width 0)
					(fill yes)
				)
			)
		)
	)
	(footprint ""
		(layer "F.Cu")
		(at 187.833 -56.5658 180)
		(property "Reference" "R224"
			(at 0 0 180)
			(layer "F.SilkS")
			(hide yes)
			(effects
				(font
					(size 1.27 1.27)
				)
			)
		)
		(property "Value" "10KR2F-2-GP"
			(at 0.064008 -3.993896 180)
			(unlocked yes)
			(layer "F.Fab")
			(hide yes)
			(effects
				(font
					(size 1.016 1.016)
					(thickness 0.1524)
				)
			)
		)
		(property "Device Type" "R402H16"
			(at 0.064008 -5.517896 180)
			(unlocked yes)
			(layer "F.Fab")
			(hide yes)
			(effects
				(font
					(size 1.016 1.016)
					(thickness 0.1524)
				)
			)
		)
		(duplicate_pad_numbers_are_jumpers no)
		(fp_line
			(start 0.508 -0.9398)
			(end -0.508 -0.9398)
			(stroke
				(width 0.1524)
				(type default)
			)
			(layer "F.SilkS")
		)
		(fp_line
			(start -0.508 -0.9398)
			(end -0.508 0.9398)
			(stroke
				(width 0.1524)
				(type default)
			)
			(layer "F.SilkS")
		)
		(fp_rect
			(start -0.508 0.9398)
			(end 0.508 -0.9398)
			(stroke
				(width 0)
				(type default)
			)
			(fill no)
			(layer "F.CrtYd")
		)
		(fp_rect
			(start -0.508 0.9398)
			(end 0.508 -0.9398)
			(stroke
				(width 0)
				(type default)
			)
			(fill no)
			(layer "F.Fab")
		)
		(pad "1" smd custom
			(at 0 -0.4445 180)
			(size 0.1397 0.1397)
			(layers "F.Cu" "F.Mask" "F.Paste")
			(net "XM_ADDR_4")
			(options
				(clearance outline)
				(anchor circle)
			)
			(primitives
				(gr_poly
					(pts
						(arc
							(start -0.1778 -0.2794)
							(mid -0.249642 -0.249642)
							(end -0.2794 -0.1778)
						)
						(arc
							(start -0.2794 0.1778)
							(mid -0.249642 0.249642)
							(end -0.1778 0.2794)
						)
						(arc
							(start 0.1778 0.2794)
							(mid 0.249642 0.249642)
							(end 0.2794 0.1778)
						)
						(arc
							(start 0.2794 -0.1778)
							(mid 0.249642 -0.249642)
							(end 0.1778 -0.2794)
						)
					)
					(width 0)
					(fill yes)
				)
			)
		)
		(pad "2" smd custom
			(at 0 0.4445 180)
			(size 0.1397 0.1397)
			(layers "F.Cu" "F.Mask" "F.Paste")
			(net "GND")
			(options
				(clearance outline)
				(anchor circle)
			)
			(primitives
				(gr_poly
					(pts
						(arc
							(start -0.1778 -0.2794)
							(mid -0.249642 -0.249642)
							(end -0.2794 -0.1778)
						)
						(arc
							(start -0.2794 0.1778)
							(mid -0.249642 0.249642)
							(end -0.1778 0.2794)
						)
						(arc
							(start 0.1778 0.2794)
							(mid 0.249642 0.249642)
							(end 0.2794 0.1778)
						)
						(arc
							(start 0.2794 -0.1778)
							(mid 0.249642 -0.249642)
							(end 0.1778 -0.2794)
						)
					)
					(width 0)
					(fill yes)
				)
			)
		)
	)
	(footprint ""
		(layer "F.Cu")
		(at 122.536458 -90.595196 180)
		(property "Reference" "R128"
			(at 0 0 180)
			(layer "F.SilkS")
			(hide yes)
			(effects
				(font
					(size 1.27 1.27)
				)
			)
		)
		(property "Value" "4K7R2F-GP"
			(at 0.064008 -3.993896 180)
			(unlocked yes)
			(layer "F.Fab")
			(hide yes)
			(effects
				(font
					(size 1.016 1.016)
					(thickness 0.1524)
				)
			)
		)
		(property "Device Type" "R402H16"
			(at 0.064008 -5.517896 180)
			(unlocked yes)
			(layer "F.Fab")
			(hide yes)
			(effects
				(font
					(size 1.016 1.016)
					(thickness 0.1524)
				)
			)
		)
		(duplicate_pad_numbers_are_jumpers no)
		(fp_line
			(start 0.508 -0.9398)
			(end -0.508 -0.9398)
			(stroke
				(width 0.1524)
				(type default)
			)
			(layer "F.SilkS")
		)
		(fp_line
			(start -0.508 -0.9398)
			(end -0.508 0.9398)
			(stroke
				(width 0.1524)
				(type default)
			)
			(layer "F.SilkS")
		)
		(fp_rect
			(start -0.508 0.9398)
			(end 0.508 -0.9398)
			(stroke
				(width 0)
				(type default)
			)
			(fill no)
			(layer "F.CrtYd")
		)
		(fp_rect
			(start -0.508 0.9398)
			(end 0.508 -0.9398)
			(stroke
				(width 0)
				(type default)
			)
			(fill no)
			(layer "F.Fab")
		)
		(pad "1" smd custom
			(at 0 -0.4445 180)
			(size 0.1397 0.1397)
			(layers "F.Cu" "F.Mask" "F.Paste")
			(net "USB_NXT")
			(options
				(clearance outline)
				(anchor circle)
			)
			(primitives
				(gr_poly
					(pts
						(arc
							(start -0.1778 -0.2794)
							(mid -0.249642 -0.249642)
							(end -0.2794 -0.1778)
						)
						(arc
							(start -0.2794 0.1778)
							(mid -0.249642 0.249642)
							(end -0.1778 0.2794)
						)
						(arc
							(start 0.1778 0.2794)
							(mid 0.249642 0.249642)
							(end 0.2794 0.1778)
						)
						(arc
							(start 0.2794 -0.1778)
							(mid 0.249642 -0.249642)
							(end 0.1778 -0.2794)
						)
					)
					(width 0)
					(fill yes)
				)
			)
		)
		(pad "2" smd custom
			(at 0 0.4445 180)
			(size 0.1397 0.1397)
			(layers "F.Cu" "F.Mask" "F.Paste")
			(net "GND")
			(options
				(clearance outline)
				(anchor circle)
			)
			(primitives
				(gr_poly
					(pts
						(arc
							(start -0.1778 -0.2794)
							(mid -0.249642 -0.249642)
							(end -0.2794 -0.1778)
						)
						(arc
							(start -0.2794 0.1778)
							(mid -0.249642 0.249642)
							(end -0.1778 0.2794)
						)
						(arc
							(start 0.1778 0.2794)
							(mid 0.249642 0.249642)
							(end 0.2794 0.1778)
						)
						(arc
							(start 0.2794 -0.1778)
							(mid 0.249642 -0.249642)
							(end 0.1778 -0.2794)
						)
					)
					(width 0)
					(fill yes)
				)
			)
		)
	)
	(footprint ""
		(layer "F.Cu")
		(at 70.485 -41.402 90)
		(property "Reference" "R165"
			(at 0 0 90)
			(layer "F.SilkS")
			(hide yes)
			(effects
				(font
					(size 1.27 1.27)
				)
			)
		)
		(property "Value" "D51R3F-2-GP"
			(at -0.0254 -2.5146 90)
			(unlocked yes)
			(layer "F.Fab")
			(hide yes)
			(effects
				(font
					(size 1.016 1.016)
					(thickness 0.1524)
				)
			)
		)
		(property "Device Type" "R603H22"
			(at -0.0254 -4.0386 90)
			(unlocked yes)
			(layer "F.Fab")
			(hide yes)
			(effects
				(font
					(size 1.016 1.016)
					(thickness 0.1524)
				)
			)
		)
		(duplicate_pad_numbers_are_jumpers no)
		(fp_line
			(start 0.2032 0)
			(end 0.4826 0)
			(stroke
				(width 0.2032)
				(type default)
			)
			(layer "F.SilkS")
		)
		(fp_line
			(start -0.4826 0)
			(end -0.2032 0)
			(stroke
				(width 0.2032)
				(type default)
			)
			(layer "F.SilkS")
		)
		(fp_rect
			(start -0.5842 1.3335)
			(end 0.5842 -1.3335)
			(stroke
				(width 0)
				(type default)
			)
			(fill no)
			(layer "F.CrtYd")
		)
		(fp_rect
			(start -0.5842 1.3335)
			(end 0.5842 -1.3335)
			(stroke
				(width 0)
				(type default)
			)
			(fill no)
			(layer "F.Fab")
		)
		(pad "1" smd custom
			(at 0 -0.762 90)
			(size 0.2159 0.2159)
			(layers "F.Cu" "F.Mask" "F.Paste")
			(net "P0V9")
			(options
				(clearance outline)
				(anchor circle)
			)
			(primitives
				(gr_poly
					(pts
						(arc
							(start -0.3302 -0.4318)
							(mid -0.402042 -0.402042)
							(end -0.4318 -0.3302)
						)
						(arc
							(start -0.4318 0.3302)
							(mid -0.402042 0.402042)
							(end -0.3302 0.4318)
						)
						(arc
							(start 0.3302 0.4318)
							(mid 0.402042 0.402042)
							(end 0.4318 0.3302)
						)
						(arc
							(start 0.4318 -0.3302)
							(mid 0.402042 -0.402042)
							(end 0.3302 -0.4318)
						)
					)
					(width 0)
					(fill yes)
				)
			)
		)
		(pad "2" smd custom
			(at 0 0.762 90)
			(size 0.2159 0.2159)
			(layers "F.Cu" "F.Mask" "F.Paste")
			(net "GB_VDDA")
			(options
				(clearance outline)
				(anchor circle)
			)
			(primitives
				(gr_poly
					(pts
						(arc
							(start -0.3302 -0.4318)
							(mid -0.402042 -0.402042)
							(end -0.4318 -0.3302)
						)
						(arc
							(start -0.4318 0.3302)
							(mid -0.402042 0.402042)
							(end -0.3302 0.4318)
						)
						(arc
							(start 0.3302 0.4318)
							(mid 0.402042 0.402042)
							(end 0.4318 0.3302)
						)
						(arc
							(start 0.4318 -0.3302)
							(mid 0.402042 -0.402042)
							(end 0.3302 -0.4318)
						)
					)
					(width 0)
					(fill yes)
				)
			)
		)
	)
	(footprint ""
		(layer "F.Cu")
		(at 56.896 -24.13 90)
		(property "Reference" "C730"
			(at 0 0 90)
			(layer "F.SilkS")
			(hide yes)
			(effects
				(font
					(size 1.27 1.27)
				)
			)
		)
		(property "Value" "SCD1U16V2KX-3GP"
			(at 1.1811 -2.7051 90)
			(unlocked yes)
			(layer "F.Fab")
			(hide yes)
			(effects
				(font
					(size 1.016 1.016)
					(thickness 0.1524)
				)
			)
		)
		(property "Device Type" "C402H22"
			(at 1.1811 -4.2291 90)
			(unlocked yes)
			(layer "F.Fab")
			(hide yes)
			(effects
				(font
					(size 1.016 1.016)
					(thickness 0.1524)
				)
			)
		)
		(duplicate_pad_numbers_are_jumpers no)
		(fp_rect
			(start -0.4318 0.9525)
			(end 0.4318 -0.9525)
			(stroke
				(width 0)
				(type default)
			)
			(fill no)
			(layer "F.CrtYd")
		)
		(fp_rect
			(start -0.4318 0.9525)
			(end 0.4318 -0.9525)
			(stroke
				(width 0)
				(type default)
			)
			(fill no)
			(layer "F.Fab")
		)
		(pad "1" smd custom
			(at 0 -0.4445 90)
			(size 0.1524 0.1524)
			(layers "F.Cu" "F.Mask" "F.Paste")
			(net "P3V3_DPB")
			(options
				(clearance outline)
				(anchor circle)
			)
			(primitives
				(gr_poly
					(pts
						(arc
							(start 0.3048 -0.2032)
							(mid 0.275042 -0.275042)
							(end 0.2032 -0.3048)
						)
						(arc
							(start -0.2032 -0.3048)
							(mid -0.275042 -0.275042)
							(end -0.3048 -0.2032)
						)
						(arc
							(start -0.3048 0.2032)
							(mid -0.275042 0.275042)
							(end -0.2032 0.3048)
						)
						(arc
							(start 0.2032 0.3048)
							(mid 0.275042 0.275042)
							(end 0.3048 0.2032)
						)
					)
					(width 0)
					(fill yes)
				)
			)
		)
		(pad "2" smd custom
			(at 0 0.4445 90)
			(size 0.1524 0.1524)
			(layers "F.Cu" "F.Mask" "F.Paste")
			(net "GND")
			(options
				(clearance outline)
				(anchor circle)
			)
			(primitives
				(gr_poly
					(pts
						(arc
							(start 0.3048 -0.2032)
							(mid 0.275042 -0.275042)
							(end 0.2032 -0.3048)
						)
						(arc
							(start -0.2032 -0.3048)
							(mid -0.275042 -0.275042)
							(end -0.3048 -0.2032)
						)
						(arc
							(start -0.3048 0.2032)
							(mid -0.275042 0.275042)
							(end -0.2032 0.3048)
						)
						(arc
							(start 0.2032 0.3048)
							(mid 0.275042 0.275042)
							(end 0.3048 0.2032)
						)
					)
					(width 0)
					(fill yes)
				)
			)
		)
	)
	(footprint ""
		(layer "F.Cu")
		(at 65.46088 -95.57258 -90)
		(property "Reference" "C638"
			(at 0 0 270)
			(layer "F.SilkS")
			(hide yes)
			(effects
				(font
					(size 1.27 1.27)
				)
			)
		)
		(property "Value" "SC1U16V3KX-5GP"
			(at 0 -2.8194 270)
			(unlocked yes)
			(layer "F.Fab")
			(hide yes)
			(effects
				(font
					(size 1.016 1.016)
					(thickness 0.1524)
				)
			)
		)
		(property "Device Type" "C603H36"
			(at 0 -4.3434 270)
			(unlocked yes)
			(layer "F.Fab")
			(hide yes)
			(effects
				(font
					(size 1.016 1.016)
					(thickness 0.1524)
				)
			)
		)
		(duplicate_pad_numbers_are_jumpers no)
		(fp_line
			(start 0.508 0)
			(end -0.508 0)
			(stroke
				(width 0.2032)
				(type default)
			)
			(layer "F.SilkS")
		)
		(fp_rect
			(start -0.5842 1.3335)
			(end 0.5842 -1.3335)
			(stroke
				(width 0)
				(type default)
			)
			(fill no)
			(layer "F.CrtYd")
		)
		(fp_rect
			(start -0.5842 1.3335)
			(end 0.5842 -1.3335)
			(stroke
				(width 0)
				(type default)
			)
			(fill no)
			(layer "F.Fab")
		)
		(pad "1" smd custom
			(at 0 -0.762 270)
			(size 0.2159 0.2159)
			(layers "F.Cu" "F.Mask" "F.Paste")
			(net "GND")
			(options
				(clearance outline)
				(anchor circle)
			)
			(primitives
				(gr_poly
					(pts
						(arc
							(start -0.3302 -0.4318)
							(mid -0.402042 -0.402042)
							(end -0.4318 -0.3302)
						)
						(arc
							(start -0.4318 0.3302)
							(mid -0.402042 0.402042)
							(end -0.3302 0.4318)
						)
						(arc
							(start 0.3302 0.4318)
							(mid 0.402042 0.402042)
							(end 0.4318 0.3302)
						)
						(arc
							(start 0.4318 -0.3302)
							(mid 0.402042 -0.402042)
							(end 0.3302 -0.4318)
						)
					)
					(width 0)
					(fill yes)
				)
			)
		)
		(pad "2" smd custom
			(at 0 0.762 270)
			(size 0.2159 0.2159)
			(layers "F.Cu" "F.Mask" "F.Paste")
			(net "P3V3_VREG")
			(options
				(clearance outline)
				(anchor circle)
			)
			(primitives
				(gr_poly
					(pts
						(arc
							(start -0.3302 -0.4318)
							(mid -0.402042 -0.402042)
							(end -0.4318 -0.3302)
						)
						(arc
							(start -0.4318 0.3302)
							(mid -0.402042 0.402042)
							(end -0.3302 0.4318)
						)
						(arc
							(start 0.3302 0.4318)
							(mid 0.402042 0.402042)
							(end 0.4318 0.3302)
						)
						(arc
							(start 0.4318 -0.3302)
							(mid 0.402042 -0.402042)
							(end 0.3302 -0.4318)
						)
					)
					(width 0)
					(fill yes)
				)
			)
		)
	)
	(footprint ""
		(layer "F.Cu")
		(at 181.8386 -124.3076 90)
		(property "Reference" "C596"
			(at 0 0 90)
			(layer "F.SilkS")
			(hide yes)
			(effects
				(font
					(size 1.27 1.27)
				)
			)
		)
		(property "Value" "SCD1U16V2KX-3GP"
			(at 1.1811 -2.7051 90)
			(unlocked yes)
			(layer "F.Fab")
			(hide yes)
			(effects
				(font
					(size 1.016 1.016)
					(thickness 0.1524)
				)
			)
		)
		(property "Device Type" "C402H22"
			(at 1.1811 -4.2291 90)
			(unlocked yes)
			(layer "F.Fab")
			(hide yes)
			(effects
				(font
					(size 1.016 1.016)
					(thickness 0.1524)
				)
			)
		)
		(duplicate_pad_numbers_are_jumpers no)
		(fp_rect
			(start -0.4318 0.9525)
			(end 0.4318 -0.9525)
			(stroke
				(width 0)
				(type default)
			)
			(fill no)
			(layer "F.CrtYd")
		)
		(fp_rect
			(start -0.4318 0.9525)
			(end 0.4318 -0.9525)
			(stroke
				(width 0)
				(type default)
			)
			(fill no)
			(layer "F.Fab")
		)
		(pad "1" smd custom
			(at 0 -0.4445 90)
			(size 0.1524 0.1524)
			(layers "F.Cu" "F.Mask" "F.Paste")
			(net "P1V8_E_OUT")
			(options
				(clearance outline)
				(anchor circle)
			)
			(primitives
				(gr_poly
					(pts
						(arc
							(start 0.3048 -0.2032)
							(mid 0.275042 -0.275042)
							(end 0.2032 -0.3048)
						)
						(arc
							(start -0.2032 -0.3048)
							(mid -0.275042 -0.275042)
							(end -0.3048 -0.2032)
						)
						(arc
							(start -0.3048 0.2032)
							(mid -0.275042 0.275042)
							(end -0.2032 0.3048)
						)
						(arc
							(start 0.2032 0.3048)
							(mid 0.275042 0.275042)
							(end 0.3048 0.2032)
						)
					)
					(width 0)
					(fill yes)
				)
			)
		)
		(pad "2" smd custom
			(at 0 0.4445 90)
			(size 0.1524 0.1524)
			(layers "F.Cu" "F.Mask" "F.Paste")
			(net "GND")
			(options
				(clearance outline)
				(anchor circle)
			)
			(primitives
				(gr_poly
					(pts
						(arc
							(start 0.3048 -0.2032)
							(mid 0.275042 -0.275042)
							(end 0.2032 -0.3048)
						)
						(arc
							(start -0.2032 -0.3048)
							(mid -0.275042 -0.275042)
							(end -0.3048 -0.2032)
						)
						(arc
							(start -0.3048 0.2032)
							(mid -0.275042 0.275042)
							(end -0.2032 0.3048)
						)
						(arc
							(start 0.2032 0.3048)
							(mid 0.275042 0.275042)
							(end 0.3048 0.2032)
						)
					)
					(width 0)
					(fill yes)
				)
			)
		)
	)
	(footprint ""
		(layer "F.Cu")
		(at 139.057634 -78.427834 180)
		(property "Reference" "VIA26"
			(at 0 0 180)
			(layer "F.SilkS")
			(hide yes)
			(effects
				(font
					(size 1.27 1.27)
				)
			)
		)
		(property "Value" "100OHM-8L-1D6MM-L18L16-GP"
			(at -3.7211 -4.5085 180)
			(unlocked yes)
			(layer "F.Fab")
			(hide yes)
			(effects
				(font
					(size 1.016 1.016)
					(thickness 0.1524)
				)
			)
		)
		(property "Device Type" "VIA-PCIE-4P-394076"
			(at -3.7211 -6.0325 180)
			(unlocked yes)
			(layer "F.Fab")
			(hide yes)
			(effects
				(font
					(size 1.016 1.016)
					(thickness 0.1524)
				)
			)
		)
		(duplicate_pad_numbers_are_jumpers no)
		(fp_rect
			(start -1.9685 0.381)
			(end 1.9685 -0.381)
			(stroke
				(width 0)
				(type default)
			)
			(fill no)
			(layer "F.CrtYd")
		)
		(fp_rect
			(start -1.9685 0.381)
			(end 1.9685 -0.381)
			(stroke
				(width 0)
				(type default)
			)
			(fill no)
			(layer "F.Fab")
		)
		(pad "1" thru_hole circle
			(at -1.5875 0 180)
			(size 0.508 0.508)
			(drill 0.254)
			(layers "*.Cu" "*.Mask")
			(remove_unused_layers no)
			(net "GND")
			(clearance 0.127)
			(thermal_gap 0.127)
		)
		(pad "2" thru_hole circle
			(at -0.5715 0 180)
			(size 0.508 0.508)
			(drill 0.254)
			(layers "*.Cu" "*.Mask")
			(remove_unused_layers no)
			(net "PHY_EXP_TO_CONN_9_DP")
			(clearance 0.127)
			(thermal_gap 0.127)
		)
		(pad "3" thru_hole circle
			(at 0.5715 0 180)
			(size 0.508 0.508)
			(drill 0.254)
			(layers "*.Cu" "*.Mask")
			(remove_unused_layers no)
			(net "PHY_EXP_TO_CONN_9_DN")
			(clearance 0.127)
			(thermal_gap 0.127)
		)
		(pad "4" thru_hole circle
			(at 1.5875 0 180)
			(size 0.508 0.508)
			(drill 0.254)
			(layers "*.Cu" "*.Mask")
			(remove_unused_layers no)
			(net "GND")
			(clearance 0.127)
			(thermal_gap 0.127)
		)
	)
	(footprint ""
		(layer "F.Cu")
		(at 180.3908 -110.80242)
		(property "Reference" "R604"
			(at 0 0 0)
			(layer "F.SilkS")
			(hide yes)
			(effects
				(font
					(size 1.27 1.27)
				)
			)
		)
		(property "Value" "4K7R2F-GP"
			(at 0.064008 -3.993896 0)
			(unlocked yes)
			(layer "F.Fab")
			(hide yes)
			(effects
				(font
					(size 1.016 1.016)
					(thickness 0.1524)
				)
			)
		)
		(property "Device Type" "R402H16"
			(at 0.064008 -5.517896 0)
			(unlocked yes)
			(layer "F.Fab")
			(hide yes)
			(effects
				(font
					(size 1.016 1.016)
					(thickness 0.1524)
				)
			)
		)
		(duplicate_pad_numbers_are_jumpers no)
		(fp_line
			(start -0.508 -0.9398)
			(end -0.508 0.9398)
			(stroke
				(width 0.1524)
				(type default)
			)
			(layer "F.SilkS")
		)
		(fp_line
			(start 0.508 -0.9398)
			(end -0.508 -0.9398)
			(stroke
				(width 0.1524)
				(type default)
			)
			(layer "F.SilkS")
		)
		(fp_rect
			(start -0.508 0.9398)
			(end 0.508 -0.9398)
			(stroke
				(width 0)
				(type default)
			)
			(fill no)
			(layer "F.CrtYd")
		)
		(fp_rect
			(start -0.508 0.9398)
			(end 0.508 -0.9398)
			(stroke
				(width 0)
				(type default)
			)
			(fill no)
			(layer "F.Fab")
		)
		(pad "1" smd custom
			(at 0 -0.4445)
			(size 0.1397 0.1397)
			(layers "F.Cu" "F.Mask" "F.Paste")
			(net "P3V3")
			(options
				(clearance outline)
				(anchor circle)
			)
			(primitives
				(gr_poly
					(pts
						(arc
							(start -0.1778 -0.2794)
							(mid -0.249642 -0.249642)
							(end -0.2794 -0.1778)
						)
						(arc
							(start -0.2794 0.1778)
							(mid -0.249642 0.249642)
							(end -0.1778 0.2794)
						)
						(arc
							(start 0.1778 0.2794)
							(mid 0.249642 0.249642)
							(end 0.2794 0.1778)
						)
						(arc
							(start 0.2794 -0.1778)
							(mid 0.249642 -0.249642)
							(end 0.1778 -0.2794)
						)
					)
					(width 0)
					(fill yes)
				)
			)
		)
		(pad "2" smd custom
			(at 0 0.4445)
			(size 0.1397 0.1397)
			(layers "F.Cu" "F.Mask" "F.Paste")
			(net "P1V8_C_PG_R_1")
			(options
				(clearance outline)
				(anchor circle)
			)
			(primitives
				(gr_poly
					(pts
						(arc
							(start -0.1778 -0.2794)
							(mid -0.249642 -0.249642)
							(end -0.2794 -0.1778)
						)
						(arc
							(start -0.2794 0.1778)
							(mid -0.249642 0.249642)
							(end -0.1778 0.2794)
						)
						(arc
							(start 0.1778 0.2794)
							(mid 0.249642 0.249642)
							(end 0.2794 0.1778)
						)
						(arc
							(start 0.2794 -0.1778)
							(mid 0.249642 -0.249642)
							(end 0.1778 -0.2794)
						)
					)
					(width 0)
					(fill yes)
				)
			)
		)
	)
	(footprint ""
		(layer "F.Cu")
		(at 139.072112 -80.197452 180)
		(property "Reference" "VIA27"
			(at 0 0 180)
			(layer "F.SilkS")
			(hide yes)
			(effects
				(font
					(size 1.27 1.27)
				)
			)
		)
		(property "Value" "100OHM-8L-1D6MM-L18L16-GP"
			(at -3.7211 -4.5085 180)
			(unlocked yes)
			(layer "F.Fab")
			(hide yes)
			(effects
				(font
					(size 1.016 1.016)
					(thickness 0.1524)
				)
			)
		)
		(property "Device Type" "VIA-PCIE-4P-394076"
			(at -3.7211 -6.0325 180)
			(unlocked yes)
			(layer "F.Fab")
			(hide yes)
			(effects
				(font
					(size 1.016 1.016)
					(thickness 0.1524)
				)
			)
		)
		(duplicate_pad_numbers_are_jumpers no)
		(fp_rect
			(start -1.9685 0.381)
			(end 1.9685 -0.381)
			(stroke
				(width 0)
				(type default)
			)
			(fill no)
			(layer "F.CrtYd")
		)
		(fp_rect
			(start -1.9685 0.381)
			(end 1.9685 -0.381)
			(stroke
				(width 0)
				(type default)
			)
			(fill no)
			(layer "F.Fab")
		)
		(pad "1" thru_hole circle
			(at -1.5875 0 180)
			(size 0.508 0.508)
			(drill 0.254)
			(layers "*.Cu" "*.Mask")
			(remove_unused_layers no)
			(net "GND")
			(clearance 0.127)
			(thermal_gap 0.127)
		)
		(pad "2" thru_hole circle
			(at -0.5715 0 180)
			(size 0.508 0.508)
			(drill 0.254)
			(layers "*.Cu" "*.Mask")
			(remove_unused_layers no)
			(net "PHY_EXP_TO_CONN_10_DP")
			(clearance 0.127)
			(thermal_gap 0.127)
		)
		(pad "3" thru_hole circle
			(at 0.5715 0 180)
			(size 0.508 0.508)
			(drill 0.254)
			(layers "*.Cu" "*.Mask")
			(remove_unused_layers no)
			(net "PHY_EXP_TO_CONN_10_DN")
			(clearance 0.127)
			(thermal_gap 0.127)
		)
		(pad "4" thru_hole circle
			(at 1.5875 0 180)
			(size 0.508 0.508)
			(drill 0.254)
			(layers "*.Cu" "*.Mask")
			(remove_unused_layers no)
			(net "GND")
			(clearance 0.127)
			(thermal_gap 0.127)
		)
	)
	(footprint ""
		(layer "F.Cu")
		(at 198.8312 -82.92338 180)
		(property "Reference" "R442"
			(at 0 0 180)
			(layer "F.SilkS")
			(hide yes)
			(effects
				(font
					(size 1.27 1.27)
				)
			)
		)
		(property "Value" "0R2J-2-GP"
			(at 0.064008 -3.993896 180)
			(unlocked yes)
			(layer "F.Fab")
			(hide yes)
			(effects
				(font
					(size 1.016 1.016)
					(thickness 0.1524)
				)
			)
		)
		(property "Device Type" "R402H16"
			(at 0.064008 -5.517896 180)
			(unlocked yes)
			(layer "F.Fab")
			(hide yes)
			(effects
				(font
					(size 1.016 1.016)
					(thickness 0.1524)
				)
			)
		)
		(duplicate_pad_numbers_are_jumpers no)
		(fp_line
			(start 0.508 -0.9398)
			(end -0.508 -0.9398)
			(stroke
				(width 0.1524)
				(type default)
			)
			(layer "F.SilkS")
		)
		(fp_line
			(start -0.508 -0.9398)
			(end -0.508 0.9398)
			(stroke
				(width 0.1524)
				(type default)
			)
			(layer "F.SilkS")
		)
		(fp_rect
			(start -0.508 0.9398)
			(end 0.508 -0.9398)
			(stroke
				(width 0)
				(type default)
			)
			(fill no)
			(layer "F.CrtYd")
		)
		(fp_rect
			(start -0.508 0.9398)
			(end 0.508 -0.9398)
			(stroke
				(width 0)
				(type default)
			)
			(fill no)
			(layer "F.Fab")
		)
		(pad "1" smd custom
			(at 0 -0.4445 180)
			(size 0.1397 0.1397)
			(layers "F.Cu" "F.Mask" "F.Paste")
			(net "P5V")
			(options
				(clearance outline)
				(anchor circle)
			)
			(primitives
				(gr_poly
					(pts
						(arc
							(start -0.1778 -0.2794)
							(mid -0.249642 -0.249642)
							(end -0.2794 -0.1778)
						)
						(arc
							(start -0.2794 0.1778)
							(mid -0.249642 0.249642)
							(end -0.1778 0.2794)
						)
						(arc
							(start 0.1778 0.2794)
							(mid 0.249642 0.249642)
							(end 0.2794 0.1778)
						)
						(arc
							(start 0.2794 -0.1778)
							(mid 0.249642 -0.249642)
							(end 0.1778 -0.2794)
						)
					)
					(width 0)
					(fill yes)
				)
			)
		)
		(pad "2" smd custom
			(at 0 0.4445 180)
			(size 0.1397 0.1397)
			(layers "F.Cu" "F.Mask" "F.Paste")
			(net "SDB_CONN_PWR_3")
			(options
				(clearance outline)
				(anchor circle)
			)
			(primitives
				(gr_poly
					(pts
						(arc
							(start -0.1778 -0.2794)
							(mid -0.249642 -0.249642)
							(end -0.2794 -0.1778)
						)
						(arc
							(start -0.2794 0.1778)
							(mid -0.249642 0.249642)
							(end -0.1778 0.2794)
						)
						(arc
							(start 0.1778 0.2794)
							(mid 0.249642 0.249642)
							(end 0.2794 0.1778)
						)
						(arc
							(start 0.2794 -0.1778)
							(mid 0.249642 -0.249642)
							(end 0.1778 -0.2794)
						)
					)
					(width 0)
					(fill yes)
				)
			)
		)
	)
	(footprint ""
		(layer "F.Cu")
		(at 162.405568 -22.462744 180)
		(property "Reference" "R169"
			(at 0 0 180)
			(layer "F.SilkS")
			(hide yes)
			(effects
				(font
					(size 1.27 1.27)
				)
			)
		)
		(property "Value" "0R2J-2-GP"
			(at 0.064008 -3.993896 180)
			(unlocked yes)
			(layer "F.Fab")
			(hide yes)
			(effects
				(font
					(size 1.016 1.016)
					(thickness 0.1524)
				)
			)
		)
		(property "Device Type" "R402H16"
			(at 0.064008 -5.517896 180)
			(unlocked yes)
			(layer "F.Fab")
			(hide yes)
			(effects
				(font
					(size 1.016 1.016)
					(thickness 0.1524)
				)
			)
		)
		(duplicate_pad_numbers_are_jumpers no)
		(fp_line
			(start 0.508 -0.9398)
			(end -0.508 -0.9398)
			(stroke
				(width 0.1524)
				(type default)
			)
			(layer "F.SilkS")
		)
		(fp_line
			(start -0.508 -0.9398)
			(end -0.508 0.9398)
			(stroke
				(width 0.1524)
				(type default)
			)
			(layer "F.SilkS")
		)
		(fp_rect
			(start -0.508 0.9398)
			(end 0.508 -0.9398)
			(stroke
				(width 0)
				(type default)
			)
			(fill no)
			(layer "F.CrtYd")
		)
		(fp_rect
			(start -0.508 0.9398)
			(end 0.508 -0.9398)
			(stroke
				(width 0)
				(type default)
			)
			(fill no)
			(layer "F.Fab")
		)
		(pad "1" smd custom
			(at 0 -0.4445 180)
			(size 0.1397 0.1397)
			(layers "F.Cu" "F.Mask" "F.Paste")
			(net "PCIE_COMP_TO_SCC_CLK_0_DP")
			(options
				(clearance outline)
				(anchor circle)
			)
			(primitives
				(gr_poly
					(pts
						(arc
							(start -0.1778 -0.2794)
							(mid -0.249642 -0.249642)
							(end -0.2794 -0.1778)
						)
						(arc
							(start -0.2794 0.1778)
							(mid -0.249642 0.249642)
							(end -0.1778 0.2794)
						)
						(arc
							(start 0.1778 0.2794)
							(mid 0.249642 0.249642)
							(end 0.2794 0.1778)
						)
						(arc
							(start 0.2794 -0.1778)
							(mid 0.249642 -0.249642)
							(end 0.1778 -0.2794)
						)
					)
					(width 0)
					(fill yes)
				)
			)
		)
		(pad "2" smd custom
			(at 0 0.4445 180)
			(size 0.1397 0.1397)
			(layers "F.Cu" "F.Mask" "F.Paste")
			(net "PCIE_CLK_R_P")
			(options
				(clearance outline)
				(anchor circle)
			)
			(primitives
				(gr_poly
					(pts
						(arc
							(start -0.1778 -0.2794)
							(mid -0.249642 -0.249642)
							(end -0.2794 -0.1778)
						)
						(arc
							(start -0.2794 0.1778)
							(mid -0.249642 0.249642)
							(end -0.1778 0.2794)
						)
						(arc
							(start 0.1778 0.2794)
							(mid 0.249642 0.249642)
							(end 0.2794 0.1778)
						)
						(arc
							(start 0.2794 -0.1778)
							(mid 0.249642 -0.249642)
							(end 0.1778 -0.2794)
						)
					)
					(width 0)
					(fill yes)
				)
			)
		)
	)
	(footprint ""
		(layer "F.Cu")
		(at 7.5438 -85.8012 -90)
		(property "Reference" "C545"
			(at 0 0 270)
			(layer "F.SilkS")
			(hide yes)
			(effects
				(font
					(size 1.27 1.27)
				)
			)
		)
		(property "Value" "SCD1U16V2KX-3GP"
			(at 1.1811 -2.7051 270)
			(unlocked yes)
			(layer "F.Fab")
			(hide yes)
			(effects
				(font
					(size 1.016 1.016)
					(thickness 0.1524)
				)
			)
		)
		(property "Device Type" "C402H22"
			(at 1.1811 -4.2291 270)
			(unlocked yes)
			(layer "F.Fab")
			(hide yes)
			(effects
				(font
					(size 1.016 1.016)
					(thickness 0.1524)
				)
			)
		)
		(duplicate_pad_numbers_are_jumpers no)
		(fp_rect
			(start -0.4318 0.9525)
			(end 0.4318 -0.9525)
			(stroke
				(width 0)
				(type default)
			)
			(fill no)
			(layer "F.CrtYd")
		)
		(fp_rect
			(start -0.4318 0.9525)
			(end 0.4318 -0.9525)
			(stroke
				(width 0)
				(type default)
			)
			(fill no)
			(layer "F.Fab")
		)
		(pad "1" smd custom
			(at 0 -0.4445 270)
			(size 0.1524 0.1524)
			(layers "F.Cu" "F.Mask" "F.Paste")
			(net "P1V8_E")
			(options
				(clearance outline)
				(anchor circle)
			)
			(primitives
				(gr_poly
					(pts
						(arc
							(start 0.3048 -0.2032)
							(mid 0.275042 -0.275042)
							(end 0.2032 -0.3048)
						)
						(arc
							(start -0.2032 -0.3048)
							(mid -0.275042 -0.275042)
							(end -0.3048 -0.2032)
						)
						(arc
							(start -0.3048 0.2032)
							(mid -0.275042 0.275042)
							(end -0.2032 0.3048)
						)
						(arc
							(start 0.2032 0.3048)
							(mid 0.275042 0.275042)
							(end 0.3048 0.2032)
						)
					)
					(width 0)
					(fill yes)
				)
			)
		)
		(pad "2" smd custom
			(at 0 0.4445 270)
			(size 0.1524 0.1524)
			(layers "F.Cu" "F.Mask" "F.Paste")
			(net "GND")
			(options
				(clearance outline)
				(anchor circle)
			)
			(primitives
				(gr_poly
					(pts
						(arc
							(start 0.3048 -0.2032)
							(mid 0.275042 -0.275042)
							(end 0.2032 -0.3048)
						)
						(arc
							(start -0.2032 -0.3048)
							(mid -0.275042 -0.275042)
							(end -0.3048 -0.2032)
						)
						(arc
							(start -0.3048 0.2032)
							(mid -0.275042 0.275042)
							(end -0.2032 0.3048)
						)
						(arc
							(start 0.2032 0.3048)
							(mid 0.275042 0.275042)
							(end 0.3048 0.2032)
						)
					)
					(width 0)
					(fill yes)
				)
			)
		)
	)
	(footprint ""
		(layer "F.Cu")
		(at 186.370468 -113.631218 90)
		(property "Reference" "R3"
			(at 0 0 90)
			(layer "F.SilkS")
			(hide yes)
			(effects
				(font
					(size 1.27 1.27)
				)
			)
		)
		(property "Value" "10KR2F-2-GP"
			(at 0.064008 -3.993896 90)
			(unlocked yes)
			(layer "F.Fab")
			(hide yes)
			(effects
				(font
					(size 1.016 1.016)
					(thickness 0.1524)
				)
			)
		)
		(property "Device Type" "R402H16"
			(at 0.064008 -5.517896 90)
			(unlocked yes)
			(layer "F.Fab")
			(hide yes)
			(effects
				(font
					(size 1.016 1.016)
					(thickness 0.1524)
				)
			)
		)
		(duplicate_pad_numbers_are_jumpers no)
		(fp_line
			(start 0.508 -0.9398)
			(end -0.508 -0.9398)
			(stroke
				(width 0.1524)
				(type default)
			)
			(layer "F.SilkS")
		)
		(fp_line
			(start -0.508 -0.9398)
			(end -0.508 0.9398)
			(stroke
				(width 0.1524)
				(type default)
			)
			(layer "F.SilkS")
		)
		(fp_rect
			(start -0.508 0.9398)
			(end 0.508 -0.9398)
			(stroke
				(width 0)
				(type default)
			)
			(fill no)
			(layer "F.CrtYd")
		)
		(fp_rect
			(start -0.508 0.9398)
			(end 0.508 -0.9398)
			(stroke
				(width 0)
				(type default)
			)
			(fill no)
			(layer "F.Fab")
		)
		(pad "1" smd custom
			(at 0 -0.4445 90)
			(size 0.1397 0.1397)
			(layers "F.Cu" "F.Mask" "F.Paste")
			(net "P12V_STBY_SCC")
			(options
				(clearance outline)
				(anchor circle)
			)
			(primitives
				(gr_poly
					(pts
						(arc
							(start -0.1778 -0.2794)
							(mid -0.249642 -0.249642)
							(end -0.2794 -0.1778)
						)
						(arc
							(start -0.2794 0.1778)
							(mid -0.249642 0.249642)
							(end -0.1778 0.2794)
						)
						(arc
							(start 0.1778 0.2794)
							(mid 0.249642 0.249642)
							(end 0.2794 0.1778)
						)
						(arc
							(start 0.2794 -0.1778)
							(mid 0.249642 -0.249642)
							(end 0.1778 -0.2794)
						)
					)
					(width 0)
					(fill yes)
				)
			)
		)
		(pad "2" smd custom
			(at 0 0.4445 90)
			(size 0.1397 0.1397)
			(layers "F.Cu" "F.Mask" "F.Paste")
			(net "P1V8_C_G_PG")
			(options
				(clearance outline)
				(anchor circle)
			)
			(primitives
				(gr_poly
					(pts
						(arc
							(start -0.1778 -0.2794)
							(mid -0.249642 -0.249642)
							(end -0.2794 -0.1778)
						)
						(arc
							(start -0.2794 0.1778)
							(mid -0.249642 0.249642)
							(end -0.1778 0.2794)
						)
						(arc
							(start 0.1778 0.2794)
							(mid 0.249642 0.249642)
							(end 0.2794 0.1778)
						)
						(arc
							(start 0.2794 -0.1778)
							(mid 0.249642 -0.249642)
							(end 0.1778 -0.2794)
						)
					)
					(width 0)
					(fill yes)
				)
			)
		)
	)
	(footprint ""
		(layer "F.Cu")
		(at 6.7564 -70.4088 180)
		(property "Reference" "R361"
			(at 0 0 180)
			(layer "F.SilkS")
			(hide yes)
			(effects
				(font
					(size 1.27 1.27)
				)
			)
		)
		(property "Value" "4K7R2F-GP"
			(at 0.064008 -3.993896 180)
			(unlocked yes)
			(layer "F.Fab")
			(hide yes)
			(effects
				(font
					(size 1.016 1.016)
					(thickness 0.1524)
				)
			)
		)
		(property "Device Type" "R402H16"
			(at 0.064008 -5.517896 180)
			(unlocked yes)
			(layer "F.Fab")
			(hide yes)
			(effects
				(font
					(size 1.016 1.016)
					(thickness 0.1524)
				)
			)
		)
		(duplicate_pad_numbers_are_jumpers no)
		(fp_line
			(start 0.508 -0.9398)
			(end -0.508 -0.9398)
			(stroke
				(width 0.1524)
				(type default)
			)
			(layer "F.SilkS")
		)
		(fp_line
			(start -0.508 -0.9398)
			(end -0.508 0.9398)
			(stroke
				(width 0.1524)
				(type default)
			)
			(layer "F.SilkS")
		)
		(fp_rect
			(start -0.508 0.9398)
			(end 0.508 -0.9398)
			(stroke
				(width 0)
				(type default)
			)
			(fill no)
			(layer "F.CrtYd")
		)
		(fp_rect
			(start -0.508 0.9398)
			(end 0.508 -0.9398)
			(stroke
				(width 0)
				(type default)
			)
			(fill no)
			(layer "F.Fab")
		)
		(pad "1" smd custom
			(at 0 -0.4445 180)
			(size 0.1397 0.1397)
			(layers "F.Cu" "F.Mask" "F.Paste")
			(net "P3V3")
			(options
				(clearance outline)
				(anchor circle)
			)
			(primitives
				(gr_poly
					(pts
						(arc
							(start -0.1778 -0.2794)
							(mid -0.249642 -0.249642)
							(end -0.2794 -0.1778)
						)
						(arc
							(start -0.2794 0.1778)
							(mid -0.249642 0.249642)
							(end -0.1778 0.2794)
						)
						(arc
							(start 0.1778 0.2794)
							(mid 0.249642 0.249642)
							(end 0.2794 0.1778)
						)
						(arc
							(start 0.2794 -0.1778)
							(mid 0.249642 -0.249642)
							(end 0.1778 -0.2794)
						)
					)
					(width 0)
					(fill yes)
				)
			)
		)
		(pad "2" smd custom
			(at 0 0.4445 180)
			(size 0.1397 0.1397)
			(layers "F.Cu" "F.Mask" "F.Paste")
			(net "FRU_EEPROM_A2")
			(options
				(clearance outline)
				(anchor circle)
			)
			(primitives
				(gr_poly
					(pts
						(arc
							(start -0.1778 -0.2794)
							(mid -0.249642 -0.249642)
							(end -0.2794 -0.1778)
						)
						(arc
							(start -0.2794 0.1778)
							(mid -0.249642 0.249642)
							(end -0.1778 0.2794)
						)
						(arc
							(start 0.1778 0.2794)
							(mid 0.249642 0.249642)
							(end 0.2794 0.1778)
						)
						(arc
							(start 0.2794 -0.1778)
							(mid 0.249642 -0.249642)
							(end 0.1778 -0.2794)
						)
					)
					(width 0)
					(fill yes)
				)
			)
		)
	)
	(footprint ""
		(layer "F.Cu")
		(at 55.88 -121.539 -90)
		(property "Reference" "C704"
			(at 0 0 270)
			(layer "F.SilkS")
			(hide yes)
			(effects
				(font
					(size 1.27 1.27)
				)
			)
		)
		(property "Value" "SC10U6D3V5KX-4GP"
			(at -0.0762 -6.1214 270)
			(unlocked yes)
			(layer "F.Fab")
			(hide yes)
			(effects
				(font
					(size 1.016 1.016)
					(thickness 0.1524)
				)
			)
		)
		(property "Device Type" "C805H58"
			(at -0.0762 -8.1534 270)
			(unlocked yes)
			(layer "F.Fab")
			(hide yes)
			(effects
				(font
					(size 1.016 1.016)
					(thickness 0.1524)
				)
			)
		)
		(duplicate_pad_numbers_are_jumpers no)
		(fp_line
			(start 0.635 0)
			(end -0.635 0)
			(stroke
				(width 0.508)
				(type default)
			)
			(layer "F.SilkS")
		)
		(fp_rect
			(start -0.9652 1.778)
			(end 0.9652 -1.778)
			(stroke
				(width 0)
				(type default)
			)
			(fill no)
			(layer "F.CrtYd")
		)
		(fp_poly
			(pts
				(xy -0.9652 -1.778) (xy 0.9652 -1.778) (xy 0.9652 1.778) (xy -0.9652 1.778)
			)
			(stroke
				(width 0)
				(type default)
			)
			(fill no)
			(layer "F.Fab")
		)
		(pad "1" smd rect
			(at 0 -0.9652 270)
			(size 1.397 1.143)
			(layers "F.Cu" "F.Mask" "F.Paste")
			(net "P3V3_OUT")
		)
		(pad "2" smd rect
			(at 0 0.9652 270)
			(size 1.397 1.143)
			(layers "F.Cu" "F.Mask" "F.Paste")
			(net "GND")
		)
	)
	(footprint ""
		(layer "F.Cu")
		(at 58.5978 -72.6948)
		(property "Reference" "R420"
			(at 0 0 0)
			(layer "F.SilkS")
			(hide yes)
			(effects
				(font
					(size 1.27 1.27)
				)
			)
		)
		(property "Value" "200KR2F-L-GP"
			(at 0.064008 -3.993896 0)
			(unlocked yes)
			(layer "F.Fab")
			(hide yes)
			(effects
				(font
					(size 1.016 1.016)
					(thickness 0.1524)
				)
			)
		)
		(property "Device Type" "R402H16"
			(at 0.064008 -5.517896 0)
			(unlocked yes)
			(layer "F.Fab")
			(hide yes)
			(effects
				(font
					(size 1.016 1.016)
					(thickness 0.1524)
				)
			)
		)
		(duplicate_pad_numbers_are_jumpers no)
		(fp_line
			(start -0.508 -0.9398)
			(end -0.508 0.9398)
			(stroke
				(width 0.1524)
				(type default)
			)
			(layer "F.SilkS")
		)
		(fp_line
			(start 0.508 -0.9398)
			(end -0.508 -0.9398)
			(stroke
				(width 0.1524)
				(type default)
			)
			(layer "F.SilkS")
		)
		(fp_rect
			(start -0.508 0.9398)
			(end 0.508 -0.9398)
			(stroke
				(width 0)
				(type default)
			)
			(fill no)
			(layer "F.CrtYd")
		)
		(fp_rect
			(start -0.508 0.9398)
			(end 0.508 -0.9398)
			(stroke
				(width 0)
				(type default)
			)
			(fill no)
			(layer "F.Fab")
		)
		(pad "1" smd custom
			(at 0 -0.4445)
			(size 0.1397 0.1397)
			(layers "F.Cu" "F.Mask" "F.Paste")
			(net "VREF4")
			(options
				(clearance outline)
				(anchor circle)
			)
			(primitives
				(gr_poly
					(pts
						(arc
							(start -0.1778 -0.2794)
							(mid -0.249642 -0.249642)
							(end -0.2794 -0.1778)
						)
						(arc
							(start -0.2794 0.1778)
							(mid -0.249642 0.249642)
							(end -0.1778 0.2794)
						)
						(arc
							(start 0.1778 0.2794)
							(mid 0.249642 0.249642)
							(end 0.2794 0.1778)
						)
						(arc
							(start 0.2794 -0.1778)
							(mid 0.249642 -0.249642)
							(end 0.1778 -0.2794)
						)
					)
					(width 0)
					(fill yes)
				)
			)
		)
		(pad "2" smd custom
			(at 0 0.4445)
			(size 0.1397 0.1397)
			(layers "F.Cu" "F.Mask" "F.Paste")
			(net "P3V3")
			(options
				(clearance outline)
				(anchor circle)
			)
			(primitives
				(gr_poly
					(pts
						(arc
							(start -0.1778 -0.2794)
							(mid -0.249642 -0.249642)
							(end -0.2794 -0.1778)
						)
						(arc
							(start -0.2794 0.1778)
							(mid -0.249642 0.249642)
							(end -0.1778 0.2794)
						)
						(arc
							(start 0.1778 0.2794)
							(mid 0.249642 0.249642)
							(end 0.2794 0.1778)
						)
						(arc
							(start 0.2794 -0.1778)
							(mid 0.249642 -0.249642)
							(end 0.1778 -0.2794)
						)
					)
					(width 0)
					(fill yes)
				)
			)
		)
	)
	(footprint ""
		(layer "F.Cu")
		(at 191.850772 -47.562262 -90)
		(property "Reference" "R216"
			(at 0 0 270)
			(layer "F.SilkS")
			(hide yes)
			(effects
				(font
					(size 1.27 1.27)
				)
			)
		)
		(property "Value" "10KR2F-2-GP"
			(at 0.064008 -3.993896 270)
			(unlocked yes)
			(layer "F.Fab")
			(hide yes)
			(effects
				(font
					(size 1.016 1.016)
					(thickness 0.1524)
				)
			)
		)
		(property "Device Type" "R402H16"
			(at 0.064008 -5.517896 270)
			(unlocked yes)
			(layer "F.Fab")
			(hide yes)
			(effects
				(font
					(size 1.016 1.016)
					(thickness 0.1524)
				)
			)
		)
		(duplicate_pad_numbers_are_jumpers no)
		(fp_line
			(start -0.508 -0.9398)
			(end -0.508 0.9398)
			(stroke
				(width 0.1524)
				(type default)
			)
			(layer "F.SilkS")
		)
		(fp_line
			(start 0.508 -0.9398)
			(end -0.508 -0.9398)
			(stroke
				(width 0.1524)
				(type default)
			)
			(layer "F.SilkS")
		)
		(fp_rect
			(start -0.508 0.9398)
			(end 0.508 -0.9398)
			(stroke
				(width 0)
				(type default)
			)
			(fill no)
			(layer "F.CrtYd")
		)
		(fp_rect
			(start -0.508 0.9398)
			(end 0.508 -0.9398)
			(stroke
				(width 0)
				(type default)
			)
			(fill no)
			(layer "F.Fab")
		)
		(pad "1" smd custom
			(at 0 -0.4445 270)
			(size 0.1397 0.1397)
			(layers "F.Cu" "F.Mask" "F.Paste")
			(net "P1V8_C")
			(options
				(clearance outline)
				(anchor circle)
			)
			(primitives
				(gr_poly
					(pts
						(arc
							(start -0.1778 -0.2794)
							(mid -0.249642 -0.249642)
							(end -0.2794 -0.1778)
						)
						(arc
							(start -0.2794 0.1778)
							(mid -0.249642 0.249642)
							(end -0.1778 0.2794)
						)
						(arc
							(start 0.1778 0.2794)
							(mid 0.249642 0.249642)
							(end 0.2794 0.1778)
						)
						(arc
							(start 0.2794 -0.1778)
							(mid 0.249642 -0.249642)
							(end 0.1778 -0.2794)
						)
					)
					(width 0)
					(fill yes)
				)
			)
		)
		(pad "2" smd custom
			(at 0 0.4445 270)
			(size 0.1397 0.1397)
			(layers "F.Cu" "F.Mask" "F.Paste")
			(net "XM_ADDR_22")
			(options
				(clearance outline)
				(anchor circle)
			)
			(primitives
				(gr_poly
					(pts
						(arc
							(start -0.1778 -0.2794)
							(mid -0.249642 -0.249642)
							(end -0.2794 -0.1778)
						)
						(arc
							(start -0.2794 0.1778)
							(mid -0.249642 0.249642)
							(end -0.1778 0.2794)
						)
						(arc
							(start 0.1778 0.2794)
							(mid 0.249642 0.249642)
							(end 0.2794 0.1778)
						)
						(arc
							(start 0.2794 -0.1778)
							(mid 0.249642 -0.249642)
							(end 0.1778 -0.2794)
						)
					)
					(width 0)
					(fill yes)
				)
			)
		)
	)
	(footprint ""
		(layer "F.Cu")
		(at 87.122 -77.216 180)
		(property "Reference" "R97"
			(at 0 0 180)
			(layer "F.SilkS")
			(hide yes)
			(effects
				(font
					(size 1.27 1.27)
				)
			)
		)
		(property "Value" "10KR2F-2-GP"
			(at 0.064008 -3.993896 180)
			(unlocked yes)
			(layer "F.Fab")
			(hide yes)
			(effects
				(font
					(size 1.016 1.016)
					(thickness 0.1524)
				)
			)
		)
		(property "Device Type" "R402H16"
			(at 0.064008 -5.517896 180)
			(unlocked yes)
			(layer "F.Fab")
			(hide yes)
			(effects
				(font
					(size 1.016 1.016)
					(thickness 0.1524)
				)
			)
		)
		(duplicate_pad_numbers_are_jumpers no)
		(fp_line
			(start 0.508 -0.9398)
			(end -0.508 -0.9398)
			(stroke
				(width 0.1524)
				(type default)
			)
			(layer "F.SilkS")
		)
		(fp_line
			(start -0.508 -0.9398)
			(end -0.508 0.9398)
			(stroke
				(width 0.1524)
				(type default)
			)
			(layer "F.SilkS")
		)
		(fp_rect
			(start -0.508 0.9398)
			(end 0.508 -0.9398)
			(stroke
				(width 0)
				(type default)
			)
			(fill no)
			(layer "F.CrtYd")
		)
		(fp_rect
			(start -0.508 0.9398)
			(end 0.508 -0.9398)
			(stroke
				(width 0)
				(type default)
			)
			(fill no)
			(layer "F.Fab")
		)
		(pad "1" smd custom
			(at 0 -0.4445 180)
			(size 0.1397 0.1397)
			(layers "F.Cu" "F.Mask" "F.Paste")
			(net "P1V8_E")
			(options
				(clearance outline)
				(anchor circle)
			)
			(primitives
				(gr_poly
					(pts
						(arc
							(start -0.1778 -0.2794)
							(mid -0.249642 -0.249642)
							(end -0.2794 -0.1778)
						)
						(arc
							(start -0.2794 0.1778)
							(mid -0.249642 0.249642)
							(end -0.1778 0.2794)
						)
						(arc
							(start 0.1778 0.2794)
							(mid 0.249642 0.249642)
							(end 0.2794 0.1778)
						)
						(arc
							(start 0.2794 -0.1778)
							(mid 0.249642 -0.249642)
							(end 0.1778 -0.2794)
						)
					)
					(width 0)
					(fill yes)
				)
			)
		)
		(pad "2" smd custom
			(at 0 0.4445 180)
			(size 0.1397 0.1397)
			(layers "F.Cu" "F.Mask" "F.Paste")
			(net "EXP_BLINK_OUT")
			(options
				(clearance outline)
				(anchor circle)
			)
			(primitives
				(gr_poly
					(pts
						(arc
							(start -0.1778 -0.2794)
							(mid -0.249642 -0.249642)
							(end -0.2794 -0.1778)
						)
						(arc
							(start -0.2794 0.1778)
							(mid -0.249642 0.249642)
							(end -0.1778 0.2794)
						)
						(arc
							(start 0.1778 0.2794)
							(mid 0.249642 0.249642)
							(end 0.2794 0.1778)
						)
						(arc
							(start 0.2794 -0.1778)
							(mid 0.249642 -0.249642)
							(end 0.1778 -0.2794)
						)
					)
					(width 0)
					(fill yes)
				)
			)
		)
	)
	(footprint ""
		(layer "F.Cu")
		(at 130.556 -89.7382)
		(property "Reference" "R117"
			(at 0 0 0)
			(layer "F.SilkS")
			(hide yes)
			(effects
				(font
					(size 1.27 1.27)
				)
			)
		)
		(property "Value" "4K75R2F-1-GP"
			(at 0.064008 -3.993896 0)
			(unlocked yes)
			(layer "F.Fab")
			(hide yes)
			(effects
				(font
					(size 1.016 1.016)
					(thickness 0.1524)
				)
			)
		)
		(property "Device Type" "R402H16"
			(at 0.064008 -5.517896 0)
			(unlocked yes)
			(layer "F.Fab")
			(hide yes)
			(effects
				(font
					(size 1.016 1.016)
					(thickness 0.1524)
				)
			)
		)
		(duplicate_pad_numbers_are_jumpers no)
		(fp_line
			(start -0.508 -0.9398)
			(end -0.508 0.9398)
			(stroke
				(width 0.1524)
				(type default)
			)
			(layer "F.SilkS")
		)
		(fp_line
			(start 0.508 -0.9398)
			(end -0.508 -0.9398)
			(stroke
				(width 0.1524)
				(type default)
			)
			(layer "F.SilkS")
		)
		(fp_rect
			(start -0.508 0.9398)
			(end 0.508 -0.9398)
			(stroke
				(width 0)
				(type default)
			)
			(fill no)
			(layer "F.CrtYd")
		)
		(fp_rect
			(start -0.508 0.9398)
			(end 0.508 -0.9398)
			(stroke
				(width 0)
				(type default)
			)
			(fill no)
			(layer "F.Fab")
		)
		(pad "1" smd custom
			(at 0 -0.4445)
			(size 0.1397 0.1397)
			(layers "F.Cu" "F.Mask" "F.Paste")
			(net "P1V8_E")
			(options
				(clearance outline)
				(anchor circle)
			)
			(primitives
				(gr_poly
					(pts
						(arc
							(start -0.1778 -0.2794)
							(mid -0.249642 -0.249642)
							(end -0.2794 -0.1778)
						)
						(arc
							(start -0.2794 0.1778)
							(mid -0.249642 0.249642)
							(end -0.1778 0.2794)
						)
						(arc
							(start 0.1778 0.2794)
							(mid 0.249642 0.249642)
							(end 0.2794 0.1778)
						)
						(arc
							(start 0.2794 -0.1778)
							(mid 0.249642 -0.249642)
							(end 0.1778 -0.2794)
						)
					)
					(width 0)
					(fill yes)
				)
			)
		)
		(pad "2" smd custom
			(at 0 0.4445)
			(size 0.1397 0.1397)
			(layers "F.Cu" "F.Mask" "F.Paste")
			(net "SAS_SMART_RX")
			(options
				(clearance outline)
				(anchor circle)
			)
			(primitives
				(gr_poly
					(pts
						(arc
							(start -0.1778 -0.2794)
							(mid -0.249642 -0.249642)
							(end -0.2794 -0.1778)
						)
						(arc
							(start -0.2794 0.1778)
							(mid -0.249642 0.249642)
							(end -0.1778 0.2794)
						)
						(arc
							(start 0.1778 0.2794)
							(mid 0.249642 0.249642)
							(end 0.2794 0.1778)
						)
						(arc
							(start 0.2794 -0.1778)
							(mid 0.249642 -0.249642)
							(end 0.1778 -0.2794)
						)
					)
					(width 0)
					(fill yes)
				)
			)
		)
	)
	(footprint ""
		(layer "F.Cu")
		(at 124.682758 -46.430438 90)
		(property "Reference" "VIA9"
			(at 0 0 90)
			(layer "F.SilkS")
			(hide yes)
			(effects
				(font
					(size 1.27 1.27)
				)
			)
		)
		(property "Value" "100OHM-8L-1D6MM-L13-GP"
			(at 3.2893 0.0508 90)
			(unlocked yes)
			(layer "F.Fab")
			(hide yes)
			(effects
				(font
					(size 1.016 1.016)
					(thickness 0.1524)
				)
			)
		)
		(property "Device Type" "VIA-PCIE-4P-409091"
			(at 3.2893 -1.4732 90)
			(unlocked yes)
			(layer "F.Fab")
			(hide yes)
			(effects
				(font
					(size 1.016 1.016)
					(thickness 0.1524)
				)
			)
		)
		(duplicate_pad_numbers_are_jumpers no)
		(fp_rect
			(start -2.0447 0.4572)
			(end 2.0447 -0.4572)
			(stroke
				(width 0)
				(type default)
			)
			(fill no)
			(layer "F.CrtYd")
		)
		(fp_rect
			(start -2.0447 0.4572)
			(end 2.0447 -0.4572)
			(stroke
				(width 0)
				(type default)
			)
			(fill no)
			(layer "F.Fab")
		)
		(pad "1" thru_hole circle
			(at -1.5875 0 90)
			(size 0.508 0.508)
			(drill 0.254)
			(layers "*.Cu" "*.Mask")
			(remove_unused_layers no)
			(net "GND")
			(clearance 0.2032)
			(thermal_gap 0.2032)
		)
		(pad "2" thru_hole circle
			(at -0.5715 0 90)
			(size 0.508 0.508)
			(drill 0.254)
			(layers "*.Cu" "*.Mask")
			(remove_unused_layers no)
			(net "PHY_IOC_TO_SCC_C_40_DP")
			(clearance 0.2032)
			(thermal_gap 0.2032)
		)
		(pad "3" thru_hole circle
			(at 0.5715 0 90)
			(size 0.508 0.508)
			(drill 0.254)
			(layers "*.Cu" "*.Mask")
			(remove_unused_layers no)
			(net "PHY_IOC_TO_SCC_C_40_DN")
			(clearance 0.2032)
			(thermal_gap 0.2032)
		)
		(pad "4" thru_hole circle
			(at 1.5875 0 90)
			(size 0.508 0.508)
			(drill 0.254)
			(layers "*.Cu" "*.Mask")
			(remove_unused_layers no)
			(net "GND")
			(clearance 0.2032)
			(thermal_gap 0.2032)
		)
	)
	(footprint ""
		(layer "F.Cu")
		(at 60.6806 -72.6948 180)
		(property "Reference" "R418"
			(at 0 0 180)
			(layer "F.SilkS")
			(hide yes)
			(effects
				(font
					(size 1.27 1.27)
				)
			)
		)
		(property "Value" "1KR2F-3-GP"
			(at 0.064008 -3.993896 180)
			(unlocked yes)
			(layer "F.Fab")
			(hide yes)
			(effects
				(font
					(size 1.016 1.016)
					(thickness 0.1524)
				)
			)
		)
		(property "Device Type" "R402H16"
			(at 0.064008 -5.517896 180)
			(unlocked yes)
			(layer "F.Fab")
			(hide yes)
			(effects
				(font
					(size 1.016 1.016)
					(thickness 0.1524)
				)
			)
		)
		(duplicate_pad_numbers_are_jumpers no)
		(fp_line
			(start 0.508 -0.9398)
			(end -0.508 -0.9398)
			(stroke
				(width 0.1524)
				(type default)
			)
			(layer "F.SilkS")
		)
		(fp_line
			(start -0.508 -0.9398)
			(end -0.508 0.9398)
			(stroke
				(width 0.1524)
				(type default)
			)
			(layer "F.SilkS")
		)
		(fp_rect
			(start -0.508 0.9398)
			(end 0.508 -0.9398)
			(stroke
				(width 0)
				(type default)
			)
			(fill no)
			(layer "F.CrtYd")
		)
		(fp_rect
			(start -0.508 0.9398)
			(end 0.508 -0.9398)
			(stroke
				(width 0)
				(type default)
			)
			(fill no)
			(layer "F.Fab")
		)
		(pad "1" smd custom
			(at 0 -0.4445 180)
			(size 0.1397 0.1397)
			(layers "F.Cu" "F.Mask" "F.Paste")
			(net "P3V3")
			(options
				(clearance outline)
				(anchor circle)
			)
			(primitives
				(gr_poly
					(pts
						(arc
							(start -0.1778 -0.2794)
							(mid -0.249642 -0.249642)
							(end -0.2794 -0.1778)
						)
						(arc
							(start -0.2794 0.1778)
							(mid -0.249642 0.249642)
							(end -0.1778 0.2794)
						)
						(arc
							(start 0.1778 0.2794)
							(mid 0.249642 0.249642)
							(end 0.2794 0.1778)
						)
						(arc
							(start 0.2794 -0.1778)
							(mid 0.249642 -0.249642)
							(end 0.1778 -0.2794)
						)
					)
					(width 0)
					(fill yes)
				)
			)
		)
		(pad "2" smd custom
			(at 0 0.4445 180)
			(size 0.1397 0.1397)
			(layers "F.Cu" "F.Mask" "F.Paste")
			(net "I2C_DRIVE_INS_SDA5")
			(options
				(clearance outline)
				(anchor circle)
			)
			(primitives
				(gr_poly
					(pts
						(arc
							(start -0.1778 -0.2794)
							(mid -0.249642 -0.249642)
							(end -0.2794 -0.1778)
						)
						(arc
							(start -0.2794 0.1778)
							(mid -0.249642 0.249642)
							(end -0.1778 0.2794)
						)
						(arc
							(start 0.1778 0.2794)
							(mid 0.249642 0.249642)
							(end 0.2794 0.1778)
						)
						(arc
							(start 0.2794 -0.1778)
							(mid 0.249642 -0.249642)
							(end 0.1778 -0.2794)
						)
					)
					(width 0)
					(fill yes)
				)
			)
		)
	)
	(footprint ""
		(layer "F.Cu")
		(at 41.21658 -26.49474 90)
		(property "Reference" "R406"
			(at 0 0 90)
			(layer "F.SilkS")
			(hide yes)
			(effects
				(font
					(size 1.27 1.27)
				)
			)
		)
		(property "Value" "0R2J-2-GP"
			(at 0.064008 -3.993896 90)
			(unlocked yes)
			(layer "F.Fab")
			(hide yes)
			(effects
				(font
					(size 1.016 1.016)
					(thickness 0.1524)
				)
			)
		)
		(property "Device Type" "R402H16"
			(at 0.064008 -5.517896 90)
			(unlocked yes)
			(layer "F.Fab")
			(hide yes)
			(effects
				(font
					(size 1.016 1.016)
					(thickness 0.1524)
				)
			)
		)
		(duplicate_pad_numbers_are_jumpers no)
		(fp_line
			(start 0.508 -0.9398)
			(end -0.508 -0.9398)
			(stroke
				(width 0.1524)
				(type default)
			)
			(layer "F.SilkS")
		)
		(fp_line
			(start -0.508 -0.9398)
			(end -0.508 0.9398)
			(stroke
				(width 0.1524)
				(type default)
			)
			(layer "F.SilkS")
		)
		(fp_rect
			(start -0.508 0.9398)
			(end 0.508 -0.9398)
			(stroke
				(width 0)
				(type default)
			)
			(fill no)
			(layer "F.CrtYd")
		)
		(fp_rect
			(start -0.508 0.9398)
			(end 0.508 -0.9398)
			(stroke
				(width 0)
				(type default)
			)
			(fill no)
			(layer "F.Fab")
		)
		(pad "1" smd custom
			(at 0 -0.4445 90)
			(size 0.1397 0.1397)
			(layers "F.Cu" "F.Mask" "F.Paste")
			(net "P0V9_PG")
			(options
				(clearance outline)
				(anchor circle)
			)
			(primitives
				(gr_poly
					(pts
						(arc
							(start -0.1778 -0.2794)
							(mid -0.249642 -0.249642)
							(end -0.2794 -0.1778)
						)
						(arc
							(start -0.2794 0.1778)
							(mid -0.249642 0.249642)
							(end -0.1778 0.2794)
						)
						(arc
							(start 0.1778 0.2794)
							(mid 0.249642 0.249642)
							(end 0.2794 0.1778)
						)
						(arc
							(start 0.2794 -0.1778)
							(mid 0.249642 -0.249642)
							(end 0.1778 -0.2794)
						)
					)
					(width 0)
					(fill yes)
				)
			)
		)
		(pad "2" smd custom
			(at 0 0.4445 90)
			(size 0.1397 0.1397)
			(layers "F.Cu" "F.Mask" "F.Paste")
			(net "SCC_FULL_PGOOD")
			(options
				(clearance outline)
				(anchor circle)
			)
			(primitives
				(gr_poly
					(pts
						(arc
							(start -0.1778 -0.2794)
							(mid -0.249642 -0.249642)
							(end -0.2794 -0.1778)
						)
						(arc
							(start -0.2794 0.1778)
							(mid -0.249642 0.249642)
							(end -0.1778 0.2794)
						)
						(arc
							(start 0.1778 0.2794)
							(mid 0.249642 0.249642)
							(end 0.2794 0.1778)
						)
						(arc
							(start 0.2794 -0.1778)
							(mid 0.249642 -0.249642)
							(end 0.1778 -0.2794)
						)
					)
					(width 0)
					(fill yes)
				)
			)
		)
	)
	(footprint ""
		(layer "F.Cu")
		(at 193.929 -29.21 -90)
		(property "Reference" "TP64"
			(at 0 0 270)
			(layer "F.SilkS")
			(hide yes)
			(effects
				(font
					(size 1.27 1.27)
				)
			)
		)
		(property "Value" "TPAD28-2-GP"
			(at -0.0127 -1.6637 270)
			(unlocked yes)
			(layer "F.Fab")
			(hide yes)
			(effects
				(font
					(size 1.016 1.016)
					(thickness 0.1524)
				)
			)
		)
		(property "Device Type" "TPAD28"
			(at -0.0127 -3.1877 270)
			(unlocked yes)
			(layer "F.Fab")
			(hide yes)
			(effects
				(font
					(size 1.016 1.016)
					(thickness 0.1524)
				)
			)
		)
		(duplicate_pad_numbers_are_jumpers no)
		(fp_poly
			(pts
				(arc
					(start 0 -0.3556)
					(mid 0 0.3556)
					(end 0 -0.3556)
				)
			)
			(stroke
				(width 0)
				(type default)
			)
			(fill no)
			(layer "F.CrtYd")
		)
		(fp_poly
			(pts
				(arc
					(start 0 -0.6096)
					(mid 0 0.6096)
					(end 0 -0.6096)
				)
			)
			(stroke
				(width 0)
				(type default)
			)
			(fill no)
			(layer "F.Fab")
		)
		(pad "1" smd circle
			(at 0 0 270)
			(size 0.7112 0.7112)
			(layers "F.Cu" "F.Mask" "F.Paste")
			(net "IOC_GPIO_11")
		)
	)
	(footprint ""
		(layer "F.Cu")
		(at 70.485 -48.133 90)
		(property "Reference" "L18"
			(at 0 0 90)
			(layer "F.SilkS")
			(hide yes)
			(effects
				(font
					(size 1.27 1.27)
				)
			)
		)
		(property "Value" "MPZ2012S300AT-GP"
			(at 0 -4.2418 90)
			(unlocked yes)
			(layer "F.Fab")
			(hide yes)
			(effects
				(font
					(size 1.016 1.016)
					(thickness 0.1524)
				)
			)
		)
		(property "Device Type" "L805H42"
			(at 0 -5.7912 90)
			(unlocked yes)
			(layer "F.Fab")
			(hide yes)
			(effects
				(font
					(size 1.016 1.016)
					(thickness 0.1524)
				)
			)
		)
		(duplicate_pad_numbers_are_jumpers no)
		(fp_line
			(start 0.889 -1.7018)
			(end 0.889 1.7018)
			(stroke
				(width 0.1524)
				(type default)
			)
			(layer "F.SilkS")
		)
		(fp_line
			(start -0.889 -1.7018)
			(end 0.889 -1.7018)
			(stroke
				(width 0.1524)
				(type default)
			)
			(layer "F.SilkS")
		)
		(fp_line
			(start 0.889 1.7018)
			(end -0.889 1.7018)
			(stroke
				(width 0.1524)
				(type default)
			)
			(layer "F.SilkS")
		)
		(fp_line
			(start -0.889 1.7018)
			(end -0.889 -1.7018)
			(stroke
				(width 0.1524)
				(type default)
			)
			(layer "F.SilkS")
		)
		(fp_rect
			(start -0.9652 1.778)
			(end 0.9652 -1.778)
			(stroke
				(width 0)
				(type default)
			)
			(fill no)
			(layer "F.CrtYd")
		)
		(fp_rect
			(start -0.9652 1.778)
			(end 0.9652 -1.778)
			(stroke
				(width 0)
				(type default)
			)
			(fill no)
			(layer "F.Fab")
		)
		(pad "1" smd rect
			(at 0 -0.9652 90)
			(size 1.397 1.143)
			(layers "F.Cu" "F.Mask" "F.Paste")
			(net "P0V9")
		)
		(pad "2" smd rect
			(at 0 0.9652 90)
			(size 1.397 1.143)
			(layers "F.Cu" "F.Mask" "F.Paste")
			(net "GB_VDDA")
		)
	)
	(footprint ""
		(layer "F.Cu")
		(at 190.119 -27.8765 -90)
		(property "Reference" "TP75"
			(at 0 0 270)
			(layer "F.SilkS")
			(hide yes)
			(effects
				(font
					(size 1.27 1.27)
				)
			)
		)
		(property "Value" "TPAD28-2-GP"
			(at -0.0127 -1.6637 270)
			(unlocked yes)
			(layer "F.Fab")
			(hide yes)
			(effects
				(font
					(size 1.016 1.016)
					(thickness 0.1524)
				)
			)
		)
		(property "Device Type" "TPAD28"
			(at -0.0127 -3.1877 270)
			(unlocked yes)
			(layer "F.Fab")
			(hide yes)
			(effects
				(font
					(size 1.016 1.016)
					(thickness 0.1524)
				)
			)
		)
		(duplicate_pad_numbers_are_jumpers no)
		(fp_poly
			(pts
				(arc
					(start 0 -0.3556)
					(mid 0 0.3556)
					(end 0 -0.3556)
				)
			)
			(stroke
				(width 0)
				(type default)
			)
			(fill no)
			(layer "F.CrtYd")
		)
		(fp_poly
			(pts
				(arc
					(start 0 -0.6096)
					(mid 0 0.6096)
					(end 0 -0.6096)
				)
			)
			(stroke
				(width 0)
				(type default)
			)
			(fill no)
			(layer "F.Fab")
		)
		(pad "1" smd circle
			(at 0 0 270)
			(size 0.7112 0.7112)
			(layers "F.Cu" "F.Mask" "F.Paste")
			(net "IOC_GPIO_22")
		)
	)
	(footprint ""
		(layer "F.Cu")
		(at 170.162474 -99.677982 -90)
		(property "Reference" "R494"
			(at 0 0 270)
			(layer "F.SilkS")
			(hide yes)
			(effects
				(font
					(size 1.27 1.27)
				)
			)
		)
		(property "Value" "7K32R2F-GP"
			(at 0.064008 -3.993896 270)
			(unlocked yes)
			(layer "F.Fab")
			(hide yes)
			(effects
				(font
					(size 1.016 1.016)
					(thickness 0.1524)
				)
			)
		)
		(property "Device Type" "R402H16"
			(at 0.064008 -5.517896 270)
			(unlocked yes)
			(layer "F.Fab")
			(hide yes)
			(effects
				(font
					(size 1.016 1.016)
					(thickness 0.1524)
				)
			)
		)
		(duplicate_pad_numbers_are_jumpers no)
		(fp_line
			(start -0.508 -0.9398)
			(end -0.508 0.9398)
			(stroke
				(width 0.1524)
				(type default)
			)
			(layer "F.SilkS")
		)
		(fp_line
			(start 0.508 -0.9398)
			(end -0.508 -0.9398)
			(stroke
				(width 0.1524)
				(type default)
			)
			(layer "F.SilkS")
		)
		(fp_rect
			(start -0.508 0.9398)
			(end 0.508 -0.9398)
			(stroke
				(width 0)
				(type default)
			)
			(fill no)
			(layer "F.CrtYd")
		)
		(fp_rect
			(start -0.508 0.9398)
			(end 0.508 -0.9398)
			(stroke
				(width 0)
				(type default)
			)
			(fill no)
			(layer "F.Fab")
		)
		(pad "1" smd custom
			(at 0 -0.4445 270)
			(size 0.1397 0.1397)
			(layers "F.Cu" "F.Mask" "F.Paste")
			(net "VT235_VREF")
			(options
				(clearance outline)
				(anchor circle)
			)
			(primitives
				(gr_poly
					(pts
						(arc
							(start -0.1778 -0.2794)
							(mid -0.249642 -0.249642)
							(end -0.2794 -0.1778)
						)
						(arc
							(start -0.2794 0.1778)
							(mid -0.249642 0.249642)
							(end -0.1778 0.2794)
						)
						(arc
							(start 0.1778 0.2794)
							(mid 0.249642 0.249642)
							(end 0.2794 0.1778)
						)
						(arc
							(start 0.2794 -0.1778)
							(mid 0.249642 -0.249642)
							(end 0.1778 -0.2794)
						)
					)
					(width 0)
					(fill yes)
				)
			)
		)
		(pad "2" smd custom
			(at 0 0.4445 270)
			(size 0.1397 0.1397)
			(layers "F.Cu" "F.Mask" "F.Paste")
			(net "VT235_VDES_RR")
			(options
				(clearance outline)
				(anchor circle)
			)
			(primitives
				(gr_poly
					(pts
						(arc
							(start -0.1778 -0.2794)
							(mid -0.249642 -0.249642)
							(end -0.2794 -0.1778)
						)
						(arc
							(start -0.2794 0.1778)
							(mid -0.249642 0.249642)
							(end -0.1778 0.2794)
						)
						(arc
							(start 0.1778 0.2794)
							(mid 0.249642 0.249642)
							(end 0.2794 0.1778)
						)
						(arc
							(start 0.2794 -0.1778)
							(mid 0.249642 -0.249642)
							(end 0.1778 -0.2794)
						)
					)
					(width 0)
					(fill yes)
				)
			)
		)
	)
	(footprint ""
		(layer "F.Cu")
		(at 168.770808 -56.46801)
		(property "Reference" "TP122"
			(at 0 0 0)
			(layer "F.SilkS")
			(hide yes)
			(effects
				(font
					(size 1.27 1.27)
				)
			)
		)
		(property "Value" "TPAD28-2-GP"
			(at -0.0127 -1.6637 0)
			(unlocked yes)
			(layer "F.Fab")
			(hide yes)
			(effects
				(font
					(size 1.016 1.016)
					(thickness 0.1524)
				)
			)
		)
		(property "Device Type" "TPAD28"
			(at -0.0127 -3.1877 0)
			(unlocked yes)
			(layer "F.Fab")
			(hide yes)
			(effects
				(font
					(size 1.016 1.016)
					(thickness 0.1524)
				)
			)
		)
		(duplicate_pad_numbers_are_jumpers no)
		(fp_poly
			(pts
				(arc
					(start 0.3556 0)
					(mid -0.3556 0)
					(end 0.3556 0)
				)
			)
			(stroke
				(width 0)
				(type default)
			)
			(fill no)
			(layer "F.CrtYd")
		)
		(fp_poly
			(pts
				(arc
					(start 0.6096 0)
					(mid -0.6096 0)
					(end 0.6096 0)
				)
			)
			(stroke
				(width 0)
				(type default)
			)
			(fill no)
			(layer "F.Fab")
		)
		(pad "1" smd circle
			(at 0 0)
			(size 0.7112 0.7112)
			(layers "F.Cu" "F.Mask" "F.Paste")
			(net "ICE0_TDO")
		)
	)
	(footprint ""
		(layer "F.Cu")
		(at 13.362178 -43.193208 180)
		(property "Reference" "R520"
			(at 0 0 180)
			(layer "F.SilkS")
			(hide yes)
			(effects
				(font
					(size 1.27 1.27)
				)
			)
		)
		(property "Value" "10R2F-L-GP"
			(at 0.064008 -3.993896 180)
			(unlocked yes)
			(layer "F.Fab")
			(hide yes)
			(effects
				(font
					(size 1.016 1.016)
					(thickness 0.1524)
				)
			)
		)
		(property "Device Type" "R402H14"
			(at 0.064008 -5.517896 180)
			(unlocked yes)
			(layer "F.Fab")
			(hide yes)
			(effects
				(font
					(size 1.016 1.016)
					(thickness 0.1524)
				)
			)
		)
		(duplicate_pad_numbers_are_jumpers no)
		(fp_line
			(start 0.508 -0.9398)
			(end -0.508 -0.9398)
			(stroke
				(width 0.1524)
				(type default)
			)
			(layer "F.SilkS")
		)
		(fp_line
			(start -0.508 -0.9398)
			(end -0.508 0.9398)
			(stroke
				(width 0.1524)
				(type default)
			)
			(layer "F.SilkS")
		)
		(fp_rect
			(start -0.508 0.9398)
			(end 0.508 -0.9398)
			(stroke
				(width 0)
				(type default)
			)
			(fill no)
			(layer "F.CrtYd")
		)
		(fp_rect
			(start -0.508 0.9398)
			(end 0.508 -0.9398)
			(stroke
				(width 0)
				(type default)
			)
			(fill no)
			(layer "F.Fab")
		)
		(pad "1" smd custom
			(at 0 -0.4445 180)
			(size 0.1397 0.1397)
			(layers "F.Cu" "F.Mask" "F.Paste")
			(net "MB0_CM_SENSE_R1_N")
			(options
				(clearance outline)
				(anchor circle)
			)
			(primitives
				(gr_poly
					(pts
						(arc
							(start -0.1778 -0.2794)
							(mid -0.249642 -0.249642)
							(end -0.2794 -0.1778)
						)
						(arc
							(start -0.2794 0.1778)
							(mid -0.249642 0.249642)
							(end -0.1778 0.2794)
						)
						(arc
							(start 0.1778 0.2794)
							(mid 0.249642 0.249642)
							(end 0.2794 0.1778)
						)
						(arc
							(start 0.2794 -0.1778)
							(mid 0.249642 -0.249642)
							(end 0.1778 -0.2794)
						)
					)
					(width 0)
					(fill yes)
				)
			)
		)
		(pad "2" smd custom
			(at 0 0.4445 180)
			(size 0.1397 0.1397)
			(layers "F.Cu" "F.Mask" "F.Paste")
			(net "MB0_CM_SENSE_N")
			(options
				(clearance outline)
				(anchor circle)
			)
			(primitives
				(gr_poly
					(pts
						(arc
							(start -0.1778 -0.2794)
							(mid -0.249642 -0.249642)
							(end -0.2794 -0.1778)
						)
						(arc
							(start -0.2794 0.1778)
							(mid -0.249642 0.249642)
							(end -0.1778 0.2794)
						)
						(arc
							(start 0.1778 0.2794)
							(mid 0.249642 0.249642)
							(end 0.2794 0.1778)
						)
						(arc
							(start 0.2794 -0.1778)
							(mid 0.249642 -0.249642)
							(end 0.1778 -0.2794)
						)
					)
					(width 0)
					(fill yes)
				)
			)
		)
	)
	(footprint ""
		(layer "F.Cu")
		(at 148.02358 -119.00662 -90)
		(property "Reference" "R27"
			(at 0 0 270)
			(layer "F.SilkS")
			(hide yes)
			(effects
				(font
					(size 1.27 1.27)
				)
			)
		)
		(property "Value" "10KR2F-2-GP"
			(at 0.064008 -3.993896 270)
			(unlocked yes)
			(layer "F.Fab")
			(hide yes)
			(effects
				(font
					(size 1.016 1.016)
					(thickness 0.1524)
				)
			)
		)
		(property "Device Type" "R402H16"
			(at 0.064008 -5.517896 270)
			(unlocked yes)
			(layer "F.Fab")
			(hide yes)
			(effects
				(font
					(size 1.016 1.016)
					(thickness 0.1524)
				)
			)
		)
		(duplicate_pad_numbers_are_jumpers no)
		(fp_line
			(start -0.508 -0.9398)
			(end -0.508 0.9398)
			(stroke
				(width 0.1524)
				(type default)
			)
			(layer "F.SilkS")
		)
		(fp_line
			(start 0.508 -0.9398)
			(end -0.508 -0.9398)
			(stroke
				(width 0.1524)
				(type default)
			)
			(layer "F.SilkS")
		)
		(fp_rect
			(start -0.508 0.9398)
			(end 0.508 -0.9398)
			(stroke
				(width 0)
				(type default)
			)
			(fill no)
			(layer "F.CrtYd")
		)
		(fp_rect
			(start -0.508 0.9398)
			(end 0.508 -0.9398)
			(stroke
				(width 0)
				(type default)
			)
			(fill no)
			(layer "F.Fab")
		)
		(pad "1" smd custom
			(at 0 -0.4445 270)
			(size 0.1397 0.1397)
			(layers "F.Cu" "F.Mask" "F.Paste")
			(net "P1V5_E_PG")
			(options
				(clearance outline)
				(anchor circle)
			)
			(primitives
				(gr_poly
					(pts
						(arc
							(start -0.1778 -0.2794)
							(mid -0.249642 -0.249642)
							(end -0.2794 -0.1778)
						)
						(arc
							(start -0.2794 0.1778)
							(mid -0.249642 0.249642)
							(end -0.1778 0.2794)
						)
						(arc
							(start 0.1778 0.2794)
							(mid 0.249642 0.249642)
							(end 0.2794 0.1778)
						)
						(arc
							(start 0.2794 -0.1778)
							(mid 0.249642 -0.249642)
							(end 0.1778 -0.2794)
						)
					)
					(width 0)
					(fill yes)
				)
			)
		)
		(pad "2" smd custom
			(at 0 0.4445 270)
			(size 0.1397 0.1397)
			(layers "F.Cu" "F.Mask" "F.Paste")
			(net "P3V3")
			(options
				(clearance outline)
				(anchor circle)
			)
			(primitives
				(gr_poly
					(pts
						(arc
							(start -0.1778 -0.2794)
							(mid -0.249642 -0.249642)
							(end -0.2794 -0.1778)
						)
						(arc
							(start -0.2794 0.1778)
							(mid -0.249642 0.249642)
							(end -0.1778 0.2794)
						)
						(arc
							(start 0.1778 0.2794)
							(mid 0.249642 0.249642)
							(end 0.2794 0.1778)
						)
						(arc
							(start 0.2794 -0.1778)
							(mid 0.249642 -0.249642)
							(end 0.1778 -0.2794)
						)
					)
					(width 0)
					(fill yes)
				)
			)
		)
	)
	(footprint ""
		(layer "F.Cu")
		(at 49.089056 -34.899092)
		(property "Reference" "PSP1"
			(at 0 0 0)
			(layer "F.SilkS")
			(hide yes)
			(effects
				(font
					(size 1.27 1.27)
				)
			)
		)
		(property "Value" "COPPER-CLOSE-GP-U"
			(at 0.0762 -2.8702 0)
			(unlocked yes)
			(layer "F.Fab")
			(hide yes)
			(effects
				(font
					(size 1.016 1.016)
					(thickness 0.1524)
				)
			)
		)
		(property "Device Type" "CON2C-U"
			(at 0.0762 -4.3942 0)
			(unlocked yes)
			(layer "F.Fab")
			(hide yes)
			(effects
				(font
					(size 1.016 1.016)
					(thickness 0.1524)
				)
			)
		)
		(duplicate_pad_numbers_are_jumpers no)
		(fp_rect
			(start -0.9398 0.9652)
			(end 0.9398 -0.9652)
			(stroke
				(width 0)
				(type default)
			)
			(fill no)
			(layer "F.CrtYd")
		)
		(fp_rect
			(start -0.9398 0.9652)
			(end 0.9398 -0.9652)
			(stroke
				(width 0)
				(type default)
			)
			(fill no)
			(layer "F.Fab")
		)
		(pad "1" smd custom
			(at 0 -0.5334)
			(size 0.17145 0.17145)
			(layers "F.Cu" "F.Mask" "F.Paste")
			(net "GND")
			(options
				(clearance outline)
				(anchor circle)
			)
			(primitives
				(gr_poly
					(pts
						(xy -0.127 0.3429) (xy -0.127 0.1651) (xy -0.635 -0.3429) (xy 0.635 -0.3429) (xy 0.127 0.1651)
						(xy 0.127 0.3429)
					)
					(width 0)
					(fill yes)
				)
			)
		)
		(pad "2" smd custom
			(at 0 0.5334)
			(size 0.17145 0.17145)
			(layers "F.Cu" "F.Mask" "F.Paste")
			(net "AGND_P0V9")
			(options
				(clearance outline)
				(anchor circle)
			)
			(primitives
				(gr_poly
					(pts
						(xy -0.635 0.3429) (xy -0.127 -0.1651) (xy -0.127 -0.3429) (xy 0.127 -0.3429) (xy 0.127 -0.1651)
						(xy 0.635 0.3429)
					)
					(width 0)
					(fill yes)
				)
			)
		)
	)
	(footprint ""
		(layer "F.Cu")
		(at 159.722312 -92.563696 90)
		(property "Reference" "R286"
			(at 0 0 90)
			(layer "F.SilkS")
			(hide yes)
			(effects
				(font
					(size 1.27 1.27)
				)
			)
		)
		(property "Value" "10KR2F-2-GP"
			(at 0.064008 -3.993896 90)
			(unlocked yes)
			(layer "F.Fab")
			(hide yes)
			(effects
				(font
					(size 1.016 1.016)
					(thickness 0.1524)
				)
			)
		)
		(property "Device Type" "R402H16"
			(at 0.064008 -5.517896 90)
			(unlocked yes)
			(layer "F.Fab")
			(hide yes)
			(effects
				(font
					(size 1.016 1.016)
					(thickness 0.1524)
				)
			)
		)
		(duplicate_pad_numbers_are_jumpers no)
		(fp_line
			(start 0.508 -0.9398)
			(end -0.508 -0.9398)
			(stroke
				(width 0.1524)
				(type default)
			)
			(layer "F.SilkS")
		)
		(fp_line
			(start -0.508 -0.9398)
			(end -0.508 0.9398)
			(stroke
				(width 0.1524)
				(type default)
			)
			(layer "F.SilkS")
		)
		(fp_rect
			(start -0.508 0.9398)
			(end 0.508 -0.9398)
			(stroke
				(width 0)
				(type default)
			)
			(fill no)
			(layer "F.CrtYd")
		)
		(fp_rect
			(start -0.508 0.9398)
			(end 0.508 -0.9398)
			(stroke
				(width 0)
				(type default)
			)
			(fill no)
			(layer "F.Fab")
		)
		(pad "1" smd custom
			(at 0 -0.4445 90)
			(size 0.1397 0.1397)
			(layers "F.Cu" "F.Mask" "F.Paste")
			(net "SMART_UART_EN")
			(options
				(clearance outline)
				(anchor circle)
			)
			(primitives
				(gr_poly
					(pts
						(arc
							(start -0.1778 -0.2794)
							(mid -0.249642 -0.249642)
							(end -0.2794 -0.1778)
						)
						(arc
							(start -0.2794 0.1778)
							(mid -0.249642 0.249642)
							(end -0.1778 0.2794)
						)
						(arc
							(start 0.1778 0.2794)
							(mid 0.249642 0.249642)
							(end 0.2794 0.1778)
						)
						(arc
							(start 0.2794 -0.1778)
							(mid 0.249642 -0.249642)
							(end 0.1778 -0.2794)
						)
					)
					(width 0)
					(fill yes)
				)
			)
		)
		(pad "2" smd custom
			(at 0 0.4445 90)
			(size 0.1397 0.1397)
			(layers "F.Cu" "F.Mask" "F.Paste")
			(net "P1V8_E")
			(options
				(clearance outline)
				(anchor circle)
			)
			(primitives
				(gr_poly
					(pts
						(arc
							(start -0.1778 -0.2794)
							(mid -0.249642 -0.249642)
							(end -0.2794 -0.1778)
						)
						(arc
							(start -0.2794 0.1778)
							(mid -0.249642 0.249642)
							(end -0.1778 0.2794)
						)
						(arc
							(start 0.1778 0.2794)
							(mid 0.249642 0.249642)
							(end 0.2794 0.1778)
						)
						(arc
							(start 0.2794 -0.1778)
							(mid 0.249642 -0.249642)
							(end 0.1778 -0.2794)
						)
					)
					(width 0)
					(fill yes)
				)
			)
		)
	)
	(footprint ""
		(layer "F.Cu")
		(at 128.863598 -87.265002 180)
		(property "Reference" "R101"
			(at 0 0 180)
			(layer "F.SilkS")
			(hide yes)
			(effects
				(font
					(size 1.27 1.27)
				)
			)
		)
		(property "Value" "0R2J-2-GP"
			(at 0.064008 -3.993896 180)
			(unlocked yes)
			(layer "F.Fab")
			(hide yes)
			(effects
				(font
					(size 1.016 1.016)
					(thickness 0.1524)
				)
			)
		)
		(property "Device Type" "R402H16"
			(at 0.064008 -5.517896 180)
			(unlocked yes)
			(layer "F.Fab")
			(hide yes)
			(effects
				(font
					(size 1.016 1.016)
					(thickness 0.1524)
				)
			)
		)
		(duplicate_pad_numbers_are_jumpers no)
		(fp_line
			(start 0.508 -0.9398)
			(end -0.508 -0.9398)
			(stroke
				(width 0.1524)
				(type default)
			)
			(layer "F.SilkS")
		)
		(fp_line
			(start -0.508 -0.9398)
			(end -0.508 0.9398)
			(stroke
				(width 0.1524)
				(type default)
			)
			(layer "F.SilkS")
		)
		(fp_rect
			(start -0.508 0.9398)
			(end 0.508 -0.9398)
			(stroke
				(width 0)
				(type default)
			)
			(fill no)
			(layer "F.CrtYd")
		)
		(fp_rect
			(start -0.508 0.9398)
			(end 0.508 -0.9398)
			(stroke
				(width 0)
				(type default)
			)
			(fill no)
			(layer "F.Fab")
		)
		(pad "1" smd custom
			(at 0 -0.4445 180)
			(size 0.1397 0.1397)
			(layers "F.Cu" "F.Mask" "F.Paste")
			(net "SMART_TX")
			(options
				(clearance outline)
				(anchor circle)
			)
			(primitives
				(gr_poly
					(pts
						(arc
							(start -0.1778 -0.2794)
							(mid -0.249642 -0.249642)
							(end -0.2794 -0.1778)
						)
						(arc
							(start -0.2794 0.1778)
							(mid -0.249642 0.249642)
							(end -0.1778 0.2794)
						)
						(arc
							(start 0.1778 0.2794)
							(mid 0.249642 0.249642)
							(end 0.2794 0.1778)
						)
						(arc
							(start 0.2794 -0.1778)
							(mid 0.249642 -0.249642)
							(end 0.1778 -0.2794)
						)
					)
					(width 0)
					(fill yes)
				)
			)
		)
		(pad "2" smd custom
			(at 0 0.4445 180)
			(size 0.1397 0.1397)
			(layers "F.Cu" "F.Mask" "F.Paste")
			(net "SAS_SMART_TX")
			(options
				(clearance outline)
				(anchor circle)
			)
			(primitives
				(gr_poly
					(pts
						(arc
							(start -0.1778 -0.2794)
							(mid -0.249642 -0.249642)
							(end -0.2794 -0.1778)
						)
						(arc
							(start -0.2794 0.1778)
							(mid -0.249642 0.249642)
							(end -0.1778 0.2794)
						)
						(arc
							(start 0.1778 0.2794)
							(mid 0.249642 0.249642)
							(end 0.2794 0.1778)
						)
						(arc
							(start 0.2794 -0.1778)
							(mid 0.249642 -0.249642)
							(end 0.1778 -0.2794)
						)
					)
					(width 0)
					(fill yes)
				)
			)
		)
	)
	(footprint ""
		(layer "F.Cu")
		(at 151.897842 -98.605594 180)
		(property "Reference" "C506"
			(at 0 0 180)
			(layer "F.SilkS")
			(hide yes)
			(effects
				(font
					(size 1.27 1.27)
				)
			)
		)
		(property "Value" "SCD1U16V2KX-3GP"
			(at 1.1811 -2.7051 180)
			(unlocked yes)
			(layer "F.Fab")
			(hide yes)
			(effects
				(font
					(size 1.016 1.016)
					(thickness 0.1524)
				)
			)
		)
		(property "Device Type" "C402H22"
			(at 1.1811 -4.2291 180)
			(unlocked yes)
			(layer "F.Fab")
			(hide yes)
			(effects
				(font
					(size 1.016 1.016)
					(thickness 0.1524)
				)
			)
		)
		(duplicate_pad_numbers_are_jumpers no)
		(fp_rect
			(start -0.4318 0.9525)
			(end 0.4318 -0.9525)
			(stroke
				(width 0)
				(type default)
			)
			(fill no)
			(layer "F.CrtYd")
		)
		(fp_rect
			(start -0.4318 0.9525)
			(end 0.4318 -0.9525)
			(stroke
				(width 0)
				(type default)
			)
			(fill no)
			(layer "F.Fab")
		)
		(pad "1" smd custom
			(at 0 -0.4445 180)
			(size 0.1524 0.1524)
			(layers "F.Cu" "F.Mask" "F.Paste")
			(net "P1V8_E")
			(options
				(clearance outline)
				(anchor circle)
			)
			(primitives
				(gr_poly
					(pts
						(arc
							(start 0.3048 -0.2032)
							(mid 0.275042 -0.275042)
							(end 0.2032 -0.3048)
						)
						(arc
							(start -0.2032 -0.3048)
							(mid -0.275042 -0.275042)
							(end -0.3048 -0.2032)
						)
						(arc
							(start -0.3048 0.2032)
							(mid -0.275042 0.275042)
							(end -0.2032 0.3048)
						)
						(arc
							(start 0.2032 0.3048)
							(mid 0.275042 0.275042)
							(end 0.3048 0.2032)
						)
					)
					(width 0)
					(fill yes)
				)
			)
		)
		(pad "2" smd custom
			(at 0 0.4445 180)
			(size 0.1524 0.1524)
			(layers "F.Cu" "F.Mask" "F.Paste")
			(net "GND")
			(options
				(clearance outline)
				(anchor circle)
			)
			(primitives
				(gr_poly
					(pts
						(arc
							(start 0.3048 -0.2032)
							(mid 0.275042 -0.275042)
							(end 0.2032 -0.3048)
						)
						(arc
							(start -0.2032 -0.3048)
							(mid -0.275042 -0.275042)
							(end -0.3048 -0.2032)
						)
						(arc
							(start -0.3048 0.2032)
							(mid -0.275042 0.275042)
							(end -0.2032 0.3048)
						)
						(arc
							(start 0.2032 0.3048)
							(mid 0.275042 0.275042)
							(end 0.3048 0.2032)
						)
					)
					(width 0)
					(fill yes)
				)
			)
		)
	)
	(footprint ""
		(layer "F.Cu")
		(at 11.045698 -43.314874 180)
		(property "Reference" "Q37"
			(at 0 0 180)
			(layer "F.SilkS")
			(hide yes)
			(effects
				(font
					(size 1.27 1.27)
				)
			)
		)
		(property "Value" "MMBT3904-3-GP"
			(at 0.10287 -10.29843 180)
			(unlocked yes)
			(layer "F.Fab")
			(hide yes)
			(effects
				(font
					(size 1.016 1.016)
					(thickness 0.1524)
				)
			)
		)
		(property "Device Type" "SOT23CBE2D4H44"
			(at 0.10287 -12.20343 180)
			(unlocked yes)
			(layer "F.Fab")
			(hide yes)
			(effects
				(font
					(size 1.016 1.016)
					(thickness 0.1524)
				)
			)
		)
		(duplicate_pad_numbers_are_jumpers no)
		(fp_line
			(start 1.651 1.778)
			(end 1.651 -1.778)
			(stroke
				(width 0.1524)
				(type default)
			)
			(layer "F.SilkS")
		)
		(fp_line
			(start 1.651 -1.778)
			(end -1.651 -1.778)
			(stroke
				(width 0.1524)
				(type default)
			)
			(layer "F.SilkS")
		)
		(fp_line
			(start -1.651 1.778)
			(end 1.651 1.778)
			(stroke
				(width 0.1524)
				(type default)
			)
			(layer "F.SilkS")
		)
		(fp_line
			(start -1.651 -1.778)
			(end -1.651 1.778)
			(stroke
				(width 0.1524)
				(type default)
			)
			(layer "F.SilkS")
		)
		(fp_poly
			(pts
				(xy -1.778 1.8796) (xy -1.778 -1.8796) (xy 1.778 -1.8796) (xy 1.778 1.8796)
			)
			(stroke
				(width 0)
				(type default)
			)
			(fill no)
			(layer "F.CrtYd")
		)
		(fp_poly
			(pts
				(xy -1.778 1.8796) (xy -1.778 -1.8796) (xy 1.778 -1.8796) (xy 1.778 1.8796)
			)
			(stroke
				(width 0)
				(type default)
			)
			(fill no)
			(layer "F.Fab")
		)
		(pad "B" smd custom
			(at -0.98425 0.9525 180)
			(size 0.1905 0.1905)
			(layers "F.Cu" "F.Mask" "F.Paste")
			(net "MB0_TEMP_C")
			(options
				(clearance outline)
				(anchor circle)
			)
			(primitives
				(gr_poly
					(pts
						(arc
							(start -0.1778 0.5715)
							(mid -0.321484 0.511984)
							(end -0.381 0.3683)
						)
						(arc
							(start -0.381 -0.3683)
							(mid -0.321484 -0.511984)
							(end -0.1778 -0.5715)
						)
						(arc
							(start 0.1778 -0.5715)
							(mid 0.321484 -0.511984)
							(end 0.381 -0.3683)
						)
						(arc
							(start 0.381 0.3683)
							(mid 0.321484 0.511984)
							(end 0.1778 0.5715)
						)
					)
					(width 0)
					(fill yes)
				)
			)
		)
		(pad "C" smd custom
			(at 0 -0.9525 180)
			(size 0.1905 0.1905)
			(layers "F.Cu" "F.Mask" "F.Paste")
			(net "MB0_TEMP_C")
			(options
				(clearance outline)
				(anchor circle)
			)
			(primitives
				(gr_poly
					(pts
						(arc
							(start -0.1778 0.5715)
							(mid -0.321484 0.511984)
							(end -0.381 0.3683)
						)
						(arc
							(start -0.381 -0.3683)
							(mid -0.321484 -0.511984)
							(end -0.1778 -0.5715)
						)
						(arc
							(start 0.1778 -0.5715)
							(mid 0.321484 -0.511984)
							(end 0.381 -0.3683)
						)
						(arc
							(start 0.381 0.3683)
							(mid 0.321484 0.511984)
							(end 0.1778 0.5715)
						)
					)
					(width 0)
					(fill yes)
				)
			)
		)
		(pad "E" smd custom
			(at 0.98425 0.9525 180)
			(size 0.1905 0.1905)
			(layers "F.Cu" "F.Mask" "F.Paste")
			(net "MB0_TEMP_E")
			(options
				(clearance outline)
				(anchor circle)
			)
			(primitives
				(gr_poly
					(pts
						(arc
							(start -0.1778 0.5715)
							(mid -0.321484 0.511984)
							(end -0.381 0.3683)
						)
						(arc
							(start -0.381 -0.3683)
							(mid -0.321484 -0.511984)
							(end -0.1778 -0.5715)
						)
						(arc
							(start 0.1778 -0.5715)
							(mid 0.321484 -0.511984)
							(end 0.381 -0.3683)
						)
						(arc
							(start 0.381 0.3683)
							(mid 0.321484 0.511984)
							(end 0.1778 0.5715)
						)
					)
					(width 0)
					(fill yes)
				)
			)
		)
	)
	(footprint ""
		(layer "F.Cu")
		(at 113.6142 -86.995)
		(property "Reference" "R455"
			(at 0 0 0)
			(layer "F.SilkS")
			(hide yes)
			(effects
				(font
					(size 1.27 1.27)
				)
			)
		)
		(property "Value" "4K7R2F-GP"
			(at 0.064008 -3.993896 0)
			(unlocked yes)
			(layer "F.Fab")
			(hide yes)
			(effects
				(font
					(size 1.016 1.016)
					(thickness 0.1524)
				)
			)
		)
		(property "Device Type" "R402H16"
			(at 0.064008 -5.517896 0)
			(unlocked yes)
			(layer "F.Fab")
			(hide yes)
			(effects
				(font
					(size 1.016 1.016)
					(thickness 0.1524)
				)
			)
		)
		(duplicate_pad_numbers_are_jumpers no)
		(fp_line
			(start -0.508 -0.9398)
			(end -0.508 0.9398)
			(stroke
				(width 0.1524)
				(type default)
			)
			(layer "F.SilkS")
		)
		(fp_line
			(start 0.508 -0.9398)
			(end -0.508 -0.9398)
			(stroke
				(width 0.1524)
				(type default)
			)
			(layer "F.SilkS")
		)
		(fp_rect
			(start -0.508 0.9398)
			(end 0.508 -0.9398)
			(stroke
				(width 0)
				(type default)
			)
			(fill no)
			(layer "F.CrtYd")
		)
		(fp_rect
			(start -0.508 0.9398)
			(end 0.508 -0.9398)
			(stroke
				(width 0)
				(type default)
			)
			(fill no)
			(layer "F.Fab")
		)
		(pad "1" smd custom
			(at 0 -0.4445)
			(size 0.1397 0.1397)
			(layers "F.Cu" "F.Mask" "F.Paste")
			(net "P1V8_E")
			(options
				(clearance outline)
				(anchor circle)
			)
			(primitives
				(gr_poly
					(pts
						(arc
							(start -0.1778 -0.2794)
							(mid -0.249642 -0.249642)
							(end -0.2794 -0.1778)
						)
						(arc
							(start -0.2794 0.1778)
							(mid -0.249642 0.249642)
							(end -0.1778 0.2794)
						)
						(arc
							(start 0.1778 0.2794)
							(mid 0.249642 0.249642)
							(end 0.2794 0.1778)
						)
						(arc
							(start 0.2794 -0.1778)
							(mid 0.249642 -0.249642)
							(end 0.1778 -0.2794)
						)
					)
					(width 0)
					(fill yes)
				)
			)
		)
		(pad "2" smd custom
			(at 0 0.4445)
			(size 0.1397 0.1397)
			(layers "F.Cu" "F.Mask" "F.Paste")
			(net "EXP_XM_ADDR_25")
			(options
				(clearance outline)
				(anchor circle)
			)
			(primitives
				(gr_poly
					(pts
						(arc
							(start -0.1778 -0.2794)
							(mid -0.249642 -0.249642)
							(end -0.2794 -0.1778)
						)
						(arc
							(start -0.2794 0.1778)
							(mid -0.249642 0.249642)
							(end -0.1778 0.2794)
						)
						(arc
							(start 0.1778 0.2794)
							(mid 0.249642 0.249642)
							(end 0.2794 0.1778)
						)
						(arc
							(start 0.2794 -0.1778)
							(mid 0.249642 -0.249642)
							(end 0.1778 -0.2794)
						)
					)
					(width 0)
					(fill yes)
				)
			)
		)
	)
	(footprint ""
		(layer "F.Cu")
		(at 58.9788 -95.9612 -90)
		(property "Reference" "C701"
			(at 0 0 270)
			(layer "F.SilkS")
			(hide yes)
			(effects
				(font
					(size 1.27 1.27)
				)
			)
		)
		(property "Value" "SC10U16V5KX-7-GP-U"
			(at -0.0762 -6.1214 270)
			(unlocked yes)
			(layer "F.Fab")
			(hide yes)
			(effects
				(font
					(size 1.016 1.016)
					(thickness 0.1524)
				)
			)
		)
		(property "Device Type" "C805H58"
			(at -0.0762 -8.1534 270)
			(unlocked yes)
			(layer "F.Fab")
			(hide yes)
			(effects
				(font
					(size 1.016 1.016)
					(thickness 0.1524)
				)
			)
		)
		(duplicate_pad_numbers_are_jumpers no)
		(fp_line
			(start 0.635 0)
			(end -0.635 0)
			(stroke
				(width 0.508)
				(type default)
			)
			(layer "F.SilkS")
		)
		(fp_rect
			(start -0.9652 1.778)
			(end 0.9652 -1.778)
			(stroke
				(width 0)
				(type default)
			)
			(fill no)
			(layer "F.CrtYd")
		)
		(fp_poly
			(pts
				(xy -0.9652 -1.778) (xy 0.9652 -1.778) (xy 0.9652 1.778) (xy -0.9652 1.778)
			)
			(stroke
				(width 0)
				(type default)
			)
			(fill no)
			(layer "F.Fab")
		)
		(pad "1" smd rect
			(at 0 -0.9652 270)
			(size 1.397 1.143)
			(layers "F.Cu" "F.Mask" "F.Paste")
			(net "P12V_STBY_VIN_U10")
		)
		(pad "2" smd rect
			(at 0 0.9652 270)
			(size 1.397 1.143)
			(layers "F.Cu" "F.Mask" "F.Paste")
			(net "GND")
		)
	)
	(footprint ""
		(layer "F.Cu")
		(at 13.895578 -44.590208 -90)
		(property "Reference" "C522"
			(at 0 0 270)
			(layer "F.SilkS")
			(hide yes)
			(effects
				(font
					(size 1.27 1.27)
				)
			)
		)
		(property "Value" "SCD015U25V2KX-GP"
			(at 1.1811 -2.7051 270)
			(unlocked yes)
			(layer "F.Fab")
			(hide yes)
			(effects
				(font
					(size 1.016 1.016)
					(thickness 0.1524)
				)
			)
		)
		(property "Device Type" "C402H22"
			(at 1.1811 -4.2291 270)
			(unlocked yes)
			(layer "F.Fab")
			(hide yes)
			(effects
				(font
					(size 1.016 1.016)
					(thickness 0.1524)
				)
			)
		)
		(duplicate_pad_numbers_are_jumpers no)
		(fp_rect
			(start -0.4318 0.9525)
			(end 0.4318 -0.9525)
			(stroke
				(width 0)
				(type default)
			)
			(fill no)
			(layer "F.CrtYd")
		)
		(fp_rect
			(start -0.4318 0.9525)
			(end 0.4318 -0.9525)
			(stroke
				(width 0)
				(type default)
			)
			(fill no)
			(layer "F.Fab")
		)
		(pad "1" smd custom
			(at 0 -0.4445 270)
			(size 0.1524 0.1524)
			(layers "F.Cu" "F.Mask" "F.Paste")
			(net "MB0_CM_SENSE_P")
			(options
				(clearance outline)
				(anchor circle)
			)
			(primitives
				(gr_poly
					(pts
						(arc
							(start 0.3048 -0.2032)
							(mid 0.275042 -0.275042)
							(end 0.2032 -0.3048)
						)
						(arc
							(start -0.2032 -0.3048)
							(mid -0.275042 -0.275042)
							(end -0.3048 -0.2032)
						)
						(arc
							(start -0.3048 0.2032)
							(mid -0.275042 0.275042)
							(end -0.2032 0.3048)
						)
						(arc
							(start 0.2032 0.3048)
							(mid 0.275042 0.275042)
							(end 0.3048 0.2032)
						)
					)
					(width 0)
					(fill yes)
				)
			)
		)
		(pad "2" smd custom
			(at 0 0.4445 270)
			(size 0.1524 0.1524)
			(layers "F.Cu" "F.Mask" "F.Paste")
			(net "MB0_CM_SENSE_N")
			(options
				(clearance outline)
				(anchor circle)
			)
			(primitives
				(gr_poly
					(pts
						(arc
							(start 0.3048 -0.2032)
							(mid 0.275042 -0.275042)
							(end 0.2032 -0.3048)
						)
						(arc
							(start -0.2032 -0.3048)
							(mid -0.275042 -0.275042)
							(end -0.3048 -0.2032)
						)
						(arc
							(start -0.3048 0.2032)
							(mid -0.275042 0.275042)
							(end -0.2032 0.3048)
						)
						(arc
							(start 0.2032 0.3048)
							(mid 0.275042 0.275042)
							(end 0.3048 0.2032)
						)
					)
					(width 0)
					(fill yes)
				)
			)
		)
	)
	(footprint ""
		(layer "F.Cu")
		(at 165.172898 -58.108596)
		(property "Reference" "R262"
			(at 0 0 0)
			(layer "F.SilkS")
			(hide yes)
			(effects
				(font
					(size 1.27 1.27)
				)
			)
		)
		(property "Value" "4K7R2F-GP"
			(at 0.064008 -3.993896 0)
			(unlocked yes)
			(layer "F.Fab")
			(hide yes)
			(effects
				(font
					(size 1.016 1.016)
					(thickness 0.1524)
				)
			)
		)
		(property "Device Type" "R402H16"
			(at 0.064008 -5.517896 0)
			(unlocked yes)
			(layer "F.Fab")
			(hide yes)
			(effects
				(font
					(size 1.016 1.016)
					(thickness 0.1524)
				)
			)
		)
		(duplicate_pad_numbers_are_jumpers no)
		(fp_line
			(start -0.508 -0.9398)
			(end -0.508 0.9398)
			(stroke
				(width 0.1524)
				(type default)
			)
			(layer "F.SilkS")
		)
		(fp_line
			(start 0.508 -0.9398)
			(end -0.508 -0.9398)
			(stroke
				(width 0.1524)
				(type default)
			)
			(layer "F.SilkS")
		)
		(fp_rect
			(start -0.508 0.9398)
			(end 0.508 -0.9398)
			(stroke
				(width 0)
				(type default)
			)
			(fill no)
			(layer "F.CrtYd")
		)
		(fp_rect
			(start -0.508 0.9398)
			(end 0.508 -0.9398)
			(stroke
				(width 0)
				(type default)
			)
			(fill no)
			(layer "F.Fab")
		)
		(pad "1" smd custom
			(at 0 -0.4445)
			(size 0.1397 0.1397)
			(layers "F.Cu" "F.Mask" "F.Paste")
			(net "P1V8_C")
			(options
				(clearance outline)
				(anchor circle)
			)
			(primitives
				(gr_poly
					(pts
						(arc
							(start -0.1778 -0.2794)
							(mid -0.249642 -0.249642)
							(end -0.2794 -0.1778)
						)
						(arc
							(start -0.2794 0.1778)
							(mid -0.249642 0.249642)
							(end -0.1778 0.2794)
						)
						(arc
							(start 0.1778 0.2794)
							(mid 0.249642 0.249642)
							(end 0.2794 0.1778)
						)
						(arc
							(start 0.2794 -0.1778)
							(mid 0.249642 -0.249642)
							(end 0.1778 -0.2794)
						)
					)
					(width 0)
					(fill yes)
				)
			)
		)
		(pad "2" smd custom
			(at 0 0.4445)
			(size 0.1397 0.1397)
			(layers "F.Cu" "F.Mask" "F.Paste")
			(net "ICE1_TMS")
			(options
				(clearance outline)
				(anchor circle)
			)
			(primitives
				(gr_poly
					(pts
						(arc
							(start -0.1778 -0.2794)
							(mid -0.249642 -0.249642)
							(end -0.2794 -0.1778)
						)
						(arc
							(start -0.2794 0.1778)
							(mid -0.249642 0.249642)
							(end -0.1778 0.2794)
						)
						(arc
							(start 0.1778 0.2794)
							(mid 0.249642 0.249642)
							(end 0.2794 0.1778)
						)
						(arc
							(start 0.2794 -0.1778)
							(mid 0.249642 -0.249642)
							(end 0.1778 -0.2794)
						)
					)
					(width 0)
					(fill yes)
				)
			)
		)
	)
	(footprint ""
		(layer "F.Cu")
		(at 18.6944 -80.8228 90)
		(property "Reference" "C528"
			(at 0 0 90)
			(layer "F.SilkS")
			(hide yes)
			(effects
				(font
					(size 1.27 1.27)
				)
			)
		)
		(property "Value" "SCD1U16V2KX-3GP"
			(at 1.1811 -2.7051 90)
			(unlocked yes)
			(layer "F.Fab")
			(hide yes)
			(effects
				(font
					(size 1.016 1.016)
					(thickness 0.1524)
				)
			)
		)
		(property "Device Type" "C402H22"
			(at 1.1811 -4.2291 90)
			(unlocked yes)
			(layer "F.Fab")
			(hide yes)
			(effects
				(font
					(size 1.016 1.016)
					(thickness 0.1524)
				)
			)
		)
		(duplicate_pad_numbers_are_jumpers no)
		(fp_rect
			(start -0.4318 0.9525)
			(end 0.4318 -0.9525)
			(stroke
				(width 0)
				(type default)
			)
			(fill no)
			(layer "F.CrtYd")
		)
		(fp_rect
			(start -0.4318 0.9525)
			(end 0.4318 -0.9525)
			(stroke
				(width 0)
				(type default)
			)
			(fill no)
			(layer "F.Fab")
		)
		(pad "1" smd custom
			(at 0 -0.4445 90)
			(size 0.1524 0.1524)
			(layers "F.Cu" "F.Mask" "F.Paste")
			(net "P3V3")
			(options
				(clearance outline)
				(anchor circle)
			)
			(primitives
				(gr_poly
					(pts
						(arc
							(start 0.3048 -0.2032)
							(mid 0.275042 -0.275042)
							(end 0.2032 -0.3048)
						)
						(arc
							(start -0.2032 -0.3048)
							(mid -0.275042 -0.275042)
							(end -0.3048 -0.2032)
						)
						(arc
							(start -0.3048 0.2032)
							(mid -0.275042 0.275042)
							(end -0.2032 0.3048)
						)
						(arc
							(start 0.2032 0.3048)
							(mid 0.275042 0.275042)
							(end 0.3048 0.2032)
						)
					)
					(width 0)
					(fill yes)
				)
			)
		)
		(pad "2" smd custom
			(at 0 0.4445 90)
			(size 0.1524 0.1524)
			(layers "F.Cu" "F.Mask" "F.Paste")
			(net "GND")
			(options
				(clearance outline)
				(anchor circle)
			)
			(primitives
				(gr_poly
					(pts
						(arc
							(start 0.3048 -0.2032)
							(mid 0.275042 -0.275042)
							(end 0.2032 -0.3048)
						)
						(arc
							(start -0.2032 -0.3048)
							(mid -0.275042 -0.275042)
							(end -0.3048 -0.2032)
						)
						(arc
							(start -0.3048 0.2032)
							(mid -0.275042 0.275042)
							(end -0.2032 0.3048)
						)
						(arc
							(start 0.2032 0.3048)
							(mid 0.275042 0.275042)
							(end 0.3048 0.2032)
						)
					)
					(width 0)
					(fill yes)
				)
			)
		)
	)
	(footprint ""
		(layer "F.Cu")
		(at 198.53656 -74.46772 90)
		(property "Reference" "R298"
			(at 0 0 90)
			(layer "F.SilkS")
			(hide yes)
			(effects
				(font
					(size 1.27 1.27)
				)
			)
		)
		(property "Value" "0R2J-2-GP"
			(at 0.064008 -3.993896 90)
			(unlocked yes)
			(layer "F.Fab")
			(hide yes)
			(effects
				(font
					(size 1.016 1.016)
					(thickness 0.1524)
				)
			)
		)
		(property "Device Type" "R402H16"
			(at 0.064008 -5.517896 90)
			(unlocked yes)
			(layer "F.Fab")
			(hide yes)
			(effects
				(font
					(size 1.016 1.016)
					(thickness 0.1524)
				)
			)
		)
		(duplicate_pad_numbers_are_jumpers no)
		(fp_line
			(start 0.508 -0.9398)
			(end -0.508 -0.9398)
			(stroke
				(width 0.1524)
				(type default)
			)
			(layer "F.SilkS")
		)
		(fp_line
			(start -0.508 -0.9398)
			(end -0.508 0.9398)
			(stroke
				(width 0.1524)
				(type default)
			)
			(layer "F.SilkS")
		)
		(fp_rect
			(start -0.508 0.9398)
			(end 0.508 -0.9398)
			(stroke
				(width 0)
				(type default)
			)
			(fill no)
			(layer "F.CrtYd")
		)
		(fp_rect
			(start -0.508 0.9398)
			(end 0.508 -0.9398)
			(stroke
				(width 0)
				(type default)
			)
			(fill no)
			(layer "F.Fab")
		)
		(pad "1" smd custom
			(at 0 -0.4445 90)
			(size 0.1397 0.1397)
			(layers "F.Cu" "F.Mask" "F.Paste")
			(net "IOC_UART_0_RX_R")
			(options
				(clearance outline)
				(anchor circle)
			)
			(primitives
				(gr_poly
					(pts
						(arc
							(start -0.1778 -0.2794)
							(mid -0.249642 -0.249642)
							(end -0.2794 -0.1778)
						)
						(arc
							(start -0.2794 0.1778)
							(mid -0.249642 0.249642)
							(end -0.1778 0.2794)
						)
						(arc
							(start 0.1778 0.2794)
							(mid 0.249642 0.249642)
							(end 0.2794 0.1778)
						)
						(arc
							(start 0.2794 -0.1778)
							(mid 0.249642 -0.249642)
							(end 0.1778 -0.2794)
						)
					)
					(width 0)
					(fill yes)
				)
			)
		)
		(pad "2" smd custom
			(at 0 0.4445 90)
			(size 0.1397 0.1397)
			(layers "F.Cu" "F.Mask" "F.Paste")
			(net "IOC_UART_0_RX")
			(options
				(clearance outline)
				(anchor circle)
			)
			(primitives
				(gr_poly
					(pts
						(arc
							(start -0.1778 -0.2794)
							(mid -0.249642 -0.249642)
							(end -0.2794 -0.1778)
						)
						(arc
							(start -0.2794 0.1778)
							(mid -0.249642 0.249642)
							(end -0.1778 0.2794)
						)
						(arc
							(start 0.1778 0.2794)
							(mid 0.249642 0.249642)
							(end 0.2794 0.1778)
						)
						(arc
							(start 0.2794 -0.1778)
							(mid 0.249642 -0.249642)
							(end 0.1778 -0.2794)
						)
					)
					(width 0)
					(fill yes)
				)
			)
		)
	)
	(footprint ""
		(layer "F.Cu")
		(at 136.398 -109.601 -90)
		(property "Reference" "C694"
			(at 0 0 270)
			(layer "F.SilkS")
			(hide yes)
			(effects
				(font
					(size 1.27 1.27)
				)
			)
		)
		(property "Value" "SC10U6D3V5KX-4GP"
			(at -0.0762 -6.1214 270)
			(unlocked yes)
			(layer "F.Fab")
			(hide yes)
			(effects
				(font
					(size 1.016 1.016)
					(thickness 0.1524)
				)
			)
		)
		(property "Device Type" "C805H58"
			(at -0.0762 -8.1534 270)
			(unlocked yes)
			(layer "F.Fab")
			(hide yes)
			(effects
				(font
					(size 1.016 1.016)
					(thickness 0.1524)
				)
			)
		)
		(duplicate_pad_numbers_are_jumpers no)
		(fp_line
			(start 0.635 0)
			(end -0.635 0)
			(stroke
				(width 0.508)
				(type default)
			)
			(layer "F.SilkS")
		)
		(fp_rect
			(start -0.9652 1.778)
			(end 0.9652 -1.778)
			(stroke
				(width 0)
				(type default)
			)
			(fill no)
			(layer "F.CrtYd")
		)
		(fp_poly
			(pts
				(xy -0.9652 -1.778) (xy 0.9652 -1.778) (xy 0.9652 1.778) (xy -0.9652 1.778)
			)
			(stroke
				(width 0)
				(type default)
			)
			(fill no)
			(layer "F.Fab")
		)
		(pad "1" smd rect
			(at 0 -0.9652 270)
			(size 1.397 1.143)
			(layers "F.Cu" "F.Mask" "F.Paste")
			(net "P1V5_E_OUT")
		)
		(pad "2" smd rect
			(at 0 0.9652 270)
			(size 1.397 1.143)
			(layers "F.Cu" "F.Mask" "F.Paste")
			(net "GND")
		)
	)
	(footprint ""
		(layer "F.Cu")
		(at 65.4685 -108.331 90)
		(property "Reference" "R514"
			(at 0 0 90)
			(layer "F.SilkS")
			(hide yes)
			(effects
				(font
					(size 1.27 1.27)
				)
			)
		)
		(property "Value" "2K7R2F-GP"
			(at 0.064008 -3.993896 90)
			(unlocked yes)
			(layer "F.Fab")
			(hide yes)
			(effects
				(font
					(size 1.016 1.016)
					(thickness 0.1524)
				)
			)
		)
		(property "Device Type" "R402H16"
			(at 0.064008 -5.517896 90)
			(unlocked yes)
			(layer "F.Fab")
			(hide yes)
			(effects
				(font
					(size 1.016 1.016)
					(thickness 0.1524)
				)
			)
		)
		(duplicate_pad_numbers_are_jumpers no)
		(fp_line
			(start 0.508 -0.9398)
			(end -0.508 -0.9398)
			(stroke
				(width 0.1524)
				(type default)
			)
			(layer "F.SilkS")
		)
		(fp_line
			(start -0.508 -0.9398)
			(end -0.508 0.9398)
			(stroke
				(width 0.1524)
				(type default)
			)
			(layer "F.SilkS")
		)
		(fp_rect
			(start -0.508 0.9398)
			(end 0.508 -0.9398)
			(stroke
				(width 0)
				(type default)
			)
			(fill no)
			(layer "F.CrtYd")
		)
		(fp_rect
			(start -0.508 0.9398)
			(end 0.508 -0.9398)
			(stroke
				(width 0)
				(type default)
			)
			(fill no)
			(layer "F.Fab")
		)
		(pad "1" smd custom
			(at 0 -0.4445 90)
			(size 0.1397 0.1397)
			(layers "F.Cu" "F.Mask" "F.Paste")
			(net "P3V3_LL")
			(options
				(clearance outline)
				(anchor circle)
			)
			(primitives
				(gr_poly
					(pts
						(arc
							(start -0.1778 -0.2794)
							(mid -0.249642 -0.249642)
							(end -0.2794 -0.1778)
						)
						(arc
							(start -0.2794 0.1778)
							(mid -0.249642 0.249642)
							(end -0.1778 0.2794)
						)
						(arc
							(start 0.1778 0.2794)
							(mid 0.249642 0.249642)
							(end 0.2794 0.1778)
						)
						(arc
							(start 0.2794 -0.1778)
							(mid 0.249642 -0.249642)
							(end 0.1778 -0.2794)
						)
					)
					(width 0)
					(fill yes)
				)
			)
		)
		(pad "2" smd custom
			(at 0 0.4445 90)
			(size 0.1397 0.1397)
			(layers "F.Cu" "F.Mask" "F.Paste")
			(net "P3V3_LL_R")
			(options
				(clearance outline)
				(anchor circle)
			)
			(primitives
				(gr_poly
					(pts
						(arc
							(start -0.1778 -0.2794)
							(mid -0.249642 -0.249642)
							(end -0.2794 -0.1778)
						)
						(arc
							(start -0.2794 0.1778)
							(mid -0.249642 0.249642)
							(end -0.1778 0.2794)
						)
						(arc
							(start 0.1778 0.2794)
							(mid 0.249642 0.249642)
							(end 0.2794 0.1778)
						)
						(arc
							(start 0.2794 -0.1778)
							(mid 0.249642 -0.249642)
							(end 0.1778 -0.2794)
						)
					)
					(width 0)
					(fill yes)
				)
			)
		)
	)
	(footprint ""
		(layer "F.Cu")
		(at 39.8018 -49.7332 180)
		(property "Reference" "C671"
			(at 0 0 180)
			(layer "F.SilkS")
			(hide yes)
			(effects
				(font
					(size 1.27 1.27)
				)
			)
		)
		(property "Value" "SC10U16V5KX-7-GP-U"
			(at -0.0762 -6.1214 180)
			(unlocked yes)
			(layer "F.Fab")
			(hide yes)
			(effects
				(font
					(size 1.016 1.016)
					(thickness 0.1524)
				)
			)
		)
		(property "Device Type" "C805H58"
			(at -0.0762 -8.1534 180)
			(unlocked yes)
			(layer "F.Fab")
			(hide yes)
			(effects
				(font
					(size 1.016 1.016)
					(thickness 0.1524)
				)
			)
		)
		(duplicate_pad_numbers_are_jumpers no)
		(fp_line
			(start 0.635 0)
			(end -0.635 0)
			(stroke
				(width 0.508)
				(type default)
			)
			(layer "F.SilkS")
		)
		(fp_rect
			(start -0.9652 1.778)
			(end 0.9652 -1.778)
			(stroke
				(width 0)
				(type default)
			)
			(fill no)
			(layer "F.CrtYd")
		)
		(fp_poly
			(pts
				(xy -0.9652 -1.778) (xy 0.9652 -1.778) (xy 0.9652 1.778) (xy -0.9652 1.778)
			)
			(stroke
				(width 0)
				(type default)
			)
			(fill no)
			(layer "F.Fab")
		)
		(pad "1" smd rect
			(at 0 -0.9652 180)
			(size 1.397 1.143)
			(layers "F.Cu" "F.Mask" "F.Paste")
			(net "P12V_STBY_VIN_Q7")
		)
		(pad "2" smd rect
			(at 0 0.9652 180)
			(size 1.397 1.143)
			(layers "F.Cu" "F.Mask" "F.Paste")
			(net "GND")
		)
	)
	(footprint ""
		(layer "F.Cu")
		(at 137.595356 -84.709762)
		(property "Reference" "R58"
			(at 0 0 0)
			(layer "F.SilkS")
			(hide yes)
			(effects
				(font
					(size 1.27 1.27)
				)
			)
		)
		(property "Value" "4K7R2F-GP"
			(at 0.064008 -3.993896 0)
			(unlocked yes)
			(layer "F.Fab")
			(hide yes)
			(effects
				(font
					(size 1.016 1.016)
					(thickness 0.1524)
				)
			)
		)
		(property "Device Type" "R402H16"
			(at 0.064008 -5.517896 0)
			(unlocked yes)
			(layer "F.Fab")
			(hide yes)
			(effects
				(font
					(size 1.016 1.016)
					(thickness 0.1524)
				)
			)
		)
		(duplicate_pad_numbers_are_jumpers no)
		(fp_line
			(start -0.508 -0.9398)
			(end -0.508 0.9398)
			(stroke
				(width 0.1524)
				(type default)
			)
			(layer "F.SilkS")
		)
		(fp_line
			(start 0.508 -0.9398)
			(end -0.508 -0.9398)
			(stroke
				(width 0.1524)
				(type default)
			)
			(layer "F.SilkS")
		)
		(fp_rect
			(start -0.508 0.9398)
			(end 0.508 -0.9398)
			(stroke
				(width 0)
				(type default)
			)
			(fill no)
			(layer "F.CrtYd")
		)
		(fp_rect
			(start -0.508 0.9398)
			(end 0.508 -0.9398)
			(stroke
				(width 0)
				(type default)
			)
			(fill no)
			(layer "F.Fab")
		)
		(pad "1" smd custom
			(at 0 -0.4445)
			(size 0.1397 0.1397)
			(layers "F.Cu" "F.Mask" "F.Paste")
			(net "P1V8_E")
			(options
				(clearance outline)
				(anchor circle)
			)
			(primitives
				(gr_poly
					(pts
						(arc
							(start -0.1778 -0.2794)
							(mid -0.249642 -0.249642)
							(end -0.2794 -0.1778)
						)
						(arc
							(start -0.2794 0.1778)
							(mid -0.249642 0.249642)
							(end -0.1778 0.2794)
						)
						(arc
							(start 0.1778 0.2794)
							(mid 0.249642 0.249642)
							(end 0.2794 0.1778)
						)
						(arc
							(start 0.2794 -0.1778)
							(mid 0.249642 -0.249642)
							(end 0.1778 -0.2794)
						)
					)
					(width 0)
					(fill yes)
				)
			)
		)
		(pad "2" smd custom
			(at 0 0.4445)
			(size 0.1397 0.1397)
			(layers "F.Cu" "F.Mask" "F.Paste")
			(net "I2C_DRIVE_INS_SCL5_LS")
			(options
				(clearance outline)
				(anchor circle)
			)
			(primitives
				(gr_poly
					(pts
						(arc
							(start -0.1778 -0.2794)
							(mid -0.249642 -0.249642)
							(end -0.2794 -0.1778)
						)
						(arc
							(start -0.2794 0.1778)
							(mid -0.249642 0.249642)
							(end -0.1778 0.2794)
						)
						(arc
							(start 0.1778 0.2794)
							(mid 0.249642 0.249642)
							(end 0.2794 0.1778)
						)
						(arc
							(start 0.2794 -0.1778)
							(mid 0.249642 -0.249642)
							(end 0.1778 -0.2794)
						)
					)
					(width 0)
					(fill yes)
				)
			)
		)
	)
	(footprint ""
		(layer "F.Cu")
		(at 62.384686 -21.500846 180)
		(property "Reference" "U49"
			(at 0 0 180)
			(layer "F.SilkS")
			(hide yes)
			(effects
				(font
					(size 1.27 1.27)
				)
			)
		)
		(property "Value" "SNLVC1G126DCKR-GP"
			(at -2.3368 -8.6868 180)
			(unlocked yes)
			(layer "F.Fab")
			(hide yes)
			(effects
				(font
					(size 1.016 1.016)
					(thickness 0.1524)
				)
			)
		)
		(property "Device Type" "SC70-5H44"
			(at -2.3114 -10.414 180)
			(unlocked yes)
			(layer "F.Fab")
			(hide yes)
			(effects
				(font
					(size 1.016 1.016)
					(thickness 0.1524)
				)
			)
		)
		(duplicate_pad_numbers_are_jumpers no)
		(fp_line
			(start 1.3843 -1.8034)
			(end 1.3843 -1.1176)
			(stroke
				(width 0.3302)
				(type default)
			)
			(layer "F.SilkS")
		)
		(fp_line
			(start 1.27 1.7018)
			(end -1.27 1.7018)
			(stroke
				(width 0.1524)
				(type default)
			)
			(layer "F.SilkS")
		)
		(fp_line
			(start 1.27 -1.7018)
			(end 1.27 1.7018)
			(stroke
				(width 0.1524)
				(type default)
			)
			(layer "F.SilkS")
		)
		(fp_line
			(start 0.6604 -1.8034)
			(end 1.3843 -1.8034)
			(stroke
				(width 0.3302)
				(type default)
			)
			(layer "F.SilkS")
		)
		(fp_line
			(start -1.27 1.7018)
			(end -1.27 -1.7018)
			(stroke
				(width 0.1524)
				(type default)
			)
			(layer "F.SilkS")
		)
		(fp_line
			(start -1.27 -1.7018)
			(end 1.27 -1.7018)
			(stroke
				(width 0.1524)
				(type default)
			)
			(layer "F.SilkS")
		)
		(fp_rect
			(start -1.524 1.9558)
			(end 1.524 -1.9558)
			(stroke
				(width 0)
				(type default)
			)
			(fill no)
			(layer "F.CrtYd")
		)
		(fp_poly
			(pts
				(xy -1.524 -1.9558) (xy 1.524 -1.9558) (xy 1.524 1.9558) (xy -1.524 1.9558)
			)
			(stroke
				(width 0)
				(type default)
			)
			(fill no)
			(layer "F.Fab")
		)
		(pad "1" smd rect
			(at 0.65024 -0.8255 180)
			(size 0.4064 1.2192)
			(layers "F.Cu" "F.Mask" "F.Paste")
			(net "U49_OE")
		)
		(pad "2" smd rect
			(at 0 -0.8255 180)
			(size 0.4064 1.2192)
			(layers "F.Cu" "F.Mask" "F.Paste")
			(net "SCC_STBY_PGOOD_U49")
		)
		(pad "3" smd rect
			(at -0.65024 -0.8255 180)
			(size 0.4064 1.2192)
			(layers "F.Cu" "F.Mask" "F.Paste")
			(net "GND")
		)
		(pad "4" smd rect
			(at -0.65024 0.8255 180)
			(size 0.4064 1.2192)
			(layers "F.Cu" "F.Mask" "F.Paste")
			(net "SCC_FULL_PWR_EN_U49")
		)
		(pad "5" smd rect
			(at 0.65024 0.8255 180)
			(size 0.4064 1.2192)
			(layers "F.Cu" "F.Mask" "F.Paste")
			(net "P3V3")
		)
	)
	(footprint ""
		(layer "F.Cu")
		(at 151.257 -85.8266 -90)
		(property "Reference" "C575"
			(at 0 0 270)
			(layer "F.SilkS")
			(hide yes)
			(effects
				(font
					(size 1.27 1.27)
				)
			)
		)
		(property "Value" "SCD1U16V2KX-3GP"
			(at 1.1811 -2.7051 270)
			(unlocked yes)
			(layer "F.Fab")
			(hide yes)
			(effects
				(font
					(size 1.016 1.016)
					(thickness 0.1524)
				)
			)
		)
		(property "Device Type" "C402H22"
			(at 1.1811 -4.2291 270)
			(unlocked yes)
			(layer "F.Fab")
			(hide yes)
			(effects
				(font
					(size 1.016 1.016)
					(thickness 0.1524)
				)
			)
		)
		(duplicate_pad_numbers_are_jumpers no)
		(fp_rect
			(start -0.4318 0.9525)
			(end 0.4318 -0.9525)
			(stroke
				(width 0)
				(type default)
			)
			(fill no)
			(layer "F.CrtYd")
		)
		(fp_rect
			(start -0.4318 0.9525)
			(end 0.4318 -0.9525)
			(stroke
				(width 0)
				(type default)
			)
			(fill no)
			(layer "F.Fab")
		)
		(pad "1" smd custom
			(at 0 -0.4445 270)
			(size 0.1524 0.1524)
			(layers "F.Cu" "F.Mask" "F.Paste")
			(net "P3V3_SENSE")
			(options
				(clearance outline)
				(anchor circle)
			)
			(primitives
				(gr_poly
					(pts
						(arc
							(start 0.3048 -0.2032)
							(mid 0.275042 -0.275042)
							(end 0.2032 -0.3048)
						)
						(arc
							(start -0.2032 -0.3048)
							(mid -0.275042 -0.275042)
							(end -0.3048 -0.2032)
						)
						(arc
							(start -0.3048 0.2032)
							(mid -0.275042 0.275042)
							(end -0.2032 0.3048)
						)
						(arc
							(start 0.2032 0.3048)
							(mid 0.275042 0.275042)
							(end 0.3048 0.2032)
						)
					)
					(width 0)
					(fill yes)
				)
			)
		)
		(pad "2" smd custom
			(at 0 0.4445 270)
			(size 0.1524 0.1524)
			(layers "F.Cu" "F.Mask" "F.Paste")
			(net "GND")
			(options
				(clearance outline)
				(anchor circle)
			)
			(primitives
				(gr_poly
					(pts
						(arc
							(start 0.3048 -0.2032)
							(mid 0.275042 -0.275042)
							(end 0.2032 -0.3048)
						)
						(arc
							(start -0.2032 -0.3048)
							(mid -0.275042 -0.275042)
							(end -0.3048 -0.2032)
						)
						(arc
							(start -0.3048 0.2032)
							(mid -0.275042 0.275042)
							(end -0.2032 0.3048)
						)
						(arc
							(start 0.2032 0.3048)
							(mid 0.275042 0.275042)
							(end 0.3048 0.2032)
						)
					)
					(width 0)
					(fill yes)
				)
			)
		)
	)
	(footprint ""
		(layer "F.Cu")
		(at 175.697134 -56.7182)
		(property "Reference" "TP136"
			(at 0 0 0)
			(layer "F.SilkS")
			(hide yes)
			(effects
				(font
					(size 1.27 1.27)
				)
			)
		)
		(property "Value" "TPAD28-2-GP"
			(at -0.0127 -1.6637 0)
			(unlocked yes)
			(layer "F.Fab")
			(hide yes)
			(effects
				(font
					(size 1.016 1.016)
					(thickness 0.1524)
				)
			)
		)
		(property "Device Type" "TPAD28"
			(at -0.0127 -3.1877 0)
			(unlocked yes)
			(layer "F.Fab")
			(hide yes)
			(effects
				(font
					(size 1.016 1.016)
					(thickness 0.1524)
				)
			)
		)
		(duplicate_pad_numbers_are_jumpers no)
		(fp_poly
			(pts
				(arc
					(start 0.3556 0)
					(mid -0.3556 0)
					(end 0.3556 0)
				)
			)
			(stroke
				(width 0)
				(type default)
			)
			(fill no)
			(layer "F.CrtYd")
		)
		(fp_poly
			(pts
				(arc
					(start 0.6096 0)
					(mid -0.6096 0)
					(end 0.6096 0)
				)
			)
			(stroke
				(width 0)
				(type default)
			)
			(fill no)
			(layer "F.Fab")
		)
		(pad "1" smd circle
			(at 0 0)
			(size 0.7112 0.7112)
			(layers "F.Cu" "F.Mask" "F.Paste")
			(net "JTAG_IOC_TDI")
		)
	)
	(footprint ""
		(layer "F.Cu")
		(at 149.837648 -38.566598 102)
		(property "Reference" "C331"
			(at 0 0 102)
			(layer "F.SilkS")
			(hide yes)
			(effects
				(font
					(size 1.27 1.27)
				)
			)
		)
		(property "Value" "SCD01U16V1KX-GP"
			(at -2.832048 -1.739777 102)
			(unlocked yes)
			(layer "F.Fab")
			(hide yes)
			(effects
				(font
					(size 1.016 1.016)
					(thickness 0.1524)
				)
			)
		)
		(property "Device Type" "C0201H13"
			(at -2.831925 -3.263781 102)
			(unlocked yes)
			(layer "F.Fab")
			(hide yes)
			(effects
				(font
					(size 1.016 1.016)
					(thickness 0.1524)
				)
			)
		)
		(duplicate_pad_numbers_are_jumpers no)
		(fp_poly
			(pts
				(xy -0.279454 -0.647706) (xy 0.279346 -0.647706) (xy 0.279346 0.647694) (xy -0.279454 0.647694)
			)
			(stroke
				(width 0)
				(type default)
			)
			(fill no)
			(layer "F.CrtYd")
		)
		(fp_poly
			(pts
				(xy -0.279454 -0.647706) (xy 0.279346 -0.647706) (xy 0.279346 0.647694) (xy -0.279454 0.647694)
			)
			(stroke
				(width 0)
				(type default)
			)
			(fill no)
			(layer "F.Fab")
		)
		(pad "1" smd custom
			(at -0.000001 -0.2794 102)
			(size 0.0762 0.0762)
			(layers "F.Cu" "F.Mask" "F.Paste")
			(net "PHY_SCC_TO_IOC_42_DP")
			(options
				(clearance outline)
				(anchor circle)
			)
			(primitives
				(gr_poly
					(pts
						(arc
							(start 0.1524 -0.127)
							(mid 0.137521 -0.162921)
							(end 0.1016 -0.1778)
						)
						(arc
							(start -0.1016 -0.1778)
							(mid -0.137521 -0.162921)
							(end -0.1524 -0.127)
						)
						(arc
							(start -0.1524 0.127)
							(mid -0.137521 0.162921)
							(end -0.1016 0.1778)
						)
						(arc
							(start 0.1016 0.1778)
							(mid 0.137521 0.162921)
							(end 0.1524 0.127)
						)
					)
					(width 0)
					(fill yes)
				)
			)
		)
		(pad "2" smd custom
			(at 0.000001 0.2794 102)
			(size 0.0762 0.0762)
			(layers "F.Cu" "F.Mask" "F.Paste")
			(net "PHY_SCC_TO_IOC_C_42_DP")
			(options
				(clearance outline)
				(anchor circle)
			)
			(primitives
				(gr_poly
					(pts
						(arc
							(start 0.1524 -0.127)
							(mid 0.137521 -0.162921)
							(end 0.1016 -0.1778)
						)
						(arc
							(start -0.1016 -0.1778)
							(mid -0.137521 -0.162921)
							(end -0.1524 -0.127)
						)
						(arc
							(start -0.1524 0.127)
							(mid -0.137521 0.162921)
							(end -0.1016 0.1778)
						)
						(arc
							(start 0.1016 0.1778)
							(mid 0.137521 0.162921)
							(end 0.1524 0.127)
						)
					)
					(width 0)
					(fill yes)
				)
			)
		)
	)
	(footprint ""
		(layer "F.Cu")
		(at 138.482324 -104.872028 180)
		(property "Reference" "R24"
			(at 0 0 180)
			(layer "F.SilkS")
			(hide yes)
			(effects
				(font
					(size 1.27 1.27)
				)
			)
		)
		(property "Value" "0R5J-5-GP"
			(at 0 -8.9535 180)
			(unlocked yes)
			(layer "F.Fab")
			(hide yes)
			(effects
				(font
					(size 1.27 1.016)
					(thickness 0.1524)
				)
			)
		)
		(property "Device Type" "R805H24"
			(at 0 -10.6299 180)
			(unlocked yes)
			(layer "F.Fab")
			(hide yes)
			(effects
				(font
					(size 1.27 1.016)
					(thickness 0.1524)
				)
			)
		)
		(duplicate_pad_numbers_are_jumpers no)
		(fp_line
			(start 0.889 1.7018)
			(end 0.889 -0.508)
			(stroke
				(width 0.1524)
				(type default)
			)
			(layer "F.SilkS")
		)
		(fp_line
			(start 0.889 -1.7018)
			(end 0.889 -0.381)
			(stroke
				(width 0.1524)
				(type default)
			)
			(layer "F.SilkS")
		)
		(fp_line
			(start 0.889 -1.7018)
			(end -0.889 -1.7018)
			(stroke
				(width 0.1524)
				(type default)
			)
			(layer "F.SilkS")
		)
		(fp_line
			(start -0.889 1.7018)
			(end 0.889 1.7018)
			(stroke
				(width 0.1524)
				(type default)
			)
			(layer "F.SilkS")
		)
		(fp_line
			(start -0.889 0.0762)
			(end -0.889 1.7018)
			(stroke
				(width 0.1524)
				(type default)
			)
			(layer "F.SilkS")
		)
		(fp_line
			(start -0.889 -1.7018)
			(end -0.889 0.2794)
			(stroke
				(width 0.1524)
				(type default)
			)
			(layer "F.SilkS")
		)
		(fp_poly
			(pts
				(xy 0.9652 -1.778) (xy 0.9652 1.778) (xy -0.9652 1.778) (xy -0.9652 -1.778)
			)
			(stroke
				(width 0)
				(type default)
			)
			(fill no)
			(layer "F.CrtYd")
		)
		(fp_rect
			(start -0.9652 1.778)
			(end 0.9652 -1.778)
			(stroke
				(width 0)
				(type default)
			)
			(fill no)
			(layer "F.Fab")
		)
		(pad "1" smd rect
			(at 0 -0.9652 180)
			(size 1.397 1.143)
			(layers "F.Cu" "F.Mask" "F.Paste")
			(net "P1V5_E")
		)
		(pad "2" smd rect
			(at 0 0.9652 180)
			(size 1.397 1.143)
			(layers "F.Cu" "F.Mask" "F.Paste")
			(net "P1V5_E_OUT")
		)
	)
	(footprint ""
		(layer "F.Cu")
		(at 181.965092 -116.771166 90)
		(property "Reference" "C109"
			(at 0 0 90)
			(layer "F.SilkS")
			(hide yes)
			(effects
				(font
					(size 1.27 1.27)
				)
			)
		)
		(property "Value" "SC10U6D3V5KX-4GP"
			(at -0.0762 -6.1214 90)
			(unlocked yes)
			(layer "F.Fab")
			(hide yes)
			(effects
				(font
					(size 1.016 1.016)
					(thickness 0.1524)
				)
			)
		)
		(property "Device Type" "C805H58"
			(at -0.0762 -8.1534 90)
			(unlocked yes)
			(layer "F.Fab")
			(hide yes)
			(effects
				(font
					(size 1.016 1.016)
					(thickness 0.1524)
				)
			)
		)
		(duplicate_pad_numbers_are_jumpers no)
		(fp_line
			(start 0.635 0)
			(end -0.635 0)
			(stroke
				(width 0.508)
				(type default)
			)
			(layer "F.SilkS")
		)
		(fp_rect
			(start -0.9652 1.778)
			(end 0.9652 -1.778)
			(stroke
				(width 0)
				(type default)
			)
			(fill no)
			(layer "F.CrtYd")
		)
		(fp_poly
			(pts
				(xy -0.9652 -1.778) (xy 0.9652 -1.778) (xy 0.9652 1.778) (xy -0.9652 1.778)
			)
			(stroke
				(width 0)
				(type default)
			)
			(fill no)
			(layer "F.Fab")
		)
		(pad "1" smd rect
			(at 0 -0.9652 90)
			(size 1.397 1.143)
			(layers "F.Cu" "F.Mask" "F.Paste")
			(net "P1V8_E_OUT")
		)
		(pad "2" smd rect
			(at 0 0.9652 90)
			(size 1.397 1.143)
			(layers "F.Cu" "F.Mask" "F.Paste")
			(net "GND")
		)
	)
	(footprint ""
		(layer "F.Cu")
		(at 175.6156 -99.7966)
		(property "Reference" "C662"
			(at 0 0 0)
			(layer "F.SilkS")
			(hide yes)
			(effects
				(font
					(size 1.27 1.27)
				)
			)
		)
		(property "Value" "SCD01U25V2KX-3GP"
			(at 1.1811 -2.7051 0)
			(unlocked yes)
			(layer "F.Fab")
			(hide yes)
			(effects
				(font
					(size 1.016 1.016)
					(thickness 0.1524)
				)
			)
		)
		(property "Device Type" "C402H22"
			(at 1.1811 -4.2291 0)
			(unlocked yes)
			(layer "F.Fab")
			(hide yes)
			(effects
				(font
					(size 1.016 1.016)
					(thickness 0.1524)
				)
			)
		)
		(duplicate_pad_numbers_are_jumpers no)
		(fp_rect
			(start -0.4318 0.9525)
			(end 0.4318 -0.9525)
			(stroke
				(width 0)
				(type default)
			)
			(fill no)
			(layer "F.CrtYd")
		)
		(fp_rect
			(start -0.4318 0.9525)
			(end 0.4318 -0.9525)
			(stroke
				(width 0)
				(type default)
			)
			(fill no)
			(layer "F.Fab")
		)
		(pad "1" smd custom
			(at 0 -0.4445)
			(size 0.1524 0.1524)
			(layers "F.Cu" "F.Mask" "F.Paste")
			(net "VT235_VDES_RCC")
			(options
				(clearance outline)
				(anchor circle)
			)
			(primitives
				(gr_poly
					(pts
						(arc
							(start 0.3048 -0.2032)
							(mid 0.275042 -0.275042)
							(end 0.2032 -0.3048)
						)
						(arc
							(start -0.2032 -0.3048)
							(mid -0.275042 -0.275042)
							(end -0.3048 -0.2032)
						)
						(arc
							(start -0.3048 0.2032)
							(mid -0.275042 0.275042)
							(end -0.2032 0.3048)
						)
						(arc
							(start 0.2032 0.3048)
							(mid 0.275042 0.275042)
							(end 0.3048 0.2032)
						)
					)
					(width 0)
					(fill yes)
				)
			)
		)
		(pad "2" smd custom
			(at 0 0.4445)
			(size 0.1524 0.1524)
			(layers "F.Cu" "F.Mask" "F.Paste")
			(net "VT235_VDES")
			(options
				(clearance outline)
				(anchor circle)
			)
			(primitives
				(gr_poly
					(pts
						(arc
							(start 0.3048 -0.2032)
							(mid 0.275042 -0.275042)
							(end 0.2032 -0.3048)
						)
						(arc
							(start -0.2032 -0.3048)
							(mid -0.275042 -0.275042)
							(end -0.3048 -0.2032)
						)
						(arc
							(start -0.3048 0.2032)
							(mid -0.275042 0.275042)
							(end -0.2032 0.3048)
						)
						(arc
							(start 0.2032 0.3048)
							(mid 0.275042 0.275042)
							(end 0.3048 0.2032)
						)
					)
					(width 0)
					(fill yes)
				)
			)
		)
	)
	(footprint ""
		(layer "F.Cu")
		(at 24.69642 -30.94228)
		(property "Reference" "C739"
			(at 0 0 0)
			(layer "F.SilkS")
			(hide yes)
			(effects
				(font
					(size 1.27 1.27)
				)
			)
		)
		(property "Value" "SC2D2U16V5KX-1GP"
			(at -0.0762 -6.1214 0)
			(unlocked yes)
			(layer "F.Fab")
			(hide yes)
			(effects
				(font
					(size 1.016 1.016)
					(thickness 0.1524)
				)
			)
		)
		(property "Device Type" "C805H58"
			(at -0.0762 -8.1534 0)
			(unlocked yes)
			(layer "F.Fab")
			(hide yes)
			(effects
				(font
					(size 1.016 1.016)
					(thickness 0.1524)
				)
			)
		)
		(duplicate_pad_numbers_are_jumpers no)
		(fp_line
			(start 0.635 0)
			(end -0.635 0)
			(stroke
				(width 0.508)
				(type default)
			)
			(layer "F.SilkS")
		)
		(fp_rect
			(start -0.9652 1.778)
			(end 0.9652 -1.778)
			(stroke
				(width 0)
				(type default)
			)
			(fill no)
			(layer "F.CrtYd")
		)
		(fp_poly
			(pts
				(xy -0.9652 -1.778) (xy 0.9652 -1.778) (xy 0.9652 1.778) (xy -0.9652 1.778)
			)
			(stroke
				(width 0)
				(type default)
			)
			(fill no)
			(layer "F.Fab")
		)
		(pad "1" smd rect
			(at 0 -0.9652)
			(size 1.397 1.143)
			(layers "F.Cu" "F.Mask" "F.Paste")
			(net "P12V_MAIN")
		)
		(pad "2" smd rect
			(at 0 0.9652)
			(size 1.397 1.143)
			(layers "F.Cu" "F.Mask" "F.Paste")
			(net "GND")
		)
	)
	(footprint ""
		(layer "F.Cu")
		(at 107.024678 -86.665054)
		(property "Reference" "TP39"
			(at 0 0 0)
			(layer "F.SilkS")
			(hide yes)
			(effects
				(font
					(size 1.27 1.27)
				)
			)
		)
		(property "Value" "TPAD28-2-GP"
			(at -0.0127 -1.6637 0)
			(unlocked yes)
			(layer "F.Fab")
			(hide yes)
			(effects
				(font
					(size 1.016 1.016)
					(thickness 0.1524)
				)
			)
		)
		(property "Device Type" "TPAD28"
			(at -0.0127 -3.1877 0)
			(unlocked yes)
			(layer "F.Fab")
			(hide yes)
			(effects
				(font
					(size 1.016 1.016)
					(thickness 0.1524)
				)
			)
		)
		(duplicate_pad_numbers_are_jumpers no)
		(fp_poly
			(pts
				(arc
					(start 0.3556 0)
					(mid -0.3556 0)
					(end 0.3556 0)
				)
			)
			(stroke
				(width 0)
				(type default)
			)
			(fill no)
			(layer "F.CrtYd")
		)
		(fp_poly
			(pts
				(arc
					(start 0.6096 0)
					(mid -0.6096 0)
					(end 0.6096 0)
				)
			)
			(stroke
				(width 0)
				(type default)
			)
			(fill no)
			(layer "F.Fab")
		)
		(pad "1" smd circle
			(at 0 0)
			(size 0.7112 0.7112)
			(layers "F.Cu" "F.Mask" "F.Paste")
			(net "JTAG_EXP_TDO")
		)
	)
	(footprint ""
		(layer "F.Cu")
		(at 12.8778 -94.801182 180)
		(property "Reference" "R430"
			(at 0 0 180)
			(layer "F.SilkS")
			(hide yes)
			(effects
				(font
					(size 1.27 1.27)
				)
			)
		)
		(property "Value" "200KR2F-L-GP"
			(at 0.064008 -3.993896 180)
			(unlocked yes)
			(layer "F.Fab")
			(hide yes)
			(effects
				(font
					(size 1.016 1.016)
					(thickness 0.1524)
				)
			)
		)
		(property "Device Type" "R402H16"
			(at 0.064008 -5.517896 180)
			(unlocked yes)
			(layer "F.Fab")
			(hide yes)
			(effects
				(font
					(size 1.016 1.016)
					(thickness 0.1524)
				)
			)
		)
		(duplicate_pad_numbers_are_jumpers no)
		(fp_line
			(start 0.508 -0.9398)
			(end -0.508 -0.9398)
			(stroke
				(width 0.1524)
				(type default)
			)
			(layer "F.SilkS")
		)
		(fp_line
			(start -0.508 -0.9398)
			(end -0.508 0.9398)
			(stroke
				(width 0.1524)
				(type default)
			)
			(layer "F.SilkS")
		)
		(fp_rect
			(start -0.508 0.9398)
			(end 0.508 -0.9398)
			(stroke
				(width 0)
				(type default)
			)
			(fill no)
			(layer "F.CrtYd")
		)
		(fp_rect
			(start -0.508 0.9398)
			(end 0.508 -0.9398)
			(stroke
				(width 0)
				(type default)
			)
			(fill no)
			(layer "F.Fab")
		)
		(pad "1" smd custom
			(at 0 -0.4445 180)
			(size 0.1397 0.1397)
			(layers "F.Cu" "F.Mask" "F.Paste")
			(net "VREF3")
			(options
				(clearance outline)
				(anchor circle)
			)
			(primitives
				(gr_poly
					(pts
						(arc
							(start -0.1778 -0.2794)
							(mid -0.249642 -0.249642)
							(end -0.2794 -0.1778)
						)
						(arc
							(start -0.2794 0.1778)
							(mid -0.249642 0.249642)
							(end -0.1778 0.2794)
						)
						(arc
							(start 0.1778 0.2794)
							(mid 0.249642 0.249642)
							(end 0.2794 0.1778)
						)
						(arc
							(start 0.2794 -0.1778)
							(mid 0.249642 -0.249642)
							(end 0.1778 -0.2794)
						)
					)
					(width 0)
					(fill yes)
				)
			)
		)
		(pad "2" smd custom
			(at 0 0.4445 180)
			(size 0.1397 0.1397)
			(layers "F.Cu" "F.Mask" "F.Paste")
			(net "P3V3")
			(options
				(clearance outline)
				(anchor circle)
			)
			(primitives
				(gr_poly
					(pts
						(arc
							(start -0.1778 -0.2794)
							(mid -0.249642 -0.249642)
							(end -0.2794 -0.1778)
						)
						(arc
							(start -0.2794 0.1778)
							(mid -0.249642 0.249642)
							(end -0.1778 0.2794)
						)
						(arc
							(start 0.1778 0.2794)
							(mid 0.249642 0.249642)
							(end 0.2794 0.1778)
						)
						(arc
							(start 0.2794 -0.1778)
							(mid 0.249642 -0.249642)
							(end 0.1778 -0.2794)
						)
					)
					(width 0)
					(fill yes)
				)
			)
		)
	)
	(footprint ""
		(layer "F.Cu")
		(at 185.600848 -58.472578)
		(property "Reference" "R395"
			(at 0 0 0)
			(layer "F.SilkS")
			(hide yes)
			(effects
				(font
					(size 1.27 1.27)
				)
			)
		)
		(property "Value" "10KR2F-2-GP"
			(at 0.064008 -3.993896 0)
			(unlocked yes)
			(layer "F.Fab")
			(hide yes)
			(effects
				(font
					(size 1.016 1.016)
					(thickness 0.1524)
				)
			)
		)
		(property "Device Type" "R402H16"
			(at 0.064008 -5.517896 0)
			(unlocked yes)
			(layer "F.Fab")
			(hide yes)
			(effects
				(font
					(size 1.016 1.016)
					(thickness 0.1524)
				)
			)
		)
		(duplicate_pad_numbers_are_jumpers no)
		(fp_line
			(start -0.508 -0.9398)
			(end -0.508 0.9398)
			(stroke
				(width 0.1524)
				(type default)
			)
			(layer "F.SilkS")
		)
		(fp_line
			(start 0.508 -0.9398)
			(end -0.508 -0.9398)
			(stroke
				(width 0.1524)
				(type default)
			)
			(layer "F.SilkS")
		)
		(fp_rect
			(start -0.508 0.9398)
			(end 0.508 -0.9398)
			(stroke
				(width 0)
				(type default)
			)
			(fill no)
			(layer "F.CrtYd")
		)
		(fp_rect
			(start -0.508 0.9398)
			(end 0.508 -0.9398)
			(stroke
				(width 0)
				(type default)
			)
			(fill no)
			(layer "F.Fab")
		)
		(pad "1" smd custom
			(at 0 -0.4445)
			(size 0.1397 0.1397)
			(layers "F.Cu" "F.Mask" "F.Paste")
			(net "P1V8_C")
			(options
				(clearance outline)
				(anchor circle)
			)
			(primitives
				(gr_poly
					(pts
						(arc
							(start -0.1778 -0.2794)
							(mid -0.249642 -0.249642)
							(end -0.2794 -0.1778)
						)
						(arc
							(start -0.2794 0.1778)
							(mid -0.249642 0.249642)
							(end -0.1778 0.2794)
						)
						(arc
							(start 0.1778 0.2794)
							(mid 0.249642 0.249642)
							(end 0.2794 0.1778)
						)
						(arc
							(start 0.2794 -0.1778)
							(mid 0.249642 -0.249642)
							(end 0.1778 -0.2794)
						)
					)
					(width 0)
					(fill yes)
				)
			)
		)
		(pad "2" smd custom
			(at 0 0.4445)
			(size 0.1397 0.1397)
			(layers "F.Cu" "F.Mask" "F.Paste")
			(net "XM_ADDR_1")
			(options
				(clearance outline)
				(anchor circle)
			)
			(primitives
				(gr_poly
					(pts
						(arc
							(start -0.1778 -0.2794)
							(mid -0.249642 -0.249642)
							(end -0.2794 -0.1778)
						)
						(arc
							(start -0.2794 0.1778)
							(mid -0.249642 0.249642)
							(end -0.1778 0.2794)
						)
						(arc
							(start 0.1778 0.2794)
							(mid 0.249642 0.249642)
							(end 0.2794 0.1778)
						)
						(arc
							(start 0.2794 -0.1778)
							(mid 0.249642 -0.249642)
							(end 0.1778 -0.2794)
						)
					)
					(width 0)
					(fill yes)
				)
			)
		)
	)
	(footprint ""
		(layer "F.Cu")
		(at 107.02925 -88.024208)
		(property "Reference" "TP40"
			(at 0 0 0)
			(layer "F.SilkS")
			(hide yes)
			(effects
				(font
					(size 1.27 1.27)
				)
			)
		)
		(property "Value" "TPAD28-2-GP"
			(at -0.0127 -1.6637 0)
			(unlocked yes)
			(layer "F.Fab")
			(hide yes)
			(effects
				(font
					(size 1.016 1.016)
					(thickness 0.1524)
				)
			)
		)
		(property "Device Type" "TPAD28"
			(at -0.0127 -3.1877 0)
			(unlocked yes)
			(layer "F.Fab")
			(hide yes)
			(effects
				(font
					(size 1.016 1.016)
					(thickness 0.1524)
				)
			)
		)
		(duplicate_pad_numbers_are_jumpers no)
		(fp_poly
			(pts
				(arc
					(start 0.3556 0)
					(mid -0.3556 0)
					(end 0.3556 0)
				)
			)
			(stroke
				(width 0)
				(type default)
			)
			(fill no)
			(layer "F.CrtYd")
		)
		(fp_poly
			(pts
				(arc
					(start 0.6096 0)
					(mid -0.6096 0)
					(end 0.6096 0)
				)
			)
			(stroke
				(width 0)
				(type default)
			)
			(fill no)
			(layer "F.Fab")
		)
		(pad "1" smd circle
			(at 0 0)
			(size 0.7112 0.7112)
			(layers "F.Cu" "F.Mask" "F.Paste")
			(net "JTAG_EXP_TMS")
		)
	)
	(footprint ""
		(layer "F.Cu")
		(at 68.453 -106.299 180)
		(property "Reference" "R88"
			(at 0 0 180)
			(layer "F.SilkS")
			(hide yes)
			(effects
				(font
					(size 1.27 1.27)
				)
			)
		)
		(property "Value" "0R2J-2-GP"
			(at 0.064008 -3.993896 180)
			(unlocked yes)
			(layer "F.Fab")
			(hide yes)
			(effects
				(font
					(size 1.016 1.016)
					(thickness 0.1524)
				)
			)
		)
		(property "Device Type" "R402H16"
			(at 0.064008 -5.517896 180)
			(unlocked yes)
			(layer "F.Fab")
			(hide yes)
			(effects
				(font
					(size 1.016 1.016)
					(thickness 0.1524)
				)
			)
		)
		(duplicate_pad_numbers_are_jumpers no)
		(fp_line
			(start 0.508 -0.9398)
			(end -0.508 -0.9398)
			(stroke
				(width 0.1524)
				(type default)
			)
			(layer "F.SilkS")
		)
		(fp_line
			(start -0.508 -0.9398)
			(end -0.508 0.9398)
			(stroke
				(width 0.1524)
				(type default)
			)
			(layer "F.SilkS")
		)
		(fp_rect
			(start -0.508 0.9398)
			(end 0.508 -0.9398)
			(stroke
				(width 0)
				(type default)
			)
			(fill no)
			(layer "F.CrtYd")
		)
		(fp_rect
			(start -0.508 0.9398)
			(end 0.508 -0.9398)
			(stroke
				(width 0)
				(type default)
			)
			(fill no)
			(layer "F.Fab")
		)
		(pad "1" smd custom
			(at 0 -0.4445 180)
			(size 0.1397 0.1397)
			(layers "F.Cu" "F.Mask" "F.Paste")
			(net "P3V3_EN")
			(options
				(clearance outline)
				(anchor circle)
			)
			(primitives
				(gr_poly
					(pts
						(arc
							(start -0.1778 -0.2794)
							(mid -0.249642 -0.249642)
							(end -0.2794 -0.1778)
						)
						(arc
							(start -0.2794 0.1778)
							(mid -0.249642 0.249642)
							(end -0.1778 0.2794)
						)
						(arc
							(start 0.1778 0.2794)
							(mid 0.249642 0.249642)
							(end 0.2794 0.1778)
						)
						(arc
							(start 0.2794 -0.1778)
							(mid 0.249642 -0.249642)
							(end 0.1778 -0.2794)
						)
					)
					(width 0)
					(fill yes)
				)
			)
		)
		(pad "2" smd custom
			(at 0 0.4445 180)
			(size 0.1397 0.1397)
			(layers "F.Cu" "F.Mask" "F.Paste")
			(net "P12V_SCC_PGOOD")
			(options
				(clearance outline)
				(anchor circle)
			)
			(primitives
				(gr_poly
					(pts
						(arc
							(start -0.1778 -0.2794)
							(mid -0.249642 -0.249642)
							(end -0.2794 -0.1778)
						)
						(arc
							(start -0.2794 0.1778)
							(mid -0.249642 0.249642)
							(end -0.1778 0.2794)
						)
						(arc
							(start 0.1778 0.2794)
							(mid 0.249642 0.249642)
							(end 0.2794 0.1778)
						)
						(arc
							(start 0.2794 -0.1778)
							(mid 0.249642 -0.249642)
							(end 0.1778 -0.2794)
						)
					)
					(width 0)
					(fill yes)
				)
			)
		)
	)
	(footprint ""
		(layer "F.Cu")
		(at 168.656 -14.097 180)
		(property "Reference" "R211"
			(at 0 0 180)
			(layer "F.SilkS")
			(hide yes)
			(effects
				(font
					(size 1.27 1.27)
				)
			)
		)
		(property "Value" "0R2J-2-GP"
			(at 0.064008 -3.993896 180)
			(unlocked yes)
			(layer "F.Fab")
			(hide yes)
			(effects
				(font
					(size 1.016 1.016)
					(thickness 0.1524)
				)
			)
		)
		(property "Device Type" "R402H16"
			(at 0.064008 -5.517896 180)
			(unlocked yes)
			(layer "F.Fab")
			(hide yes)
			(effects
				(font
					(size 1.016 1.016)
					(thickness 0.1524)
				)
			)
		)
		(duplicate_pad_numbers_are_jumpers no)
		(fp_line
			(start 0.508 -0.9398)
			(end -0.508 -0.9398)
			(stroke
				(width 0.1524)
				(type default)
			)
			(layer "F.SilkS")
		)
		(fp_line
			(start -0.508 -0.9398)
			(end -0.508 0.9398)
			(stroke
				(width 0.1524)
				(type default)
			)
			(layer "F.SilkS")
		)
		(fp_rect
			(start -0.508 0.9398)
			(end 0.508 -0.9398)
			(stroke
				(width 0)
				(type default)
			)
			(fill no)
			(layer "F.CrtYd")
		)
		(fp_rect
			(start -0.508 0.9398)
			(end 0.508 -0.9398)
			(stroke
				(width 0)
				(type default)
			)
			(fill no)
			(layer "F.Fab")
		)
		(pad "1" smd custom
			(at 0 -0.4445 180)
			(size 0.1397 0.1397)
			(layers "F.Cu" "F.Mask" "F.Paste")
			(net "P0V9_PG")
			(options
				(clearance outline)
				(anchor circle)
			)
			(primitives
				(gr_poly
					(pts
						(arc
							(start -0.1778 -0.2794)
							(mid -0.249642 -0.249642)
							(end -0.2794 -0.1778)
						)
						(arc
							(start -0.2794 0.1778)
							(mid -0.249642 0.249642)
							(end -0.1778 0.2794)
						)
						(arc
							(start 0.1778 0.2794)
							(mid 0.249642 0.249642)
							(end 0.2794 0.1778)
						)
						(arc
							(start 0.2794 -0.1778)
							(mid 0.249642 -0.249642)
							(end 0.1778 -0.2794)
						)
					)
					(width 0)
					(fill yes)
				)
			)
		)
		(pad "2" smd custom
			(at 0 0.4445 180)
			(size 0.1397 0.1397)
			(layers "F.Cu" "F.Mask" "F.Paste")
			(net "P0V9_PG_Q")
			(options
				(clearance outline)
				(anchor circle)
			)
			(primitives
				(gr_poly
					(pts
						(arc
							(start -0.1778 -0.2794)
							(mid -0.249642 -0.249642)
							(end -0.2794 -0.1778)
						)
						(arc
							(start -0.2794 0.1778)
							(mid -0.249642 0.249642)
							(end -0.1778 0.2794)
						)
						(arc
							(start 0.1778 0.2794)
							(mid 0.249642 0.249642)
							(end 0.2794 0.1778)
						)
						(arc
							(start 0.2794 -0.1778)
							(mid 0.249642 -0.249642)
							(end 0.1778 -0.2794)
						)
					)
					(width 0)
					(fill yes)
				)
			)
		)
	)
	(footprint ""
		(layer "F.Cu")
		(at 8.23087 -47.248318)
		(property "Reference" "R435"
			(at 0 0 0)
			(layer "F.SilkS")
			(hide yes)
			(effects
				(font
					(size 1.27 1.27)
				)
			)
		)
		(property "Value" "100R2D-GP"
			(at 0.064008 -3.993896 0)
			(unlocked yes)
			(layer "F.Fab")
			(hide yes)
			(effects
				(font
					(size 1.016 1.016)
					(thickness 0.1524)
				)
			)
		)
		(property "Device Type" "R402H14"
			(at 0.064008 -5.517896 0)
			(unlocked yes)
			(layer "F.Fab")
			(hide yes)
			(effects
				(font
					(size 1.016 1.016)
					(thickness 0.1524)
				)
			)
		)
		(duplicate_pad_numbers_are_jumpers no)
		(fp_line
			(start -0.508 -0.9398)
			(end -0.508 0.9398)
			(stroke
				(width 0.1524)
				(type default)
			)
			(layer "F.SilkS")
		)
		(fp_line
			(start 0.508 -0.9398)
			(end -0.508 -0.9398)
			(stroke
				(width 0.1524)
				(type default)
			)
			(layer "F.SilkS")
		)
		(fp_rect
			(start -0.508 0.9398)
			(end 0.508 -0.9398)
			(stroke
				(width 0)
				(type default)
			)
			(fill no)
			(layer "F.CrtYd")
		)
		(fp_rect
			(start -0.508 0.9398)
			(end 0.508 -0.9398)
			(stroke
				(width 0)
				(type default)
			)
			(fill no)
			(layer "F.Fab")
		)
		(pad "1" smd custom
			(at 0 -0.4445)
			(size 0.1397 0.1397)
			(layers "F.Cu" "F.Mask" "F.Paste")
			(net "GND")
			(options
				(clearance outline)
				(anchor circle)
			)
			(primitives
				(gr_poly
					(pts
						(arc
							(start -0.1778 -0.2794)
							(mid -0.249642 -0.249642)
							(end -0.2794 -0.1778)
						)
						(arc
							(start -0.2794 0.1778)
							(mid -0.249642 0.249642)
							(end -0.1778 0.2794)
						)
						(arc
							(start 0.1778 0.2794)
							(mid 0.249642 0.249642)
							(end 0.2794 0.1778)
						)
						(arc
							(start 0.2794 -0.1778)
							(mid 0.249642 -0.249642)
							(end 0.1778 -0.2794)
						)
					)
					(width 0)
					(fill yes)
				)
			)
		)
		(pad "2" smd custom
			(at 0 0.4445)
			(size 0.1397 0.1397)
			(layers "F.Cu" "F.Mask" "F.Paste")
			(net "MB0_TEMP_E")
			(options
				(clearance outline)
				(anchor circle)
			)
			(primitives
				(gr_poly
					(pts
						(arc
							(start -0.1778 -0.2794)
							(mid -0.249642 -0.249642)
							(end -0.2794 -0.1778)
						)
						(arc
							(start -0.2794 0.1778)
							(mid -0.249642 0.249642)
							(end -0.1778 0.2794)
						)
						(arc
							(start 0.1778 0.2794)
							(mid 0.249642 0.249642)
							(end 0.2794 0.1778)
						)
						(arc
							(start 0.2794 -0.1778)
							(mid 0.249642 -0.249642)
							(end 0.1778 -0.2794)
						)
					)
					(width 0)
					(fill yes)
				)
			)
		)
	)
	(footprint ""
		(layer "F.Cu")
		(at 189.73038 -78.49108)
		(property "Reference" "R364"
			(at 0 0 0)
			(layer "F.SilkS")
			(hide yes)
			(effects
				(font
					(size 1.27 1.27)
				)
			)
		)
		(property "Value" "4K7R2F-GP"
			(at 0.064008 -3.993896 0)
			(unlocked yes)
			(layer "F.Fab")
			(hide yes)
			(effects
				(font
					(size 1.016 1.016)
					(thickness 0.1524)
				)
			)
		)
		(property "Device Type" "R402H16"
			(at 0.064008 -5.517896 0)
			(unlocked yes)
			(layer "F.Fab")
			(hide yes)
			(effects
				(font
					(size 1.016 1.016)
					(thickness 0.1524)
				)
			)
		)
		(duplicate_pad_numbers_are_jumpers no)
		(fp_line
			(start -0.508 -0.9398)
			(end -0.508 0.9398)
			(stroke
				(width 0.1524)
				(type default)
			)
			(layer "F.SilkS")
		)
		(fp_line
			(start 0.508 -0.9398)
			(end -0.508 -0.9398)
			(stroke
				(width 0.1524)
				(type default)
			)
			(layer "F.SilkS")
		)
		(fp_rect
			(start -0.508 0.9398)
			(end 0.508 -0.9398)
			(stroke
				(width 0)
				(type default)
			)
			(fill no)
			(layer "F.CrtYd")
		)
		(fp_rect
			(start -0.508 0.9398)
			(end 0.508 -0.9398)
			(stroke
				(width 0)
				(type default)
			)
			(fill no)
			(layer "F.Fab")
		)
		(pad "1" smd custom
			(at 0 -0.4445)
			(size 0.1397 0.1397)
			(layers "F.Cu" "F.Mask" "F.Paste")
			(net "P3V3")
			(options
				(clearance outline)
				(anchor circle)
			)
			(primitives
				(gr_poly
					(pts
						(arc
							(start -0.1778 -0.2794)
							(mid -0.249642 -0.249642)
							(end -0.2794 -0.1778)
						)
						(arc
							(start -0.2794 0.1778)
							(mid -0.249642 0.249642)
							(end -0.1778 0.2794)
						)
						(arc
							(start 0.1778 0.2794)
							(mid 0.249642 0.249642)
							(end 0.2794 0.1778)
						)
						(arc
							(start 0.2794 -0.1778)
							(mid 0.249642 -0.249642)
							(end 0.1778 -0.2794)
						)
					)
					(width 0)
					(fill yes)
				)
			)
		)
		(pad "2" smd custom
			(at 0 0.4445)
			(size 0.1397 0.1397)
			(layers "F.Cu" "F.Mask" "F.Paste")
			(net "TEMP2_A1")
			(options
				(clearance outline)
				(anchor circle)
			)
			(primitives
				(gr_poly
					(pts
						(arc
							(start -0.1778 -0.2794)
							(mid -0.249642 -0.249642)
							(end -0.2794 -0.1778)
						)
						(arc
							(start -0.2794 0.1778)
							(mid -0.249642 0.249642)
							(end -0.1778 0.2794)
						)
						(arc
							(start 0.1778 0.2794)
							(mid 0.249642 0.249642)
							(end 0.2794 0.1778)
						)
						(arc
							(start 0.2794 -0.1778)
							(mid 0.249642 -0.249642)
							(end 0.1778 -0.2794)
						)
					)
					(width 0)
					(fill yes)
				)
			)
		)
	)
	(footprint ""
		(layer "F.Cu")
		(at 75.72629 -26.460958 -90)
		(property "Reference" "R348"
			(at 0 0 270)
			(layer "F.SilkS")
			(hide yes)
			(effects
				(font
					(size 1.27 1.27)
				)
			)
		)
		(property "Value" "0R2J-2-GP"
			(at 0.064008 -3.993896 270)
			(unlocked yes)
			(layer "F.Fab")
			(hide yes)
			(effects
				(font
					(size 1.016 1.016)
					(thickness 0.1524)
				)
			)
		)
		(property "Device Type" "R402H16"
			(at 0.064008 -5.517896 270)
			(unlocked yes)
			(layer "F.Fab")
			(hide yes)
			(effects
				(font
					(size 1.016 1.016)
					(thickness 0.1524)
				)
			)
		)
		(duplicate_pad_numbers_are_jumpers no)
		(fp_line
			(start -0.508 -0.9398)
			(end -0.508 0.9398)
			(stroke
				(width 0.1524)
				(type default)
			)
			(layer "F.SilkS")
		)
		(fp_line
			(start 0.508 -0.9398)
			(end -0.508 -0.9398)
			(stroke
				(width 0.1524)
				(type default)
			)
			(layer "F.SilkS")
		)
		(fp_rect
			(start -0.508 0.9398)
			(end 0.508 -0.9398)
			(stroke
				(width 0)
				(type default)
			)
			(fill no)
			(layer "F.CrtYd")
		)
		(fp_rect
			(start -0.508 0.9398)
			(end 0.508 -0.9398)
			(stroke
				(width 0)
				(type default)
			)
			(fill no)
			(layer "F.Fab")
		)
		(pad "1" smd custom
			(at 0 -0.4445 270)
			(size 0.1397 0.1397)
			(layers "F.Cu" "F.Mask" "F.Paste")
			(net "SCC_LOC_INS_N")
			(options
				(clearance outline)
				(anchor circle)
			)
			(primitives
				(gr_poly
					(pts
						(arc
							(start -0.1778 -0.2794)
							(mid -0.249642 -0.249642)
							(end -0.2794 -0.1778)
						)
						(arc
							(start -0.2794 0.1778)
							(mid -0.249642 0.249642)
							(end -0.1778 0.2794)
						)
						(arc
							(start 0.1778 0.2794)
							(mid 0.249642 0.249642)
							(end 0.2794 0.1778)
						)
						(arc
							(start 0.2794 -0.1778)
							(mid 0.249642 -0.249642)
							(end 0.1778 -0.2794)
						)
					)
					(width 0)
					(fill yes)
				)
			)
		)
		(pad "2" smd custom
			(at 0 0.4445 270)
			(size 0.1397 0.1397)
			(layers "F.Cu" "F.Mask" "F.Paste")
			(net "GND")
			(options
				(clearance outline)
				(anchor circle)
			)
			(primitives
				(gr_poly
					(pts
						(arc
							(start -0.1778 -0.2794)
							(mid -0.249642 -0.249642)
							(end -0.2794 -0.1778)
						)
						(arc
							(start -0.2794 0.1778)
							(mid -0.249642 0.249642)
							(end -0.1778 0.2794)
						)
						(arc
							(start 0.1778 0.2794)
							(mid 0.249642 0.249642)
							(end 0.2794 0.1778)
						)
						(arc
							(start 0.2794 -0.1778)
							(mid 0.249642 -0.249642)
							(end 0.1778 -0.2794)
						)
					)
					(width 0)
					(fill yes)
				)
			)
		)
	)
	(footprint ""
		(layer "F.Cu")
		(at 132.994908 -87.827866)
		(property "Reference" "TP18"
			(at 0 0 0)
			(layer "F.SilkS")
			(hide yes)
			(effects
				(font
					(size 1.27 1.27)
				)
			)
		)
		(property "Value" "TPAD28-2-GP"
			(at -0.0127 -1.6637 0)
			(unlocked yes)
			(layer "F.Fab")
			(hide yes)
			(effects
				(font
					(size 1.016 1.016)
					(thickness 0.1524)
				)
			)
		)
		(property "Device Type" "TPAD28"
			(at -0.0127 -3.1877 0)
			(unlocked yes)
			(layer "F.Fab")
			(hide yes)
			(effects
				(font
					(size 1.016 1.016)
					(thickness 0.1524)
				)
			)
		)
		(duplicate_pad_numbers_are_jumpers no)
		(fp_poly
			(pts
				(arc
					(start 0.3556 0)
					(mid -0.3556 0)
					(end 0.3556 0)
				)
			)
			(stroke
				(width 0)
				(type default)
			)
			(fill no)
			(layer "F.CrtYd")
		)
		(fp_poly
			(pts
				(arc
					(start 0.6096 0)
					(mid -0.6096 0)
					(end 0.6096 0)
				)
			)
			(stroke
				(width 0)
				(type default)
			)
			(fill no)
			(layer "F.Fab")
		)
		(pad "1" smd circle
			(at 0 0)
			(size 0.7112 0.7112)
			(layers "F.Cu" "F.Mask" "F.Paste")
			(net "EXP_I2C_SCL10")
		)
	)
	(footprint ""
		(layer "F.Cu")
		(at 150.5458 -121.6914 90)
		(property "Reference" "R373"
			(at 0 0 90)
			(layer "F.SilkS")
			(hide yes)
			(effects
				(font
					(size 1.27 1.27)
				)
			)
		)
		(property "Value" "10KR2F-2-GP"
			(at 0.064008 -3.993896 90)
			(unlocked yes)
			(layer "F.Fab")
			(hide yes)
			(effects
				(font
					(size 1.016 1.016)
					(thickness 0.1524)
				)
			)
		)
		(property "Device Type" "R402H16"
			(at 0.064008 -5.517896 90)
			(unlocked yes)
			(layer "F.Fab")
			(hide yes)
			(effects
				(font
					(size 1.016 1.016)
					(thickness 0.1524)
				)
			)
		)
		(duplicate_pad_numbers_are_jumpers no)
		(fp_line
			(start 0.508 -0.9398)
			(end -0.508 -0.9398)
			(stroke
				(width 0.1524)
				(type default)
			)
			(layer "F.SilkS")
		)
		(fp_line
			(start -0.508 -0.9398)
			(end -0.508 0.9398)
			(stroke
				(width 0.1524)
				(type default)
			)
			(layer "F.SilkS")
		)
		(fp_rect
			(start -0.508 0.9398)
			(end 0.508 -0.9398)
			(stroke
				(width 0)
				(type default)
			)
			(fill no)
			(layer "F.CrtYd")
		)
		(fp_rect
			(start -0.508 0.9398)
			(end 0.508 -0.9398)
			(stroke
				(width 0)
				(type default)
			)
			(fill no)
			(layer "F.Fab")
		)
		(pad "1" smd custom
			(at 0 -0.4445 90)
			(size 0.1397 0.1397)
			(layers "F.Cu" "F.Mask" "F.Paste")
			(net "P1V5_E_VFB")
			(options
				(clearance outline)
				(anchor circle)
			)
			(primitives
				(gr_poly
					(pts
						(arc
							(start -0.1778 -0.2794)
							(mid -0.249642 -0.249642)
							(end -0.2794 -0.1778)
						)
						(arc
							(start -0.2794 0.1778)
							(mid -0.249642 0.249642)
							(end -0.1778 0.2794)
						)
						(arc
							(start 0.1778 0.2794)
							(mid 0.249642 0.249642)
							(end 0.2794 0.1778)
						)
						(arc
							(start 0.2794 -0.1778)
							(mid 0.249642 -0.249642)
							(end 0.1778 -0.2794)
						)
					)
					(width 0)
					(fill yes)
				)
			)
		)
		(pad "2" smd custom
			(at 0 0.4445 90)
			(size 0.1397 0.1397)
			(layers "F.Cu" "F.Mask" "F.Paste")
			(net "AGND_P1V5_E")
			(options
				(clearance outline)
				(anchor circle)
			)
			(primitives
				(gr_poly
					(pts
						(arc
							(start -0.1778 -0.2794)
							(mid -0.249642 -0.249642)
							(end -0.2794 -0.1778)
						)
						(arc
							(start -0.2794 0.1778)
							(mid -0.249642 0.249642)
							(end -0.1778 0.2794)
						)
						(arc
							(start 0.1778 0.2794)
							(mid 0.249642 0.249642)
							(end 0.2794 0.1778)
						)
						(arc
							(start 0.2794 -0.1778)
							(mid 0.249642 -0.249642)
							(end 0.1778 -0.2794)
						)
					)
					(width 0)
					(fill yes)
				)
			)
		)
	)
	(footprint ""
		(layer "F.Cu")
		(at 83.999832 -111.675672 -90)
		(property "Reference" "C742"
			(at 0 0 270)
			(layer "F.SilkS")
			(hide yes)
			(effects
				(font
					(size 1.27 1.27)
				)
			)
		)
		(property "Value" "SCD1U16V2KX-3GP"
			(at 1.1811 -2.7051 270)
			(unlocked yes)
			(layer "F.Fab")
			(hide yes)
			(effects
				(font
					(size 1.016 1.016)
					(thickness 0.1524)
				)
			)
		)
		(property "Device Type" "C402H22"
			(at 1.1811 -4.2291 270)
			(unlocked yes)
			(layer "F.Fab")
			(hide yes)
			(effects
				(font
					(size 1.016 1.016)
					(thickness 0.1524)
				)
			)
		)
		(duplicate_pad_numbers_are_jumpers no)
		(fp_rect
			(start -0.4318 0.9525)
			(end 0.4318 -0.9525)
			(stroke
				(width 0)
				(type default)
			)
			(fill no)
			(layer "F.CrtYd")
		)
		(fp_rect
			(start -0.4318 0.9525)
			(end 0.4318 -0.9525)
			(stroke
				(width 0)
				(type default)
			)
			(fill no)
			(layer "F.Fab")
		)
		(pad "1" smd custom
			(at 0 -0.4445 270)
			(size 0.1524 0.1524)
			(layers "F.Cu" "F.Mask" "F.Paste")
			(net "U48_OE")
			(options
				(clearance outline)
				(anchor circle)
			)
			(primitives
				(gr_poly
					(pts
						(arc
							(start 0.3048 -0.2032)
							(mid 0.275042 -0.275042)
							(end 0.2032 -0.3048)
						)
						(arc
							(start -0.2032 -0.3048)
							(mid -0.275042 -0.275042)
							(end -0.3048 -0.2032)
						)
						(arc
							(start -0.3048 0.2032)
							(mid -0.275042 0.275042)
							(end -0.2032 0.3048)
						)
						(arc
							(start 0.2032 0.3048)
							(mid 0.275042 0.275042)
							(end 0.3048 0.2032)
						)
					)
					(width 0)
					(fill yes)
				)
			)
		)
		(pad "2" smd custom
			(at 0 0.4445 270)
			(size 0.1524 0.1524)
			(layers "F.Cu" "F.Mask" "F.Paste")
			(net "GND")
			(options
				(clearance outline)
				(anchor circle)
			)
			(primitives
				(gr_poly
					(pts
						(arc
							(start 0.3048 -0.2032)
							(mid 0.275042 -0.275042)
							(end 0.2032 -0.3048)
						)
						(arc
							(start -0.2032 -0.3048)
							(mid -0.275042 -0.275042)
							(end -0.3048 -0.2032)
						)
						(arc
							(start -0.3048 0.2032)
							(mid -0.275042 0.275042)
							(end -0.2032 0.3048)
						)
						(arc
							(start 0.2032 0.3048)
							(mid 0.275042 0.275042)
							(end 0.3048 0.2032)
						)
					)
					(width 0)
					(fill yes)
				)
			)
		)
	)
	(footprint ""
		(layer "F.Cu")
		(at 202.30338 -76.86548 -90)
		(property "Reference" "R367"
			(at 0 0 270)
			(layer "F.SilkS")
			(hide yes)
			(effects
				(font
					(size 1.27 1.27)
				)
			)
		)
		(property "Value" "0R2J-2-GP"
			(at 0.064008 -3.993896 270)
			(unlocked yes)
			(layer "F.Fab")
			(hide yes)
			(effects
				(font
					(size 1.016 1.016)
					(thickness 0.1524)
				)
			)
		)
		(property "Device Type" "R402H16"
			(at 0.064008 -5.517896 270)
			(unlocked yes)
			(layer "F.Fab")
			(hide yes)
			(effects
				(font
					(size 1.016 1.016)
					(thickness 0.1524)
				)
			)
		)
		(duplicate_pad_numbers_are_jumpers no)
		(fp_line
			(start -0.508 -0.9398)
			(end -0.508 0.9398)
			(stroke
				(width 0.1524)
				(type default)
			)
			(layer "F.SilkS")
		)
		(fp_line
			(start 0.508 -0.9398)
			(end -0.508 -0.9398)
			(stroke
				(width 0.1524)
				(type default)
			)
			(layer "F.SilkS")
		)
		(fp_rect
			(start -0.508 0.9398)
			(end 0.508 -0.9398)
			(stroke
				(width 0)
				(type default)
			)
			(fill no)
			(layer "F.CrtYd")
		)
		(fp_rect
			(start -0.508 0.9398)
			(end 0.508 -0.9398)
			(stroke
				(width 0)
				(type default)
			)
			(fill no)
			(layer "F.Fab")
		)
		(pad "1" smd custom
			(at 0 -0.4445 270)
			(size 0.1397 0.1397)
			(layers "F.Cu" "F.Mask" "F.Paste")
			(net "I2C_SCC_SDA2")
			(options
				(clearance outline)
				(anchor circle)
			)
			(primitives
				(gr_poly
					(pts
						(arc
							(start -0.1778 -0.2794)
							(mid -0.249642 -0.249642)
							(end -0.2794 -0.1778)
						)
						(arc
							(start -0.2794 0.1778)
							(mid -0.249642 0.249642)
							(end -0.1778 0.2794)
						)
						(arc
							(start 0.1778 0.2794)
							(mid 0.249642 0.249642)
							(end 0.2794 0.1778)
						)
						(arc
							(start 0.2794 -0.1778)
							(mid 0.249642 -0.249642)
							(end 0.1778 -0.2794)
						)
					)
					(width 0)
					(fill yes)
				)
			)
		)
		(pad "2" smd custom
			(at 0 0.4445 270)
			(size 0.1397 0.1397)
			(layers "F.Cu" "F.Mask" "F.Paste")
			(net "TEMP2_SDA")
			(options
				(clearance outline)
				(anchor circle)
			)
			(primitives
				(gr_poly
					(pts
						(arc
							(start -0.1778 -0.2794)
							(mid -0.249642 -0.249642)
							(end -0.2794 -0.1778)
						)
						(arc
							(start -0.2794 0.1778)
							(mid -0.249642 0.249642)
							(end -0.1778 0.2794)
						)
						(arc
							(start 0.1778 0.2794)
							(mid 0.249642 0.249642)
							(end 0.2794 0.1778)
						)
						(arc
							(start 0.2794 -0.1778)
							(mid 0.249642 -0.249642)
							(end 0.1778 -0.2794)
						)
					)
					(width 0)
					(fill yes)
				)
			)
		)
	)
	(footprint ""
		(layer "F.Cu")
		(at 128.5748 -89.916)
		(property "Reference" "R118"
			(at 0 0 0)
			(layer "F.SilkS")
			(hide yes)
			(effects
				(font
					(size 1.27 1.27)
				)
			)
		)
		(property "Value" "4K75R2F-1-GP"
			(at 0.064008 -3.993896 0)
			(unlocked yes)
			(layer "F.Fab")
			(hide yes)
			(effects
				(font
					(size 1.016 1.016)
					(thickness 0.1524)
				)
			)
		)
		(property "Device Type" "R402H16"
			(at 0.064008 -5.517896 0)
			(unlocked yes)
			(layer "F.Fab")
			(hide yes)
			(effects
				(font
					(size 1.016 1.016)
					(thickness 0.1524)
				)
			)
		)
		(duplicate_pad_numbers_are_jumpers no)
		(fp_line
			(start -0.508 -0.9398)
			(end -0.508 0.9398)
			(stroke
				(width 0.1524)
				(type default)
			)
			(layer "F.SilkS")
		)
		(fp_line
			(start 0.508 -0.9398)
			(end -0.508 -0.9398)
			(stroke
				(width 0.1524)
				(type default)
			)
			(layer "F.SilkS")
		)
		(fp_rect
			(start -0.508 0.9398)
			(end 0.508 -0.9398)
			(stroke
				(width 0)
				(type default)
			)
			(fill no)
			(layer "F.CrtYd")
		)
		(fp_rect
			(start -0.508 0.9398)
			(end 0.508 -0.9398)
			(stroke
				(width 0)
				(type default)
			)
			(fill no)
			(layer "F.Fab")
		)
		(pad "1" smd custom
			(at 0 -0.4445)
			(size 0.1397 0.1397)
			(layers "F.Cu" "F.Mask" "F.Paste")
			(net "P1V8_E")
			(options
				(clearance outline)
				(anchor circle)
			)
			(primitives
				(gr_poly
					(pts
						(arc
							(start -0.1778 -0.2794)
							(mid -0.249642 -0.249642)
							(end -0.2794 -0.1778)
						)
						(arc
							(start -0.2794 0.1778)
							(mid -0.249642 0.249642)
							(end -0.1778 0.2794)
						)
						(arc
							(start 0.1778 0.2794)
							(mid 0.249642 0.249642)
							(end 0.2794 0.1778)
						)
						(arc
							(start 0.2794 -0.1778)
							(mid 0.249642 -0.249642)
							(end 0.1778 -0.2794)
						)
					)
					(width 0)
					(fill yes)
				)
			)
		)
		(pad "2" smd custom
			(at 0 0.4445)
			(size 0.1397 0.1397)
			(layers "F.Cu" "F.Mask" "F.Paste")
			(net "SAS_SMART_TX")
			(options
				(clearance outline)
				(anchor circle)
			)
			(primitives
				(gr_poly
					(pts
						(arc
							(start -0.1778 -0.2794)
							(mid -0.249642 -0.249642)
							(end -0.2794 -0.1778)
						)
						(arc
							(start -0.2794 0.1778)
							(mid -0.249642 0.249642)
							(end -0.1778 0.2794)
						)
						(arc
							(start 0.1778 0.2794)
							(mid 0.249642 0.249642)
							(end 0.2794 0.1778)
						)
						(arc
							(start 0.2794 -0.1778)
							(mid 0.249642 -0.249642)
							(end 0.1778 -0.2794)
						)
					)
					(width 0)
					(fill yes)
				)
			)
		)
	)
	(footprint ""
		(layer "F.Cu")
		(at 181.821836 -122.7836 90)
		(property "Reference" "C686"
			(at 0 0 90)
			(layer "F.SilkS")
			(hide yes)
			(effects
				(font
					(size 1.27 1.27)
				)
			)
		)
		(property "Value" "SC10U6D3V5KX-4GP"
			(at -0.0762 -6.1214 90)
			(unlocked yes)
			(layer "F.Fab")
			(hide yes)
			(effects
				(font
					(size 1.016 1.016)
					(thickness 0.1524)
				)
			)
		)
		(property "Device Type" "C805H58"
			(at -0.0762 -8.1534 90)
			(unlocked yes)
			(layer "F.Fab")
			(hide yes)
			(effects
				(font
					(size 1.016 1.016)
					(thickness 0.1524)
				)
			)
		)
		(duplicate_pad_numbers_are_jumpers no)
		(fp_line
			(start 0.635 0)
			(end -0.635 0)
			(stroke
				(width 0.508)
				(type default)
			)
			(layer "F.SilkS")
		)
		(fp_rect
			(start -0.9652 1.778)
			(end 0.9652 -1.778)
			(stroke
				(width 0)
				(type default)
			)
			(fill no)
			(layer "F.CrtYd")
		)
		(fp_poly
			(pts
				(xy -0.9652 -1.778) (xy 0.9652 -1.778) (xy 0.9652 1.778) (xy -0.9652 1.778)
			)
			(stroke
				(width 0)
				(type default)
			)
			(fill no)
			(layer "F.Fab")
		)
		(pad "1" smd rect
			(at 0 -0.9652 90)
			(size 1.397 1.143)
			(layers "F.Cu" "F.Mask" "F.Paste")
			(net "P1V8_E_OUT")
		)
		(pad "2" smd rect
			(at 0 0.9652 90)
			(size 1.397 1.143)
			(layers "F.Cu" "F.Mask" "F.Paste")
			(net "GND")
		)
	)
	(footprint ""
		(layer "F.Cu")
		(at 136.2456 -80.5688 90)
		(property "Reference" "C610"
			(at 0 0 90)
			(layer "F.SilkS")
			(hide yes)
			(effects
				(font
					(size 1.27 1.27)
				)
			)
		)
		(property "Value" "SCD01U16V1KX-GP"
			(at -2.8321 -1.7399 90)
			(unlocked yes)
			(layer "F.Fab")
			(hide yes)
			(effects
				(font
					(size 1.016 1.016)
					(thickness 0.1524)
				)
			)
		)
		(property "Device Type" "C0201H13"
			(at -2.8321 -3.2639 90)
			(unlocked yes)
			(layer "F.Fab")
			(hide yes)
			(effects
				(font
					(size 1.016 1.016)
					(thickness 0.1524)
				)
			)
		)
		(duplicate_pad_numbers_are_jumpers no)
		(fp_rect
			(start -0.2794 0.6477)
			(end 0.2794 -0.6477)
			(stroke
				(width 0)
				(type default)
			)
			(fill no)
			(layer "F.CrtYd")
		)
		(fp_rect
			(start -0.2794 0.6477)
			(end 0.2794 -0.6477)
			(stroke
				(width 0)
				(type default)
			)
			(fill no)
			(layer "F.Fab")
		)
		(pad "1" smd custom
			(at 0 -0.2794 90)
			(size 0.0762 0.0762)
			(layers "F.Cu" "F.Mask" "F.Paste")
			(net "PHY_EXP_TO_CONN_C_11_DP")
			(options
				(clearance outline)
				(anchor circle)
			)
			(primitives
				(gr_poly
					(pts
						(arc
							(start 0.1524 -0.127)
							(mid 0.137521 -0.162921)
							(end 0.1016 -0.1778)
						)
						(arc
							(start -0.1016 -0.1778)
							(mid -0.137521 -0.162921)
							(end -0.1524 -0.127)
						)
						(arc
							(start -0.1524 0.127)
							(mid -0.137521 0.162921)
							(end -0.1016 0.1778)
						)
						(arc
							(start 0.1016 0.1778)
							(mid 0.137521 0.162921)
							(end 0.1524 0.127)
						)
					)
					(width 0)
					(fill yes)
				)
			)
		)
		(pad "2" smd custom
			(at 0 0.2794 90)
			(size 0.0762 0.0762)
			(layers "F.Cu" "F.Mask" "F.Paste")
			(net "PHY_EXP_TO_CONN_11_DP")
			(options
				(clearance outline)
				(anchor circle)
			)
			(primitives
				(gr_poly
					(pts
						(arc
							(start 0.1524 -0.127)
							(mid 0.137521 -0.162921)
							(end 0.1016 -0.1778)
						)
						(arc
							(start -0.1016 -0.1778)
							(mid -0.137521 -0.162921)
							(end -0.1524 -0.127)
						)
						(arc
							(start -0.1524 0.127)
							(mid -0.137521 0.162921)
							(end -0.1016 0.1778)
						)
						(arc
							(start 0.1016 0.1778)
							(mid 0.137521 0.162921)
							(end 0.1524 0.127)
						)
					)
					(width 0)
					(fill yes)
				)
			)
		)
	)
	(footprint ""
		(layer "F.Cu")
		(at 17.3736 -46.9646)
		(property "Reference" "C650"
			(at 0 0 0)
			(layer "F.SilkS")
			(hide yes)
			(effects
				(font
					(size 1.27 1.27)
				)
			)
		)
		(property "Value" "SC1U16V3KX-5GP"
			(at 0 -2.8194 0)
			(unlocked yes)
			(layer "F.Fab")
			(hide yes)
			(effects
				(font
					(size 1.016 1.016)
					(thickness 0.1524)
				)
			)
		)
		(property "Device Type" "C603H36"
			(at 0 -4.3434 0)
			(unlocked yes)
			(layer "F.Fab")
			(hide yes)
			(effects
				(font
					(size 1.016 1.016)
					(thickness 0.1524)
				)
			)
		)
		(duplicate_pad_numbers_are_jumpers no)
		(fp_line
			(start 0.508 0)
			(end -0.508 0)
			(stroke
				(width 0.2032)
				(type default)
			)
			(layer "F.SilkS")
		)
		(fp_rect
			(start -0.5842 1.3335)
			(end 0.5842 -1.3335)
			(stroke
				(width 0)
				(type default)
			)
			(fill no)
			(layer "F.CrtYd")
		)
		(fp_rect
			(start -0.5842 1.3335)
			(end 0.5842 -1.3335)
			(stroke
				(width 0)
				(type default)
			)
			(fill no)
			(layer "F.Fab")
		)
		(pad "1" smd custom
			(at 0 -0.762)
			(size 0.2159 0.2159)
			(layers "F.Cu" "F.Mask" "F.Paste")
			(net "MB0_CM_UV_R")
			(options
				(clearance outline)
				(anchor circle)
			)
			(primitives
				(gr_poly
					(pts
						(arc
							(start -0.3302 -0.4318)
							(mid -0.402042 -0.402042)
							(end -0.4318 -0.3302)
						)
						(arc
							(start -0.4318 0.3302)
							(mid -0.402042 0.402042)
							(end -0.3302 0.4318)
						)
						(arc
							(start 0.3302 0.4318)
							(mid 0.402042 0.402042)
							(end 0.4318 0.3302)
						)
						(arc
							(start 0.4318 -0.3302)
							(mid 0.402042 -0.402042)
							(end 0.3302 -0.4318)
						)
					)
					(width 0)
					(fill yes)
				)
			)
		)
		(pad "2" smd custom
			(at 0 0.762)
			(size 0.2159 0.2159)
			(layers "F.Cu" "F.Mask" "F.Paste")
			(net "AGND_CURRENT_MON")
			(options
				(clearance outline)
				(anchor circle)
			)
			(primitives
				(gr_poly
					(pts
						(arc
							(start -0.3302 -0.4318)
							(mid -0.402042 -0.402042)
							(end -0.4318 -0.3302)
						)
						(arc
							(start -0.4318 0.3302)
							(mid -0.402042 0.402042)
							(end -0.3302 0.4318)
						)
						(arc
							(start 0.3302 0.4318)
							(mid 0.402042 0.402042)
							(end 0.4318 0.3302)
						)
						(arc
							(start 0.4318 -0.3302)
							(mid 0.402042 -0.402042)
							(end 0.3302 -0.4318)
						)
					)
					(width 0)
					(fill yes)
				)
			)
		)
	)
	(footprint ""
		(layer "F.Cu")
		(at 24.4094 -89.0524)
		(property "Reference" "U46"
			(at 0 0 0)
			(layer "F.SilkS")
			(hide yes)
			(effects
				(font
					(size 1.27 1.27)
				)
			)
		)
		(property "Value" "PCA9306DCTR-GP"
			(at 0 -11.6332 0)
			(unlocked yes)
			(layer "F.Fab")
			(hide yes)
			(effects
				(font
					(size 1.016 1.016)
					(thickness 0.1524)
				)
			)
		)
		(property "Device Type" "SSOIC8H52"
			(at 0 -13.1572 0)
			(unlocked yes)
			(layer "F.Fab")
			(hide yes)
			(effects
				(font
					(size 1.016 1.016)
					(thickness 0.1524)
				)
			)
		)
		(duplicate_pad_numbers_are_jumpers no)
		(fp_line
			(start -1.7018 -0.5842)
			(end -1.7018 2.286)
			(stroke
				(width 0.1524)
				(type default)
			)
			(layer "F.SilkS")
		)
		(fp_line
			(start -1.7018 -0.5842)
			(end 1.0668 -0.5842)
			(stroke
				(width 0.1524)
				(type default)
			)
			(layer "F.SilkS")
		)
		(fp_line
			(start -1.524 0.5842)
			(end -1.524 2.286)
			(stroke
				(width 0.508)
				(type default)
			)
			(layer "F.SilkS")
		)
		(fp_line
			(start -1.397 0)
			(end -1.7018 -0.3048)
			(stroke
				(width 0.1524)
				(type default)
			)
			(layer "F.SilkS")
		)
		(fp_line
			(start -1.397 0)
			(end -1.7018 0.3048)
			(stroke
				(width 0.1524)
				(type default)
			)
			(layer "F.SilkS")
		)
		(fp_line
			(start 1.0668 -0.5842)
			(end 1.0668 0.5842)
			(stroke
				(width 0.1524)
				(type default)
			)
			(layer "F.SilkS")
		)
		(fp_line
			(start 1.0668 0.5842)
			(end -1.524 0.5842)
			(stroke
				(width 0.1524)
				(type default)
			)
			(layer "F.SilkS")
		)
		(fp_poly
			(pts
				(xy -1.1684 -0.5842) (xy 1.0668 -0.5842) (xy 1.0668 0.5842) (xy -1.1684 0.5842)
			)
			(stroke
				(width 0)
				(type default)
			)
			(fill yes)
			(layer "F.SilkS")
		)
		(fp_poly
			(pts
				(xy -1.778 2.54) (xy 1.778 2.54) (xy 1.778 -2.54) (xy -1.778 -2.54)
			)
			(stroke
				(width 0)
				(type default)
			)
			(fill no)
			(layer "F.CrtYd")
		)
		(fp_poly
			(pts
				(xy -1.778 -2.54) (xy 1.778 -2.54) (xy 1.778 2.54) (xy -1.778 2.54)
			)
			(stroke
				(width 0)
				(type default)
			)
			(fill no)
			(layer "F.Fab")
		)
		(pad "1" smd rect
			(at -0.97536 1.6256)
			(size 0.3556 1.524)
			(layers "F.Cu" "F.Mask" "F.Paste")
			(net "GND")
		)
		(pad "2" smd rect
			(at -0.32512 1.6256)
			(size 0.3556 1.524)
			(layers "F.Cu" "F.Mask" "F.Paste")
			(net "P1V8_E")
		)
		(pad "3" smd rect
			(at 0.32512 1.6256)
			(size 0.3556 1.524)
			(layers "F.Cu" "F.Mask" "F.Paste")
			(net "I2C_BMC_RMT_SCL1_LS")
		)
		(pad "4" smd rect
			(at 0.97536 1.6256)
			(size 0.3556 1.524)
			(layers "F.Cu" "F.Mask" "F.Paste")
			(net "I2C_BMC_RMT_SDA1_LS")
		)
		(pad "5" smd rect
			(at 0.97536 -1.6256)
			(size 0.3556 1.524)
			(layers "F.Cu" "F.Mask" "F.Paste")
			(net "I2C_BMC_RMT_SDA1")
		)
		(pad "6" smd rect
			(at 0.32512 -1.6256)
			(size 0.3556 1.524)
			(layers "F.Cu" "F.Mask" "F.Paste")
			(net "I2C_BMC_RMT_SCL1")
		)
		(pad "7" smd rect
			(at -0.32512 -1.6256)
			(size 0.3556 1.524)
			(layers "F.Cu" "F.Mask" "F.Paste")
			(net "VREF1")
		)
		(pad "8" smd rect
			(at -0.97536 -1.6256)
			(size 0.3556 1.524)
			(layers "F.Cu" "F.Mask" "F.Paste")
			(net "LS_EN_U46")
		)
	)
	(footprint ""
		(layer "F.Cu")
		(at 23.7998 -99.7966)
		(property "Reference" "R558"
			(at 0 0 0)
			(layer "F.SilkS")
			(hide yes)
			(effects
				(font
					(size 1.27 1.27)
				)
			)
		)
		(property "Value" "0R2J-2-GP"
			(at 0.064008 -3.993896 0)
			(unlocked yes)
			(layer "F.Fab")
			(hide yes)
			(effects
				(font
					(size 1.016 1.016)
					(thickness 0.1524)
				)
			)
		)
		(property "Device Type" "R402H16"
			(at 0.064008 -5.517896 0)
			(unlocked yes)
			(layer "F.Fab")
			(hide yes)
			(effects
				(font
					(size 1.016 1.016)
					(thickness 0.1524)
				)
			)
		)
		(duplicate_pad_numbers_are_jumpers no)
		(fp_line
			(start -0.508 -0.9398)
			(end -0.508 0.9398)
			(stroke
				(width 0.1524)
				(type default)
			)
			(layer "F.SilkS")
		)
		(fp_line
			(start 0.508 -0.9398)
			(end -0.508 -0.9398)
			(stroke
				(width 0.1524)
				(type default)
			)
			(layer "F.SilkS")
		)
		(fp_rect
			(start -0.508 0.9398)
			(end 0.508 -0.9398)
			(stroke
				(width 0)
				(type default)
			)
			(fill no)
			(layer "F.CrtYd")
		)
		(fp_rect
			(start -0.508 0.9398)
			(end 0.508 -0.9398)
			(stroke
				(width 0)
				(type default)
			)
			(fill no)
			(layer "F.Fab")
		)
		(pad "1" smd custom
			(at 0 -0.4445)
			(size 0.1397 0.1397)
			(layers "F.Cu" "F.Mask" "F.Paste")
			(net "SCC_STBY_PGOOD_R")
			(options
				(clearance outline)
				(anchor circle)
			)
			(primitives
				(gr_poly
					(pts
						(arc
							(start -0.1778 -0.2794)
							(mid -0.249642 -0.249642)
							(end -0.2794 -0.1778)
						)
						(arc
							(start -0.2794 0.1778)
							(mid -0.249642 0.249642)
							(end -0.1778 0.2794)
						)
						(arc
							(start 0.1778 0.2794)
							(mid 0.249642 0.249642)
							(end 0.2794 0.1778)
						)
						(arc
							(start 0.2794 -0.1778)
							(mid 0.249642 -0.249642)
							(end 0.1778 -0.2794)
						)
					)
					(width 0)
					(fill yes)
				)
			)
		)
		(pad "2" smd custom
			(at 0 0.4445)
			(size 0.1397 0.1397)
			(layers "F.Cu" "F.Mask" "F.Paste")
			(net "SCC_STBY_PGOOD")
			(options
				(clearance outline)
				(anchor circle)
			)
			(primitives
				(gr_poly
					(pts
						(arc
							(start -0.1778 -0.2794)
							(mid -0.249642 -0.249642)
							(end -0.2794 -0.1778)
						)
						(arc
							(start -0.2794 0.1778)
							(mid -0.249642 0.249642)
							(end -0.1778 0.2794)
						)
						(arc
							(start 0.1778 0.2794)
							(mid 0.249642 0.249642)
							(end 0.2794 0.1778)
						)
						(arc
							(start 0.2794 -0.1778)
							(mid 0.249642 -0.249642)
							(end 0.1778 -0.2794)
						)
					)
					(width 0)
					(fill yes)
				)
			)
		)
	)
	(footprint ""
		(layer "F.Cu")
		(at 63.71463 -71.051928 -90)
		(property "Reference" "C551"
			(at 0 0 270)
			(layer "F.SilkS")
			(hide yes)
			(effects
				(font
					(size 1.27 1.27)
				)
			)
		)
		(property "Value" "SCD1U16V2KX-3GP"
			(at 1.1811 -2.7051 270)
			(unlocked yes)
			(layer "F.Fab")
			(hide yes)
			(effects
				(font
					(size 1.016 1.016)
					(thickness 0.1524)
				)
			)
		)
		(property "Device Type" "C402H22"
			(at 1.1811 -4.2291 270)
			(unlocked yes)
			(layer "F.Fab")
			(hide yes)
			(effects
				(font
					(size 1.016 1.016)
					(thickness 0.1524)
				)
			)
		)
		(duplicate_pad_numbers_are_jumpers no)
		(fp_rect
			(start -0.4318 0.9525)
			(end 0.4318 -0.9525)
			(stroke
				(width 0)
				(type default)
			)
			(fill no)
			(layer "F.CrtYd")
		)
		(fp_rect
			(start -0.4318 0.9525)
			(end 0.4318 -0.9525)
			(stroke
				(width 0)
				(type default)
			)
			(fill no)
			(layer "F.Fab")
		)
		(pad "1" smd custom
			(at 0 -0.4445 270)
			(size 0.1524 0.1524)
			(layers "F.Cu" "F.Mask" "F.Paste")
			(net "VREF5")
			(options
				(clearance outline)
				(anchor circle)
			)
			(primitives
				(gr_poly
					(pts
						(arc
							(start 0.3048 -0.2032)
							(mid 0.275042 -0.275042)
							(end 0.2032 -0.3048)
						)
						(arc
							(start -0.2032 -0.3048)
							(mid -0.275042 -0.275042)
							(end -0.3048 -0.2032)
						)
						(arc
							(start -0.3048 0.2032)
							(mid -0.275042 0.275042)
							(end -0.2032 0.3048)
						)
						(arc
							(start 0.2032 0.3048)
							(mid 0.275042 0.275042)
							(end 0.3048 0.2032)
						)
					)
					(width 0)
					(fill yes)
				)
			)
		)
		(pad "2" smd custom
			(at 0 0.4445 270)
			(size 0.1524 0.1524)
			(layers "F.Cu" "F.Mask" "F.Paste")
			(net "GND")
			(options
				(clearance outline)
				(anchor circle)
			)
			(primitives
				(gr_poly
					(pts
						(arc
							(start 0.3048 -0.2032)
							(mid 0.275042 -0.275042)
							(end 0.2032 -0.3048)
						)
						(arc
							(start -0.2032 -0.3048)
							(mid -0.275042 -0.275042)
							(end -0.3048 -0.2032)
						)
						(arc
							(start -0.3048 0.2032)
							(mid -0.275042 0.275042)
							(end -0.2032 0.3048)
						)
						(arc
							(start 0.2032 0.3048)
							(mid 0.275042 0.275042)
							(end 0.3048 0.2032)
						)
					)
					(width 0)
					(fill yes)
				)
			)
		)
	)
	(footprint ""
		(layer "F.Cu")
		(at 167.34536 -100.67544)
		(property "Reference" "R535"
			(at 0 0 0)
			(layer "F.SilkS")
			(hide yes)
			(effects
				(font
					(size 1.27 1.27)
				)
			)
		)
		(property "Value" "0R2J-2-GP"
			(at 0.064008 -3.993896 0)
			(unlocked yes)
			(layer "F.Fab")
			(hide yes)
			(effects
				(font
					(size 1.016 1.016)
					(thickness 0.1524)
				)
			)
		)
		(property "Device Type" "R402H16"
			(at 0.064008 -5.517896 0)
			(unlocked yes)
			(layer "F.Fab")
			(hide yes)
			(effects
				(font
					(size 1.016 1.016)
					(thickness 0.1524)
				)
			)
		)
		(duplicate_pad_numbers_are_jumpers no)
		(fp_line
			(start -0.508 -0.9398)
			(end -0.508 0.9398)
			(stroke
				(width 0.1524)
				(type default)
			)
			(layer "F.SilkS")
		)
		(fp_line
			(start 0.508 -0.9398)
			(end -0.508 -0.9398)
			(stroke
				(width 0.1524)
				(type default)
			)
			(layer "F.SilkS")
		)
		(fp_rect
			(start -0.508 0.9398)
			(end 0.508 -0.9398)
			(stroke
				(width 0)
				(type default)
			)
			(fill no)
			(layer "F.CrtYd")
		)
		(fp_rect
			(start -0.508 0.9398)
			(end 0.508 -0.9398)
			(stroke
				(width 0)
				(type default)
			)
			(fill no)
			(layer "F.Fab")
		)
		(pad "1" smd custom
			(at 0 -0.4445)
			(size 0.1397 0.1397)
			(layers "F.Cu" "F.Mask" "F.Paste")
			(net "SCC_FULL_PGOOD")
			(options
				(clearance outline)
				(anchor circle)
			)
			(primitives
				(gr_poly
					(pts
						(arc
							(start -0.1778 -0.2794)
							(mid -0.249642 -0.249642)
							(end -0.2794 -0.1778)
						)
						(arc
							(start -0.2794 0.1778)
							(mid -0.249642 0.249642)
							(end -0.1778 0.2794)
						)
						(arc
							(start 0.1778 0.2794)
							(mid 0.249642 0.249642)
							(end 0.2794 0.1778)
						)
						(arc
							(start 0.2794 -0.1778)
							(mid 0.249642 -0.249642)
							(end 0.1778 -0.2794)
						)
					)
					(width 0)
					(fill yes)
				)
			)
		)
		(pad "2" smd custom
			(at 0 0.4445)
			(size 0.1397 0.1397)
			(layers "F.Cu" "F.Mask" "F.Paste")
			(net "P0V975_STAT")
			(options
				(clearance outline)
				(anchor circle)
			)
			(primitives
				(gr_poly
					(pts
						(arc
							(start -0.1778 -0.2794)
							(mid -0.249642 -0.249642)
							(end -0.2794 -0.1778)
						)
						(arc
							(start -0.2794 0.1778)
							(mid -0.249642 0.249642)
							(end -0.1778 0.2794)
						)
						(arc
							(start 0.1778 0.2794)
							(mid 0.249642 0.249642)
							(end 0.2794 0.1778)
						)
						(arc
							(start 0.2794 -0.1778)
							(mid 0.249642 -0.249642)
							(end 0.1778 -0.2794)
						)
					)
					(width 0)
					(fill yes)
				)
			)
		)
	)
	(footprint ""
		(layer "F.Cu")
		(at 160.274 -70.80123 -90)
		(property "Reference" "R359"
			(at 0 0 270)
			(layer "F.SilkS")
			(hide yes)
			(effects
				(font
					(size 1.27 1.27)
				)
			)
		)
		(property "Value" "1KR2F-3-GP"
			(at 0.064008 -3.993896 270)
			(unlocked yes)
			(layer "F.Fab")
			(hide yes)
			(effects
				(font
					(size 1.016 1.016)
					(thickness 0.1524)
				)
			)
		)
		(property "Device Type" "R402H16"
			(at 0.064008 -5.517896 270)
			(unlocked yes)
			(layer "F.Fab")
			(hide yes)
			(effects
				(font
					(size 1.016 1.016)
					(thickness 0.1524)
				)
			)
		)
		(duplicate_pad_numbers_are_jumpers no)
		(fp_line
			(start -0.508 -0.9398)
			(end -0.508 0.9398)
			(stroke
				(width 0.1524)
				(type default)
			)
			(layer "F.SilkS")
		)
		(fp_line
			(start 0.508 -0.9398)
			(end -0.508 -0.9398)
			(stroke
				(width 0.1524)
				(type default)
			)
			(layer "F.SilkS")
		)
		(fp_rect
			(start -0.508 0.9398)
			(end 0.508 -0.9398)
			(stroke
				(width 0)
				(type default)
			)
			(fill no)
			(layer "F.CrtYd")
		)
		(fp_rect
			(start -0.508 0.9398)
			(end 0.508 -0.9398)
			(stroke
				(width 0)
				(type default)
			)
			(fill no)
			(layer "F.Fab")
		)
		(pad "1" smd custom
			(at 0 -0.4445 270)
			(size 0.1397 0.1397)
			(layers "F.Cu" "F.Mask" "F.Paste")
			(net "P0V975")
			(options
				(clearance outline)
				(anchor circle)
			)
			(primitives
				(gr_poly
					(pts
						(arc
							(start -0.1778 -0.2794)
							(mid -0.249642 -0.249642)
							(end -0.2794 -0.1778)
						)
						(arc
							(start -0.2794 0.1778)
							(mid -0.249642 0.249642)
							(end -0.1778 0.2794)
						)
						(arc
							(start 0.1778 0.2794)
							(mid 0.249642 0.249642)
							(end 0.2794 0.1778)
						)
						(arc
							(start 0.2794 -0.1778)
							(mid 0.249642 -0.249642)
							(end 0.1778 -0.2794)
						)
					)
					(width 0)
					(fill yes)
				)
			)
		)
		(pad "2" smd custom
			(at 0 0.4445 270)
			(size 0.1397 0.1397)
			(layers "F.Cu" "F.Mask" "F.Paste")
			(net "P0V975_SENSE")
			(options
				(clearance outline)
				(anchor circle)
			)
			(primitives
				(gr_poly
					(pts
						(arc
							(start -0.1778 -0.2794)
							(mid -0.249642 -0.249642)
							(end -0.2794 -0.1778)
						)
						(arc
							(start -0.2794 0.1778)
							(mid -0.249642 0.249642)
							(end -0.1778 0.2794)
						)
						(arc
							(start 0.1778 0.2794)
							(mid 0.249642 0.249642)
							(end 0.2794 0.1778)
						)
						(arc
							(start 0.2794 -0.1778)
							(mid 0.249642 -0.249642)
							(end 0.1778 -0.2794)
						)
					)
					(width 0)
					(fill yes)
				)
			)
		)
	)
	(footprint ""
		(layer "F.Cu")
		(at 185.478674 -24.966422 -90)
		(property "Reference" "R235"
			(at 0 0 270)
			(layer "F.SilkS")
			(hide yes)
			(effects
				(font
					(size 1.27 1.27)
				)
			)
		)
		(property "Value" "4K7R2F-GP"
			(at 0.064008 -3.993896 270)
			(unlocked yes)
			(layer "F.Fab")
			(hide yes)
			(effects
				(font
					(size 1.016 1.016)
					(thickness 0.1524)
				)
			)
		)
		(property "Device Type" "R402H16"
			(at 0.064008 -5.517896 270)
			(unlocked yes)
			(layer "F.Fab")
			(hide yes)
			(effects
				(font
					(size 1.016 1.016)
					(thickness 0.1524)
				)
			)
		)
		(duplicate_pad_numbers_are_jumpers no)
		(fp_line
			(start -0.508 -0.9398)
			(end -0.508 0.9398)
			(stroke
				(width 0.1524)
				(type default)
			)
			(layer "F.SilkS")
		)
		(fp_line
			(start 0.508 -0.9398)
			(end -0.508 -0.9398)
			(stroke
				(width 0.1524)
				(type default)
			)
			(layer "F.SilkS")
		)
		(fp_rect
			(start -0.508 0.9398)
			(end 0.508 -0.9398)
			(stroke
				(width 0)
				(type default)
			)
			(fill no)
			(layer "F.CrtYd")
		)
		(fp_rect
			(start -0.508 0.9398)
			(end 0.508 -0.9398)
			(stroke
				(width 0)
				(type default)
			)
			(fill no)
			(layer "F.Fab")
		)
		(pad "1" smd custom
			(at 0 -0.4445 270)
			(size 0.1397 0.1397)
			(layers "F.Cu" "F.Mask" "F.Paste")
			(net "P1V8_C")
			(options
				(clearance outline)
				(anchor circle)
			)
			(primitives
				(gr_poly
					(pts
						(arc
							(start -0.1778 -0.2794)
							(mid -0.249642 -0.249642)
							(end -0.2794 -0.1778)
						)
						(arc
							(start -0.2794 0.1778)
							(mid -0.249642 0.249642)
							(end -0.1778 0.2794)
						)
						(arc
							(start 0.1778 0.2794)
							(mid 0.249642 0.249642)
							(end 0.2794 0.1778)
						)
						(arc
							(start 0.2794 -0.1778)
							(mid 0.249642 -0.249642)
							(end 0.1778 -0.2794)
						)
					)
					(width 0)
					(fill yes)
				)
			)
		)
		(pad "2" smd custom
			(at 0 0.4445 270)
			(size 0.1397 0.1397)
			(layers "F.Cu" "F.Mask" "F.Paste")
			(net "IOC_UART_0_RX")
			(options
				(clearance outline)
				(anchor circle)
			)
			(primitives
				(gr_poly
					(pts
						(arc
							(start -0.1778 -0.2794)
							(mid -0.249642 -0.249642)
							(end -0.2794 -0.1778)
						)
						(arc
							(start -0.2794 0.1778)
							(mid -0.249642 0.249642)
							(end -0.1778 0.2794)
						)
						(arc
							(start 0.1778 0.2794)
							(mid 0.249642 0.249642)
							(end 0.2794 0.1778)
						)
						(arc
							(start 0.2794 -0.1778)
							(mid 0.249642 -0.249642)
							(end 0.1778 -0.2794)
						)
					)
					(width 0)
					(fill yes)
				)
			)
		)
	)
	(footprint ""
		(layer "F.Cu")
		(at 13.53947 -89.003378)
		(property "Reference" "U40"
			(at 0 0 0)
			(layer "F.SilkS")
			(hide yes)
			(effects
				(font
					(size 1.27 1.27)
				)
			)
		)
		(property "Value" "PCA9306DCTR-GP"
			(at 0 -11.6332 0)
			(unlocked yes)
			(layer "F.Fab")
			(hide yes)
			(effects
				(font
					(size 1.016 1.016)
					(thickness 0.1524)
				)
			)
		)
		(property "Device Type" "SSOIC8H52"
			(at 0 -13.1572 0)
			(unlocked yes)
			(layer "F.Fab")
			(hide yes)
			(effects
				(font
					(size 1.016 1.016)
					(thickness 0.1524)
				)
			)
		)
		(duplicate_pad_numbers_are_jumpers no)
		(fp_line
			(start -1.7018 -0.5842)
			(end -1.7018 2.286)
			(stroke
				(width 0.1524)
				(type default)
			)
			(layer "F.SilkS")
		)
		(fp_line
			(start -1.7018 -0.5842)
			(end 1.0668 -0.5842)
			(stroke
				(width 0.1524)
				(type default)
			)
			(layer "F.SilkS")
		)
		(fp_line
			(start -1.524 0.5842)
			(end -1.524 2.286)
			(stroke
				(width 0.508)
				(type default)
			)
			(layer "F.SilkS")
		)
		(fp_line
			(start -1.397 0)
			(end -1.7018 -0.3048)
			(stroke
				(width 0.1524)
				(type default)
			)
			(layer "F.SilkS")
		)
		(fp_line
			(start -1.397 0)
			(end -1.7018 0.3048)
			(stroke
				(width 0.1524)
				(type default)
			)
			(layer "F.SilkS")
		)
		(fp_line
			(start 1.0668 -0.5842)
			(end 1.0668 0.5842)
			(stroke
				(width 0.1524)
				(type default)
			)
			(layer "F.SilkS")
		)
		(fp_line
			(start 1.0668 0.5842)
			(end -1.524 0.5842)
			(stroke
				(width 0.1524)
				(type default)
			)
			(layer "F.SilkS")
		)
		(fp_poly
			(pts
				(xy -1.1684 -0.5842) (xy 1.0668 -0.5842) (xy 1.0668 0.5842) (xy -1.1684 0.5842)
			)
			(stroke
				(width 0)
				(type default)
			)
			(fill yes)
			(layer "F.SilkS")
		)
		(fp_poly
			(pts
				(xy -1.778 2.54) (xy 1.778 2.54) (xy 1.778 -2.54) (xy -1.778 -2.54)
			)
			(stroke
				(width 0)
				(type default)
			)
			(fill no)
			(layer "F.CrtYd")
		)
		(fp_poly
			(pts
				(xy -1.778 -2.54) (xy 1.778 -2.54) (xy 1.778 2.54) (xy -1.778 2.54)
			)
			(stroke
				(width 0)
				(type default)
			)
			(fill no)
			(layer "F.Fab")
		)
		(pad "1" smd rect
			(at -0.97536 1.6256)
			(size 0.3556 1.524)
			(layers "F.Cu" "F.Mask" "F.Paste")
			(net "GND")
		)
		(pad "2" smd rect
			(at -0.32512 1.6256)
			(size 0.3556 1.524)
			(layers "F.Cu" "F.Mask" "F.Paste")
			(net "P1V8_E")
		)
		(pad "3" smd rect
			(at 0.32512 1.6256)
			(size 0.3556 1.524)
			(layers "F.Cu" "F.Mask" "F.Paste")
			(net "I2C_DPB_SCL3_LS")
		)
		(pad "4" smd rect
			(at 0.97536 1.6256)
			(size 0.3556 1.524)
			(layers "F.Cu" "F.Mask" "F.Paste")
			(net "I2C_DPB_SDA3_LS")
		)
		(pad "5" smd rect
			(at 0.97536 -1.6256)
			(size 0.3556 1.524)
			(layers "F.Cu" "F.Mask" "F.Paste")
			(net "I2C_DPB_SDA3")
		)
		(pad "6" smd rect
			(at 0.32512 -1.6256)
			(size 0.3556 1.524)
			(layers "F.Cu" "F.Mask" "F.Paste")
			(net "I2C_DPB_SCL3")
		)
		(pad "7" smd rect
			(at -0.32512 -1.6256)
			(size 0.3556 1.524)
			(layers "F.Cu" "F.Mask" "F.Paste")
			(net "VREF3")
		)
		(pad "8" smd rect
			(at -0.97536 -1.6256)
			(size 0.3556 1.524)
			(layers "F.Cu" "F.Mask" "F.Paste")
			(net "LS_EN_U40")
		)
	)
	(footprint ""
		(layer "F.Cu")
		(at 168.42994 -58.08345)
		(property "Reference" "R264"
			(at 0 0 0)
			(layer "F.SilkS")
			(hide yes)
			(effects
				(font
					(size 1.27 1.27)
				)
			)
		)
		(property "Value" "4K7R2F-GP"
			(at 0.064008 -3.993896 0)
			(unlocked yes)
			(layer "F.Fab")
			(hide yes)
			(effects
				(font
					(size 1.016 1.016)
					(thickness 0.1524)
				)
			)
		)
		(property "Device Type" "R402H16"
			(at 0.064008 -5.517896 0)
			(unlocked yes)
			(layer "F.Fab")
			(hide yes)
			(effects
				(font
					(size 1.016 1.016)
					(thickness 0.1524)
				)
			)
		)
		(duplicate_pad_numbers_are_jumpers no)
		(fp_line
			(start -0.508 -0.9398)
			(end -0.508 0.9398)
			(stroke
				(width 0.1524)
				(type default)
			)
			(layer "F.SilkS")
		)
		(fp_line
			(start 0.508 -0.9398)
			(end -0.508 -0.9398)
			(stroke
				(width 0.1524)
				(type default)
			)
			(layer "F.SilkS")
		)
		(fp_rect
			(start -0.508 0.9398)
			(end 0.508 -0.9398)
			(stroke
				(width 0)
				(type default)
			)
			(fill no)
			(layer "F.CrtYd")
		)
		(fp_rect
			(start -0.508 0.9398)
			(end 0.508 -0.9398)
			(stroke
				(width 0)
				(type default)
			)
			(fill no)
			(layer "F.Fab")
		)
		(pad "1" smd custom
			(at 0 -0.4445)
			(size 0.1397 0.1397)
			(layers "F.Cu" "F.Mask" "F.Paste")
			(net "P1V8_C")
			(options
				(clearance outline)
				(anchor circle)
			)
			(primitives
				(gr_poly
					(pts
						(arc
							(start -0.1778 -0.2794)
							(mid -0.249642 -0.249642)
							(end -0.2794 -0.1778)
						)
						(arc
							(start -0.2794 0.1778)
							(mid -0.249642 0.249642)
							(end -0.1778 0.2794)
						)
						(arc
							(start 0.1778 0.2794)
							(mid 0.249642 0.249642)
							(end 0.2794 0.1778)
						)
						(arc
							(start 0.2794 -0.1778)
							(mid 0.249642 -0.249642)
							(end 0.1778 -0.2794)
						)
					)
					(width 0)
					(fill yes)
				)
			)
		)
		(pad "2" smd custom
			(at 0 0.4445)
			(size 0.1397 0.1397)
			(layers "F.Cu" "F.Mask" "F.Paste")
			(net "ICE0_TRST#")
			(options
				(clearance outline)
				(anchor circle)
			)
			(primitives
				(gr_poly
					(pts
						(arc
							(start -0.1778 -0.2794)
							(mid -0.249642 -0.249642)
							(end -0.2794 -0.1778)
						)
						(arc
							(start -0.2794 0.1778)
							(mid -0.249642 0.249642)
							(end -0.1778 0.2794)
						)
						(arc
							(start 0.1778 0.2794)
							(mid 0.249642 0.249642)
							(end 0.2794 0.1778)
						)
						(arc
							(start 0.2794 -0.1778)
							(mid 0.249642 -0.249642)
							(end 0.1778 -0.2794)
						)
					)
					(width 0)
					(fill yes)
				)
			)
		)
	)
	(footprint ""
		(layer "F.Cu")
		(at 55.88 -119.507 -90)
		(property "Reference" "C703"
			(at 0 0 270)
			(layer "F.SilkS")
			(hide yes)
			(effects
				(font
					(size 1.27 1.27)
				)
			)
		)
		(property "Value" "SC10U6D3V5KX-4GP"
			(at -0.0762 -6.1214 270)
			(unlocked yes)
			(layer "F.Fab")
			(hide yes)
			(effects
				(font
					(size 1.016 1.016)
					(thickness 0.1524)
				)
			)
		)
		(property "Device Type" "C805H58"
			(at -0.0762 -8.1534 270)
			(unlocked yes)
			(layer "F.Fab")
			(hide yes)
			(effects
				(font
					(size 1.016 1.016)
					(thickness 0.1524)
				)
			)
		)
		(duplicate_pad_numbers_are_jumpers no)
		(fp_line
			(start 0.635 0)
			(end -0.635 0)
			(stroke
				(width 0.508)
				(type default)
			)
			(layer "F.SilkS")
		)
		(fp_rect
			(start -0.9652 1.778)
			(end 0.9652 -1.778)
			(stroke
				(width 0)
				(type default)
			)
			(fill no)
			(layer "F.CrtYd")
		)
		(fp_poly
			(pts
				(xy -0.9652 -1.778) (xy 0.9652 -1.778) (xy 0.9652 1.778) (xy -0.9652 1.778)
			)
			(stroke
				(width 0)
				(type default)
			)
			(fill no)
			(layer "F.Fab")
		)
		(pad "1" smd rect
			(at 0 -0.9652 270)
			(size 1.397 1.143)
			(layers "F.Cu" "F.Mask" "F.Paste")
			(net "P3V3_OUT")
		)
		(pad "2" smd rect
			(at 0 0.9652 270)
			(size 1.397 1.143)
			(layers "F.Cu" "F.Mask" "F.Paste")
			(net "GND")
		)
	)
	(footprint ""
		(layer "F.Cu")
		(at 7.4422 -43.561 90)
		(property "Reference" "R527"
			(at 0 0 90)
			(layer "F.SilkS")
			(hide yes)
			(effects
				(font
					(size 1.27 1.27)
				)
			)
		)
		(property "Value" "0R5J-5-GP"
			(at 0 -8.9535 90)
			(unlocked yes)
			(layer "F.Fab")
			(hide yes)
			(effects
				(font
					(size 1.27 1.016)
					(thickness 0.1524)
				)
			)
		)
		(property "Device Type" "R805H24"
			(at 0 -10.6299 90)
			(unlocked yes)
			(layer "F.Fab")
			(hide yes)
			(effects
				(font
					(size 1.27 1.016)
					(thickness 0.1524)
				)
			)
		)
		(duplicate_pad_numbers_are_jumpers no)
		(fp_line
			(start 0.889 -1.7018)
			(end -0.889 -1.7018)
			(stroke
				(width 0.1524)
				(type default)
			)
			(layer "F.SilkS")
		)
		(fp_line
			(start 0.889 -1.7018)
			(end 0.889 -0.381)
			(stroke
				(width 0.1524)
				(type default)
			)
			(layer "F.SilkS")
		)
		(fp_line
			(start -0.889 -1.7018)
			(end -0.889 0.2794)
			(stroke
				(width 0.1524)
				(type default)
			)
			(layer "F.SilkS")
		)
		(fp_line
			(start -0.889 0.0762)
			(end -0.889 1.7018)
			(stroke
				(width 0.1524)
				(type default)
			)
			(layer "F.SilkS")
		)
		(fp_line
			(start 0.889 1.7018)
			(end 0.889 -0.508)
			(stroke
				(width 0.1524)
				(type default)
			)
			(layer "F.SilkS")
		)
		(fp_line
			(start -0.889 1.7018)
			(end 0.889 1.7018)
			(stroke
				(width 0.1524)
				(type default)
			)
			(layer "F.SilkS")
		)
		(fp_poly
			(pts
				(xy 0.9652 -1.778) (xy 0.9652 1.778) (xy -0.9652 1.778) (xy -0.9652 -1.778)
			)
			(stroke
				(width 0)
				(type default)
			)
			(fill no)
			(layer "F.CrtYd")
		)
		(fp_rect
			(start -0.9652 1.778)
			(end 0.9652 -1.778)
			(stroke
				(width 0)
				(type default)
			)
			(fill no)
			(layer "F.Fab")
		)
		(pad "1" smd rect
			(at 0 -0.9652 90)
			(size 1.397 1.143)
			(layers "F.Cu" "F.Mask" "F.Paste")
			(net "MB0_CM_GATE")
		)
		(pad "2" smd rect
			(at 0 0.9652 90)
			(size 1.397 1.143)
			(layers "F.Cu" "F.Mask" "F.Paste")
			(net "MB0_CM_GATE_R")
		)
	)
	(footprint ""
		(layer "F.Cu")
		(at 69.181472 -97.0788 -90)
		(property "Reference" "R502"
			(at 0 0 270)
			(layer "F.SilkS")
			(hide yes)
			(effects
				(font
					(size 1.27 1.27)
				)
			)
		)
		(property "Value" "619KR2F-GP"
			(at 0.064008 -3.993896 270)
			(unlocked yes)
			(layer "F.Fab")
			(hide yes)
			(effects
				(font
					(size 1.016 1.016)
					(thickness 0.1524)
				)
			)
		)
		(property "Device Type" "R402H16"
			(at 0.064008 -5.517896 270)
			(unlocked yes)
			(layer "F.Fab")
			(hide yes)
			(effects
				(font
					(size 1.016 1.016)
					(thickness 0.1524)
				)
			)
		)
		(duplicate_pad_numbers_are_jumpers no)
		(fp_line
			(start -0.508 -0.9398)
			(end -0.508 0.9398)
			(stroke
				(width 0.1524)
				(type default)
			)
			(layer "F.SilkS")
		)
		(fp_line
			(start 0.508 -0.9398)
			(end -0.508 -0.9398)
			(stroke
				(width 0.1524)
				(type default)
			)
			(layer "F.SilkS")
		)
		(fp_rect
			(start -0.508 0.9398)
			(end 0.508 -0.9398)
			(stroke
				(width 0)
				(type default)
			)
			(fill no)
			(layer "F.CrtYd")
		)
		(fp_rect
			(start -0.508 0.9398)
			(end 0.508 -0.9398)
			(stroke
				(width 0)
				(type default)
			)
			(fill no)
			(layer "F.Fab")
		)
		(pad "1" smd custom
			(at 0 -0.4445 270)
			(size 0.1397 0.1397)
			(layers "F.Cu" "F.Mask" "F.Paste")
			(net "AGND_P3V3")
			(options
				(clearance outline)
				(anchor circle)
			)
			(primitives
				(gr_poly
					(pts
						(arc
							(start -0.1778 -0.2794)
							(mid -0.249642 -0.249642)
							(end -0.2794 -0.1778)
						)
						(arc
							(start -0.2794 0.1778)
							(mid -0.249642 0.249642)
							(end -0.1778 0.2794)
						)
						(arc
							(start 0.1778 0.2794)
							(mid 0.249642 0.249642)
							(end 0.2794 0.1778)
						)
						(arc
							(start 0.2794 -0.1778)
							(mid 0.249642 -0.249642)
							(end 0.1778 -0.2794)
						)
					)
					(width 0)
					(fill yes)
				)
			)
		)
		(pad "2" smd custom
			(at 0 0.4445 270)
			(size 0.1397 0.1397)
			(layers "F.Cu" "F.Mask" "F.Paste")
			(net "P3V3_RF")
			(options
				(clearance outline)
				(anchor circle)
			)
			(primitives
				(gr_poly
					(pts
						(arc
							(start -0.1778 -0.2794)
							(mid -0.249642 -0.249642)
							(end -0.2794 -0.1778)
						)
						(arc
							(start -0.2794 0.1778)
							(mid -0.249642 0.249642)
							(end -0.1778 0.2794)
						)
						(arc
							(start 0.1778 0.2794)
							(mid 0.249642 0.249642)
							(end 0.2794 0.1778)
						)
						(arc
							(start 0.2794 -0.1778)
							(mid 0.249642 -0.249642)
							(end 0.1778 -0.2794)
						)
					)
					(width 0)
					(fill yes)
				)
			)
		)
	)
	(footprint ""
		(layer "F.Cu")
		(at 177.8508 -96.52 180)
		(property "Reference" "R489"
			(at 0 0 180)
			(layer "F.SilkS")
			(hide yes)
			(effects
				(font
					(size 1.27 1.27)
				)
			)
		)
		(property "Value" "221R2F-2-GP"
			(at 0.064008 -3.993896 180)
			(unlocked yes)
			(layer "F.Fab")
			(hide yes)
			(effects
				(font
					(size 1.016 1.016)
					(thickness 0.1524)
				)
			)
		)
		(property "Device Type" "R402H16"
			(at 0.064008 -5.517896 180)
			(unlocked yes)
			(layer "F.Fab")
			(hide yes)
			(effects
				(font
					(size 1.016 1.016)
					(thickness 0.1524)
				)
			)
		)
		(duplicate_pad_numbers_are_jumpers no)
		(fp_line
			(start 0.508 -0.9398)
			(end -0.508 -0.9398)
			(stroke
				(width 0.1524)
				(type default)
			)
			(layer "F.SilkS")
		)
		(fp_line
			(start -0.508 -0.9398)
			(end -0.508 0.9398)
			(stroke
				(width 0.1524)
				(type default)
			)
			(layer "F.SilkS")
		)
		(fp_rect
			(start -0.508 0.9398)
			(end 0.508 -0.9398)
			(stroke
				(width 0)
				(type default)
			)
			(fill no)
			(layer "F.CrtYd")
		)
		(fp_rect
			(start -0.508 0.9398)
			(end 0.508 -0.9398)
			(stroke
				(width 0)
				(type default)
			)
			(fill no)
			(layer "F.Fab")
		)
		(pad "1" smd custom
			(at 0 -0.4445 180)
			(size 0.1397 0.1397)
			(layers "F.Cu" "F.Mask" "F.Paste")
			(net "VT235_VFB")
			(options
				(clearance outline)
				(anchor circle)
			)
			(primitives
				(gr_poly
					(pts
						(arc
							(start -0.1778 -0.2794)
							(mid -0.249642 -0.249642)
							(end -0.2794 -0.1778)
						)
						(arc
							(start -0.2794 0.1778)
							(mid -0.249642 0.249642)
							(end -0.1778 0.2794)
						)
						(arc
							(start 0.1778 0.2794)
							(mid 0.249642 0.249642)
							(end 0.2794 0.1778)
						)
						(arc
							(start 0.2794 -0.1778)
							(mid 0.249642 -0.249642)
							(end 0.1778 -0.2794)
						)
					)
					(width 0)
					(fill yes)
				)
			)
		)
		(pad "2" smd custom
			(at 0 0.4445 180)
			(size 0.1397 0.1397)
			(layers "F.Cu" "F.Mask" "F.Paste")
			(net "P0V975_SEN")
			(options
				(clearance outline)
				(anchor circle)
			)
			(primitives
				(gr_poly
					(pts
						(arc
							(start -0.1778 -0.2794)
							(mid -0.249642 -0.249642)
							(end -0.2794 -0.1778)
						)
						(arc
							(start -0.2794 0.1778)
							(mid -0.249642 0.249642)
							(end -0.1778 0.2794)
						)
						(arc
							(start 0.1778 0.2794)
							(mid 0.249642 0.249642)
							(end 0.2794 0.1778)
						)
						(arc
							(start 0.2794 -0.1778)
							(mid 0.249642 -0.249642)
							(end 0.1778 -0.2794)
						)
					)
					(width 0)
					(fill yes)
				)
			)
		)
	)
	(footprint ""
		(layer "F.Cu")
		(at 26.00833 -93.622622)
		(property "Reference" "R450"
			(at 0 0 0)
			(layer "F.SilkS")
			(hide yes)
			(effects
				(font
					(size 1.27 1.27)
				)
			)
		)
		(property "Value" "1KR2F-3-GP"
			(at 0.064008 -3.993896 0)
			(unlocked yes)
			(layer "F.Fab")
			(hide yes)
			(effects
				(font
					(size 1.016 1.016)
					(thickness 0.1524)
				)
			)
		)
		(property "Device Type" "R402H16"
			(at 0.064008 -5.517896 0)
			(unlocked yes)
			(layer "F.Fab")
			(hide yes)
			(effects
				(font
					(size 1.016 1.016)
					(thickness 0.1524)
				)
			)
		)
		(duplicate_pad_numbers_are_jumpers no)
		(fp_line
			(start -0.508 -0.9398)
			(end -0.508 0.9398)
			(stroke
				(width 0.1524)
				(type default)
			)
			(layer "F.SilkS")
		)
		(fp_line
			(start 0.508 -0.9398)
			(end -0.508 -0.9398)
			(stroke
				(width 0.1524)
				(type default)
			)
			(layer "F.SilkS")
		)
		(fp_rect
			(start -0.508 0.9398)
			(end 0.508 -0.9398)
			(stroke
				(width 0)
				(type default)
			)
			(fill no)
			(layer "F.CrtYd")
		)
		(fp_rect
			(start -0.508 0.9398)
			(end 0.508 -0.9398)
			(stroke
				(width 0)
				(type default)
			)
			(fill no)
			(layer "F.Fab")
		)
		(pad "1" smd custom
			(at 0 -0.4445)
			(size 0.1397 0.1397)
			(layers "F.Cu" "F.Mask" "F.Paste")
			(net "P3V3")
			(options
				(clearance outline)
				(anchor circle)
			)
			(primitives
				(gr_poly
					(pts
						(arc
							(start -0.1778 -0.2794)
							(mid -0.249642 -0.249642)
							(end -0.2794 -0.1778)
						)
						(arc
							(start -0.2794 0.1778)
							(mid -0.249642 0.249642)
							(end -0.1778 0.2794)
						)
						(arc
							(start 0.1778 0.2794)
							(mid 0.249642 0.249642)
							(end 0.2794 0.1778)
						)
						(arc
							(start 0.2794 -0.1778)
							(mid 0.249642 -0.249642)
							(end 0.1778 -0.2794)
						)
					)
					(width 0)
					(fill yes)
				)
			)
		)
		(pad "2" smd custom
			(at 0 0.4445)
			(size 0.1397 0.1397)
			(layers "F.Cu" "F.Mask" "F.Paste")
			(net "I2C_BMC_RMT_SDA1")
			(options
				(clearance outline)
				(anchor circle)
			)
			(primitives
				(gr_poly
					(pts
						(arc
							(start -0.1778 -0.2794)
							(mid -0.249642 -0.249642)
							(end -0.2794 -0.1778)
						)
						(arc
							(start -0.2794 0.1778)
							(mid -0.249642 0.249642)
							(end -0.1778 0.2794)
						)
						(arc
							(start 0.1778 0.2794)
							(mid 0.249642 0.249642)
							(end 0.2794 0.1778)
						)
						(arc
							(start 0.2794 -0.1778)
							(mid 0.249642 -0.249642)
							(end 0.1778 -0.2794)
						)
					)
					(width 0)
					(fill yes)
				)
			)
		)
	)
	(footprint ""
		(layer "F.Cu")
		(at 184.570624 -58.470292 180)
		(property "Reference" "R222"
			(at 0 0 180)
			(layer "F.SilkS")
			(hide yes)
			(effects
				(font
					(size 1.27 1.27)
				)
			)
		)
		(property "Value" "10KR2F-2-GP"
			(at 0.064008 -3.993896 180)
			(unlocked yes)
			(layer "F.Fab")
			(hide yes)
			(effects
				(font
					(size 1.016 1.016)
					(thickness 0.1524)
				)
			)
		)
		(property "Device Type" "R402H16"
			(at 0.064008 -5.517896 180)
			(unlocked yes)
			(layer "F.Fab")
			(hide yes)
			(effects
				(font
					(size 1.016 1.016)
					(thickness 0.1524)
				)
			)
		)
		(duplicate_pad_numbers_are_jumpers no)
		(fp_line
			(start 0.508 -0.9398)
			(end -0.508 -0.9398)
			(stroke
				(width 0.1524)
				(type default)
			)
			(layer "F.SilkS")
		)
		(fp_line
			(start -0.508 -0.9398)
			(end -0.508 0.9398)
			(stroke
				(width 0.1524)
				(type default)
			)
			(layer "F.SilkS")
		)
		(fp_rect
			(start -0.508 0.9398)
			(end 0.508 -0.9398)
			(stroke
				(width 0)
				(type default)
			)
			(fill no)
			(layer "F.CrtYd")
		)
		(fp_rect
			(start -0.508 0.9398)
			(end 0.508 -0.9398)
			(stroke
				(width 0)
				(type default)
			)
			(fill no)
			(layer "F.Fab")
		)
		(pad "1" smd custom
			(at 0 -0.4445 180)
			(size 0.1397 0.1397)
			(layers "F.Cu" "F.Mask" "F.Paste")
			(net "XM_ADDR_1")
			(options
				(clearance outline)
				(anchor circle)
			)
			(primitives
				(gr_poly
					(pts
						(arc
							(start -0.1778 -0.2794)
							(mid -0.249642 -0.249642)
							(end -0.2794 -0.1778)
						)
						(arc
							(start -0.2794 0.1778)
							(mid -0.249642 0.249642)
							(end -0.1778 0.2794)
						)
						(arc
							(start 0.1778 0.2794)
							(mid 0.249642 0.249642)
							(end 0.2794 0.1778)
						)
						(arc
							(start 0.2794 -0.1778)
							(mid 0.249642 -0.249642)
							(end 0.1778 -0.2794)
						)
					)
					(width 0)
					(fill yes)
				)
			)
		)
		(pad "2" smd custom
			(at 0 0.4445 180)
			(size 0.1397 0.1397)
			(layers "F.Cu" "F.Mask" "F.Paste")
			(net "GND")
			(options
				(clearance outline)
				(anchor circle)
			)
			(primitives
				(gr_poly
					(pts
						(arc
							(start -0.1778 -0.2794)
							(mid -0.249642 -0.249642)
							(end -0.2794 -0.1778)
						)
						(arc
							(start -0.2794 0.1778)
							(mid -0.249642 0.249642)
							(end -0.1778 0.2794)
						)
						(arc
							(start 0.1778 0.2794)
							(mid 0.249642 0.249642)
							(end 0.2794 0.1778)
						)
						(arc
							(start 0.2794 -0.1778)
							(mid 0.249642 -0.249642)
							(end 0.1778 -0.2794)
						)
					)
					(width 0)
					(fill yes)
				)
			)
		)
	)
	(footprint ""
		(layer "F.Cu")
		(at 12.319 -98.425 90)
		(property "Reference" "C736"
			(at 0 0 90)
			(layer "F.SilkS")
			(hide yes)
			(effects
				(font
					(size 1.27 1.27)
				)
			)
		)
		(property "Value" "SCD1U16V2KX-3GP"
			(at 1.1811 -2.7051 90)
			(unlocked yes)
			(layer "F.Fab")
			(hide yes)
			(effects
				(font
					(size 1.016 1.016)
					(thickness 0.1524)
				)
			)
		)
		(property "Device Type" "C402H22"
			(at 1.1811 -4.2291 90)
			(unlocked yes)
			(layer "F.Fab")
			(hide yes)
			(effects
				(font
					(size 1.016 1.016)
					(thickness 0.1524)
				)
			)
		)
		(duplicate_pad_numbers_are_jumpers no)
		(fp_rect
			(start -0.4318 0.9525)
			(end 0.4318 -0.9525)
			(stroke
				(width 0)
				(type default)
			)
			(fill no)
			(layer "F.CrtYd")
		)
		(fp_rect
			(start -0.4318 0.9525)
			(end 0.4318 -0.9525)
			(stroke
				(width 0)
				(type default)
			)
			(fill no)
			(layer "F.Fab")
		)
		(pad "1" smd custom
			(at 0 -0.4445 90)
			(size 0.1524 0.1524)
			(layers "F.Cu" "F.Mask" "F.Paste")
			(net "U120_EN")
			(options
				(clearance outline)
				(anchor circle)
			)
			(primitives
				(gr_poly
					(pts
						(arc
							(start 0.3048 -0.2032)
							(mid 0.275042 -0.275042)
							(end 0.2032 -0.3048)
						)
						(arc
							(start -0.2032 -0.3048)
							(mid -0.275042 -0.275042)
							(end -0.3048 -0.2032)
						)
						(arc
							(start -0.3048 0.2032)
							(mid -0.275042 0.275042)
							(end -0.2032 0.3048)
						)
						(arc
							(start 0.2032 0.3048)
							(mid 0.275042 0.275042)
							(end 0.3048 0.2032)
						)
					)
					(width 0)
					(fill yes)
				)
			)
		)
		(pad "2" smd custom
			(at 0 0.4445 90)
			(size 0.1524 0.1524)
			(layers "F.Cu" "F.Mask" "F.Paste")
			(net "GND")
			(options
				(clearance outline)
				(anchor circle)
			)
			(primitives
				(gr_poly
					(pts
						(arc
							(start 0.3048 -0.2032)
							(mid 0.275042 -0.275042)
							(end 0.2032 -0.3048)
						)
						(arc
							(start -0.2032 -0.3048)
							(mid -0.275042 -0.275042)
							(end -0.3048 -0.2032)
						)
						(arc
							(start -0.3048 0.2032)
							(mid -0.275042 0.275042)
							(end -0.2032 0.3048)
						)
						(arc
							(start 0.2032 0.3048)
							(mid 0.275042 0.275042)
							(end 0.3048 0.2032)
						)
					)
					(width 0)
					(fill yes)
				)
			)
		)
	)
	(footprint ""
		(layer "F.Cu")
		(at 133.72973 -44.702984 180)
		(property "Reference" "C42"
			(at 0 0 180)
			(layer "F.SilkS")
			(hide yes)
			(effects
				(font
					(size 1.27 1.27)
				)
			)
		)
		(property "Value" "SCD01U16V1KX-GP"
			(at -2.8321 -1.7399 180)
			(unlocked yes)
			(layer "F.Fab")
			(hide yes)
			(effects
				(font
					(size 1.016 1.016)
					(thickness 0.1524)
				)
			)
		)
		(property "Device Type" "C0201H13"
			(at -2.8321 -3.2639 180)
			(unlocked yes)
			(layer "F.Fab")
			(hide yes)
			(effects
				(font
					(size 1.016 1.016)
					(thickness 0.1524)
				)
			)
		)
		(duplicate_pad_numbers_are_jumpers no)
		(fp_rect
			(start -0.2794 0.6477)
			(end 0.2794 -0.6477)
			(stroke
				(width 0)
				(type default)
			)
			(fill no)
			(layer "F.CrtYd")
		)
		(fp_rect
			(start -0.2794 0.6477)
			(end 0.2794 -0.6477)
			(stroke
				(width 0)
				(type default)
			)
			(fill no)
			(layer "F.Fab")
		)
		(pad "1" smd custom
			(at 0 -0.2794 180)
			(size 0.0762 0.0762)
			(layers "F.Cu" "F.Mask" "F.Paste")
			(net "PHY_IOC_TO_SCC_43_DN")
			(options
				(clearance outline)
				(anchor circle)
			)
			(primitives
				(gr_poly
					(pts
						(arc
							(start 0.1524 -0.127)
							(mid 0.137521 -0.162921)
							(end 0.1016 -0.1778)
						)
						(arc
							(start -0.1016 -0.1778)
							(mid -0.137521 -0.162921)
							(end -0.1524 -0.127)
						)
						(arc
							(start -0.1524 0.127)
							(mid -0.137521 0.162921)
							(end -0.1016 0.1778)
						)
						(arc
							(start 0.1016 0.1778)
							(mid 0.137521 0.162921)
							(end 0.1524 0.127)
						)
					)
					(width 0)
					(fill yes)
				)
			)
		)
		(pad "2" smd custom
			(at 0 0.2794 180)
			(size 0.0762 0.0762)
			(layers "F.Cu" "F.Mask" "F.Paste")
			(net "PHY_IOC_TO_SCC_C_43_DN")
			(options
				(clearance outline)
				(anchor circle)
			)
			(primitives
				(gr_poly
					(pts
						(arc
							(start 0.1524 -0.127)
							(mid 0.137521 -0.162921)
							(end 0.1016 -0.1778)
						)
						(arc
							(start -0.1016 -0.1778)
							(mid -0.137521 -0.162921)
							(end -0.1524 -0.127)
						)
						(arc
							(start -0.1524 0.127)
							(mid -0.137521 0.162921)
							(end -0.1016 0.1778)
						)
						(arc
							(start 0.1016 0.1778)
							(mid 0.137521 0.162921)
							(end 0.1524 0.127)
						)
					)
					(width 0)
					(fill yes)
				)
			)
		)
	)
	(footprint ""
		(layer "F.Cu")
		(at 129.648458 -46.400974 90)
		(property "Reference" "VIA11"
			(at 0 0 90)
			(layer "F.SilkS")
			(hide yes)
			(effects
				(font
					(size 1.27 1.27)
				)
			)
		)
		(property "Value" "100OHM-8L-1D6MM-L13-GP"
			(at 3.2893 0.0508 90)
			(unlocked yes)
			(layer "F.Fab")
			(hide yes)
			(effects
				(font
					(size 1.016 1.016)
					(thickness 0.1524)
				)
			)
		)
		(property "Device Type" "VIA-PCIE-4P-409091"
			(at 3.2893 -1.4732 90)
			(unlocked yes)
			(layer "F.Fab")
			(hide yes)
			(effects
				(font
					(size 1.016 1.016)
					(thickness 0.1524)
				)
			)
		)
		(duplicate_pad_numbers_are_jumpers no)
		(fp_rect
			(start -2.0447 0.4572)
			(end 2.0447 -0.4572)
			(stroke
				(width 0)
				(type default)
			)
			(fill no)
			(layer "F.CrtYd")
		)
		(fp_rect
			(start -2.0447 0.4572)
			(end 2.0447 -0.4572)
			(stroke
				(width 0)
				(type default)
			)
			(fill no)
			(layer "F.Fab")
		)
		(pad "1" thru_hole circle
			(at -1.5875 0 90)
			(size 0.508 0.508)
			(drill 0.254)
			(layers "*.Cu" "*.Mask")
			(remove_unused_layers no)
			(net "GND")
			(clearance 0.2032)
			(thermal_gap 0.2032)
		)
		(pad "2" thru_hole circle
			(at -0.5715 0 90)
			(size 0.508 0.508)
			(drill 0.254)
			(layers "*.Cu" "*.Mask")
			(remove_unused_layers no)
			(net "PHY_IOC_TO_SCC_C_42_DP")
			(clearance 0.2032)
			(thermal_gap 0.2032)
		)
		(pad "3" thru_hole circle
			(at 0.5715 0 90)
			(size 0.508 0.508)
			(drill 0.254)
			(layers "*.Cu" "*.Mask")
			(remove_unused_layers no)
			(net "PHY_IOC_TO_SCC_C_42_DN")
			(clearance 0.2032)
			(thermal_gap 0.2032)
		)
		(pad "4" thru_hole circle
			(at 1.5875 0 90)
			(size 0.508 0.508)
			(drill 0.254)
			(layers "*.Cu" "*.Mask")
			(remove_unused_layers no)
			(net "GND")
			(clearance 0.2032)
			(thermal_gap 0.2032)
		)
	)
	(footprint ""
		(layer "F.Cu")
		(at 192.951354 -67.337178 180)
		(property "Reference" "R297"
			(at 0 0 180)
			(layer "F.SilkS")
			(hide yes)
			(effects
				(font
					(size 1.27 1.27)
				)
			)
		)
		(property "Value" "0R2J-2-GP"
			(at 0.064008 -3.993896 180)
			(unlocked yes)
			(layer "F.Fab")
			(hide yes)
			(effects
				(font
					(size 1.016 1.016)
					(thickness 0.1524)
				)
			)
		)
		(property "Device Type" "R402H16"
			(at 0.064008 -5.517896 180)
			(unlocked yes)
			(layer "F.Fab")
			(hide yes)
			(effects
				(font
					(size 1.016 1.016)
					(thickness 0.1524)
				)
			)
		)
		(duplicate_pad_numbers_are_jumpers no)
		(fp_line
			(start 0.508 -0.9398)
			(end -0.508 -0.9398)
			(stroke
				(width 0.1524)
				(type default)
			)
			(layer "F.SilkS")
		)
		(fp_line
			(start -0.508 -0.9398)
			(end -0.508 0.9398)
			(stroke
				(width 0.1524)
				(type default)
			)
			(layer "F.SilkS")
		)
		(fp_rect
			(start -0.508 0.9398)
			(end 0.508 -0.9398)
			(stroke
				(width 0)
				(type default)
			)
			(fill no)
			(layer "F.CrtYd")
		)
		(fp_rect
			(start -0.508 0.9398)
			(end 0.508 -0.9398)
			(stroke
				(width 0)
				(type default)
			)
			(fill no)
			(layer "F.Fab")
		)
		(pad "1" smd custom
			(at 0 -0.4445 180)
			(size 0.1397 0.1397)
			(layers "F.Cu" "F.Mask" "F.Paste")
			(net "UART_IOC_TX")
			(options
				(clearance outline)
				(anchor circle)
			)
			(primitives
				(gr_poly
					(pts
						(arc
							(start -0.1778 -0.2794)
							(mid -0.249642 -0.249642)
							(end -0.2794 -0.1778)
						)
						(arc
							(start -0.2794 0.1778)
							(mid -0.249642 0.249642)
							(end -0.1778 0.2794)
						)
						(arc
							(start 0.1778 0.2794)
							(mid 0.249642 0.249642)
							(end 0.2794 0.1778)
						)
						(arc
							(start 0.2794 -0.1778)
							(mid 0.249642 -0.249642)
							(end 0.1778 -0.2794)
						)
					)
					(width 0)
					(fill yes)
				)
			)
		)
		(pad "2" smd custom
			(at 0 0.4445 180)
			(size 0.1397 0.1397)
			(layers "F.Cu" "F.Mask" "F.Paste")
			(net "IOC_UART_R_TX")
			(options
				(clearance outline)
				(anchor circle)
			)
			(primitives
				(gr_poly
					(pts
						(arc
							(start -0.1778 -0.2794)
							(mid -0.249642 -0.249642)
							(end -0.2794 -0.1778)
						)
						(arc
							(start -0.2794 0.1778)
							(mid -0.249642 0.249642)
							(end -0.1778 0.2794)
						)
						(arc
							(start 0.1778 0.2794)
							(mid 0.249642 0.249642)
							(end 0.2794 0.1778)
						)
						(arc
							(start 0.2794 -0.1778)
							(mid 0.249642 -0.249642)
							(end 0.1778 -0.2794)
						)
					)
					(width 0)
					(fill yes)
				)
			)
		)
	)
	(footprint ""
		(layer "F.Cu")
		(at 51.308 -75.8952 90)
		(property "Reference" "R471"
			(at 0 0 90)
			(layer "F.SilkS")
			(hide yes)
			(effects
				(font
					(size 1.27 1.27)
				)
			)
		)
		(property "Value" "1KR2F-3-GP"
			(at 0.064008 -3.993896 90)
			(unlocked yes)
			(layer "F.Fab")
			(hide yes)
			(effects
				(font
					(size 1.016 1.016)
					(thickness 0.1524)
				)
			)
		)
		(property "Device Type" "R402H16"
			(at 0.064008 -5.517896 90)
			(unlocked yes)
			(layer "F.Fab")
			(hide yes)
			(effects
				(font
					(size 1.016 1.016)
					(thickness 0.1524)
				)
			)
		)
		(duplicate_pad_numbers_are_jumpers no)
		(fp_line
			(start 0.508 -0.9398)
			(end -0.508 -0.9398)
			(stroke
				(width 0.1524)
				(type default)
			)
			(layer "F.SilkS")
		)
		(fp_line
			(start -0.508 -0.9398)
			(end -0.508 0.9398)
			(stroke
				(width 0.1524)
				(type default)
			)
			(layer "F.SilkS")
		)
		(fp_rect
			(start -0.508 0.9398)
			(end 0.508 -0.9398)
			(stroke
				(width 0)
				(type default)
			)
			(fill no)
			(layer "F.CrtYd")
		)
		(fp_rect
			(start -0.508 0.9398)
			(end 0.508 -0.9398)
			(stroke
				(width 0)
				(type default)
			)
			(fill no)
			(layer "F.Fab")
		)
		(pad "1" smd custom
			(at 0 -0.4445 90)
			(size 0.1397 0.1397)
			(layers "F.Cu" "F.Mask" "F.Paste")
			(net "P3V3")
			(options
				(clearance outline)
				(anchor circle)
			)
			(primitives
				(gr_poly
					(pts
						(arc
							(start -0.1778 -0.2794)
							(mid -0.249642 -0.249642)
							(end -0.2794 -0.1778)
						)
						(arc
							(start -0.2794 0.1778)
							(mid -0.249642 0.249642)
							(end -0.1778 0.2794)
						)
						(arc
							(start 0.1778 0.2794)
							(mid 0.249642 0.249642)
							(end 0.2794 0.1778)
						)
						(arc
							(start 0.2794 -0.1778)
							(mid 0.249642 -0.249642)
							(end 0.1778 -0.2794)
						)
					)
					(width 0)
					(fill yes)
				)
			)
		)
		(pad "2" smd custom
			(at 0 0.4445 90)
			(size 0.1397 0.1397)
			(layers "F.Cu" "F.Mask" "F.Paste")
			(net "I2C_CLIP_SDA7")
			(options
				(clearance outline)
				(anchor circle)
			)
			(primitives
				(gr_poly
					(pts
						(arc
							(start -0.1778 -0.2794)
							(mid -0.249642 -0.249642)
							(end -0.2794 -0.1778)
						)
						(arc
							(start -0.2794 0.1778)
							(mid -0.249642 0.249642)
							(end -0.1778 0.2794)
						)
						(arc
							(start 0.1778 0.2794)
							(mid 0.249642 0.249642)
							(end 0.2794 0.1778)
						)
						(arc
							(start 0.2794 -0.1778)
							(mid 0.249642 -0.249642)
							(end 0.1778 -0.2794)
						)
					)
					(width 0)
					(fill yes)
				)
			)
		)
	)
	(footprint ""
		(layer "F.Cu")
		(at 158.496 -41.275 90)
		(property "Reference" "R177"
			(at 0 0 90)
			(layer "F.SilkS")
			(hide yes)
			(effects
				(font
					(size 1.27 1.27)
				)
			)
		)
		(property "Value" "0R2J-2-GP"
			(at 0.064008 -3.993896 90)
			(unlocked yes)
			(layer "F.Fab")
			(hide yes)
			(effects
				(font
					(size 1.016 1.016)
					(thickness 0.1524)
				)
			)
		)
		(property "Device Type" "R402H16"
			(at 0.064008 -5.517896 90)
			(unlocked yes)
			(layer "F.Fab")
			(hide yes)
			(effects
				(font
					(size 1.016 1.016)
					(thickness 0.1524)
				)
			)
		)
		(duplicate_pad_numbers_are_jumpers no)
		(fp_line
			(start 0.508 -0.9398)
			(end -0.508 -0.9398)
			(stroke
				(width 0.1524)
				(type default)
			)
			(layer "F.SilkS")
		)
		(fp_line
			(start -0.508 -0.9398)
			(end -0.508 0.9398)
			(stroke
				(width 0.1524)
				(type default)
			)
			(layer "F.SilkS")
		)
		(fp_rect
			(start -0.508 0.9398)
			(end 0.508 -0.9398)
			(stroke
				(width 0)
				(type default)
			)
			(fill no)
			(layer "F.CrtYd")
		)
		(fp_rect
			(start -0.508 0.9398)
			(end 0.508 -0.9398)
			(stroke
				(width 0)
				(type default)
			)
			(fill no)
			(layer "F.Fab")
		)
		(pad "1" smd custom
			(at 0 -0.4445 90)
			(size 0.1397 0.1397)
			(layers "F.Cu" "F.Mask" "F.Paste")
			(net "REF_CLK")
			(options
				(clearance outline)
				(anchor circle)
			)
			(primitives
				(gr_poly
					(pts
						(arc
							(start -0.1778 -0.2794)
							(mid -0.249642 -0.249642)
							(end -0.2794 -0.1778)
						)
						(arc
							(start -0.2794 0.1778)
							(mid -0.249642 0.249642)
							(end -0.1778 0.2794)
						)
						(arc
							(start 0.1778 0.2794)
							(mid 0.249642 0.249642)
							(end 0.2794 0.1778)
						)
						(arc
							(start 0.2794 -0.1778)
							(mid 0.249642 -0.249642)
							(end 0.1778 -0.2794)
						)
					)
					(width 0)
					(fill yes)
				)
			)
		)
		(pad "2" smd custom
			(at 0 0.4445 90)
			(size 0.1397 0.1397)
			(layers "F.Cu" "F.Mask" "F.Paste")
			(net "IOC_REF_CLK_N")
			(options
				(clearance outline)
				(anchor circle)
			)
			(primitives
				(gr_poly
					(pts
						(arc
							(start -0.1778 -0.2794)
							(mid -0.249642 -0.249642)
							(end -0.2794 -0.1778)
						)
						(arc
							(start -0.2794 0.1778)
							(mid -0.249642 0.249642)
							(end -0.1778 0.2794)
						)
						(arc
							(start 0.1778 0.2794)
							(mid 0.249642 0.249642)
							(end 0.2794 0.1778)
						)
						(arc
							(start 0.2794 -0.1778)
							(mid 0.249642 -0.249642)
							(end 0.1778 -0.2794)
						)
					)
					(width 0)
					(fill yes)
				)
			)
		)
	)
	(footprint ""
		(layer "F.Cu")
		(at 148.509736 -44.828714 102)
		(property "Reference" "C337"
			(at 0 0 102)
			(layer "F.SilkS")
			(hide yes)
			(effects
				(font
					(size 1.27 1.27)
				)
			)
		)
		(property "Value" "SCD01U16V1KX-GP"
			(at -2.832048 -1.739777 102)
			(unlocked yes)
			(layer "F.Fab")
			(hide yes)
			(effects
				(font
					(size 1.016 1.016)
					(thickness 0.1524)
				)
			)
		)
		(property "Device Type" "C0201H13"
			(at -2.832174 -3.263834 102)
			(unlocked yes)
			(layer "F.Fab")
			(hide yes)
			(effects
				(font
					(size 1.016 1.016)
					(thickness 0.1524)
				)
			)
		)
		(duplicate_pad_numbers_are_jumpers no)
		(fp_poly
			(pts
				(xy -0.279454 -0.647706) (xy 0.279346 -0.647706) (xy 0.279346 0.647694) (xy -0.279454 0.647694)
			)
			(stroke
				(width 0)
				(type default)
			)
			(fill no)
			(layer "F.CrtYd")
		)
		(fp_poly
			(pts
				(xy -0.279454 -0.647706) (xy 0.279346 -0.647706) (xy 0.279346 0.647694) (xy -0.279454 0.647694)
			)
			(stroke
				(width 0)
				(type default)
			)
			(fill no)
			(layer "F.Fab")
		)
		(pad "1" smd custom
			(at -0.000001 -0.2794 102)
			(size 0.0762 0.0762)
			(layers "F.Cu" "F.Mask" "F.Paste")
			(net "PHY_SCC_TO_IOC_44_DP")
			(options
				(clearance outline)
				(anchor circle)
			)
			(primitives
				(gr_poly
					(pts
						(arc
							(start 0.1524 -0.127)
							(mid 0.137521 -0.162921)
							(end 0.1016 -0.1778)
						)
						(arc
							(start -0.1016 -0.1778)
							(mid -0.137521 -0.162921)
							(end -0.1524 -0.127)
						)
						(arc
							(start -0.1524 0.127)
							(mid -0.137521 0.162921)
							(end -0.1016 0.1778)
						)
						(arc
							(start 0.1016 0.1778)
							(mid 0.137521 0.162921)
							(end 0.1524 0.127)
						)
					)
					(width 0)
					(fill yes)
				)
			)
		)
		(pad "2" smd custom
			(at 0.000001 0.2794 102)
			(size 0.0762 0.0762)
			(layers "F.Cu" "F.Mask" "F.Paste")
			(net "PHY_SCC_TO_IOC_C_44_DP")
			(options
				(clearance outline)
				(anchor circle)
			)
			(primitives
				(gr_poly
					(pts
						(arc
							(start 0.1524 -0.127)
							(mid 0.137521 -0.162921)
							(end 0.1016 -0.1778)
						)
						(arc
							(start -0.1016 -0.1778)
							(mid -0.137521 -0.162921)
							(end -0.1524 -0.127)
						)
						(arc
							(start -0.1524 0.127)
							(mid -0.137521 0.162921)
							(end -0.1016 0.1778)
						)
						(arc
							(start 0.1016 0.1778)
							(mid 0.137521 0.162921)
							(end 0.1524 0.127)
						)
					)
					(width 0)
					(fill yes)
				)
			)
		)
	)
	(footprint ""
		(layer "F.Cu")
		(at 160.274 -76.934314 90)
		(property "Reference" "C520"
			(at 0 0 90)
			(layer "F.SilkS")
			(hide yes)
			(effects
				(font
					(size 1.27 1.27)
				)
			)
		)
		(property "Value" "SC1U16V2KX-7-GP"
			(at 1.7526 -1.6002 90)
			(unlocked yes)
			(layer "F.Fab")
			(hide yes)
			(effects
				(font
					(size 1.016 1.016)
					(thickness 0.1524)
				)
			)
		)
		(property "Device Type" "C402-TO0D2H24"
			(at 1.7526 -3.1242 90)
			(unlocked yes)
			(layer "F.Fab")
			(hide yes)
			(effects
				(font
					(size 1.016 1.016)
					(thickness 0.1524)
				)
			)
		)
		(duplicate_pad_numbers_are_jumpers no)
		(fp_rect
			(start -0.4826 0.889)
			(end 0.4826 -0.889)
			(stroke
				(width 0)
				(type default)
			)
			(fill no)
			(layer "F.CrtYd")
		)
		(fp_rect
			(start -0.4826 0.889)
			(end 0.4826 -0.889)
			(stroke
				(width 0)
				(type default)
			)
			(fill no)
			(layer "F.Fab")
		)
		(pad "1" smd custom
			(at 0 -0.4572 90)
			(size 0.1524 0.1524)
			(layers "F.Cu" "F.Mask" "F.Paste")
			(net "P3V3")
			(options
				(clearance outline)
				(anchor circle)
			)
			(primitives
				(gr_poly
					(pts
						(arc
							(start -0.254 0.3048)
							(mid -0.325842 0.275042)
							(end -0.3556 0.2032)
						)
						(arc
							(start -0.3556 -0.2032)
							(mid -0.325842 -0.275042)
							(end -0.254 -0.3048)
						)
						(arc
							(start 0.254 -0.3048)
							(mid 0.325842 -0.275042)
							(end 0.3556 -0.2032)
						)
						(arc
							(start 0.3556 0.2032)
							(mid 0.325842 0.275042)
							(end 0.254 0.3048)
						)
					)
					(width 0)
					(fill yes)
				)
			)
		)
		(pad "2" smd custom
			(at 0 0.4572 90)
			(size 0.1524 0.1524)
			(layers "F.Cu" "F.Mask" "F.Paste")
			(net "GND")
			(options
				(clearance outline)
				(anchor circle)
			)
			(primitives
				(gr_poly
					(pts
						(arc
							(start -0.254 0.3048)
							(mid -0.325842 0.275042)
							(end -0.3556 0.2032)
						)
						(arc
							(start -0.3556 -0.2032)
							(mid -0.325842 -0.275042)
							(end -0.254 -0.3048)
						)
						(arc
							(start 0.254 -0.3048)
							(mid 0.325842 -0.275042)
							(end 0.3556 -0.2032)
						)
						(arc
							(start 0.3556 0.2032)
							(mid 0.325842 0.275042)
							(end 0.254 0.3048)
						)
					)
					(width 0)
					(fill yes)
				)
			)
		)
	)
	(footprint ""
		(layer "F.Cu")
		(at 184.413906 -21.57857)
		(property "Reference" "TP133"
			(at 0 0 0)
			(layer "F.SilkS")
			(hide yes)
			(effects
				(font
					(size 1.27 1.27)
				)
			)
		)
		(property "Value" "TPAD28-2-GP"
			(at -0.0127 -1.6637 0)
			(unlocked yes)
			(layer "F.Fab")
			(hide yes)
			(effects
				(font
					(size 1.016 1.016)
					(thickness 0.1524)
				)
			)
		)
		(property "Device Type" "TPAD28"
			(at -0.0127 -3.1877 0)
			(unlocked yes)
			(layer "F.Fab")
			(hide yes)
			(effects
				(font
					(size 1.016 1.016)
					(thickness 0.1524)
				)
			)
		)
		(duplicate_pad_numbers_are_jumpers no)
		(fp_poly
			(pts
				(arc
					(start 0.3556 0)
					(mid -0.3556 0)
					(end 0.3556 0)
				)
			)
			(stroke
				(width 0)
				(type default)
			)
			(fill no)
			(layer "F.CrtYd")
		)
		(fp_poly
			(pts
				(arc
					(start 0.6096 0)
					(mid -0.6096 0)
					(end 0.6096 0)
				)
			)
			(stroke
				(width 0)
				(type default)
			)
			(fill no)
			(layer "F.Fab")
		)
		(pad "1" smd circle
			(at 0 0)
			(size 0.7112 0.7112)
			(layers "F.Cu" "F.Mask" "F.Paste")
			(net "SYS_DBMODE1")
		)
	)
	(footprint ""
		(layer "F.Cu")
		(at 120.8786 -89.1032 90)
		(property "Reference" "R33"
			(at 0 0 90)
			(layer "F.SilkS")
			(hide yes)
			(effects
				(font
					(size 1.27 1.27)
				)
			)
		)
		(property "Value" "4K7R2F-GP"
			(at 0.064008 -3.993896 90)
			(unlocked yes)
			(layer "F.Fab")
			(hide yes)
			(effects
				(font
					(size 1.016 1.016)
					(thickness 0.1524)
				)
			)
		)
		(property "Device Type" "R402H16"
			(at 0.064008 -5.517896 90)
			(unlocked yes)
			(layer "F.Fab")
			(hide yes)
			(effects
				(font
					(size 1.016 1.016)
					(thickness 0.1524)
				)
			)
		)
		(duplicate_pad_numbers_are_jumpers no)
		(fp_line
			(start 0.508 -0.9398)
			(end -0.508 -0.9398)
			(stroke
				(width 0.1524)
				(type default)
			)
			(layer "F.SilkS")
		)
		(fp_line
			(start -0.508 -0.9398)
			(end -0.508 0.9398)
			(stroke
				(width 0.1524)
				(type default)
			)
			(layer "F.SilkS")
		)
		(fp_rect
			(start -0.508 0.9398)
			(end 0.508 -0.9398)
			(stroke
				(width 0)
				(type default)
			)
			(fill no)
			(layer "F.CrtYd")
		)
		(fp_rect
			(start -0.508 0.9398)
			(end 0.508 -0.9398)
			(stroke
				(width 0)
				(type default)
			)
			(fill no)
			(layer "F.Fab")
		)
		(pad "1" smd custom
			(at 0 -0.4445 90)
			(size 0.1397 0.1397)
			(layers "F.Cu" "F.Mask" "F.Paste")
			(net "P1V8_E")
			(options
				(clearance outline)
				(anchor circle)
			)
			(primitives
				(gr_poly
					(pts
						(arc
							(start -0.1778 -0.2794)
							(mid -0.249642 -0.249642)
							(end -0.2794 -0.1778)
						)
						(arc
							(start -0.2794 0.1778)
							(mid -0.249642 0.249642)
							(end -0.1778 0.2794)
						)
						(arc
							(start 0.1778 0.2794)
							(mid 0.249642 0.249642)
							(end 0.2794 0.1778)
						)
						(arc
							(start 0.2794 -0.1778)
							(mid 0.249642 -0.249642)
							(end 0.1778 -0.2794)
						)
					)
					(width 0)
					(fill yes)
				)
			)
		)
		(pad "2" smd custom
			(at 0 0.4445 90)
			(size 0.1397 0.1397)
			(layers "F.Cu" "F.Mask" "F.Paste")
			(net "EXP_GPIO13")
			(options
				(clearance outline)
				(anchor circle)
			)
			(primitives
				(gr_poly
					(pts
						(arc
							(start -0.1778 -0.2794)
							(mid -0.249642 -0.249642)
							(end -0.2794 -0.1778)
						)
						(arc
							(start -0.2794 0.1778)
							(mid -0.249642 0.249642)
							(end -0.1778 0.2794)
						)
						(arc
							(start 0.1778 0.2794)
							(mid 0.249642 0.249642)
							(end 0.2794 0.1778)
						)
						(arc
							(start 0.2794 -0.1778)
							(mid 0.249642 -0.249642)
							(end 0.1778 -0.2794)
						)
					)
					(width 0)
					(fill yes)
				)
			)
		)
	)
	(footprint ""
		(layer "F.Cu")
		(at 6.5278 -101.0158)
		(property "Reference" "R534"
			(at 0 0 0)
			(layer "F.SilkS")
			(hide yes)
			(effects
				(font
					(size 1.27 1.27)
				)
			)
		)
		(property "Value" "0R2J-2-GP"
			(at 0.064008 -3.993896 0)
			(unlocked yes)
			(layer "F.Fab")
			(hide yes)
			(effects
				(font
					(size 1.016 1.016)
					(thickness 0.1524)
				)
			)
		)
		(property "Device Type" "R402H16"
			(at 0.064008 -5.517896 0)
			(unlocked yes)
			(layer "F.Fab")
			(hide yes)
			(effects
				(font
					(size 1.016 1.016)
					(thickness 0.1524)
				)
			)
		)
		(duplicate_pad_numbers_are_jumpers no)
		(fp_line
			(start -0.508 -0.9398)
			(end -0.508 0.9398)
			(stroke
				(width 0.1524)
				(type default)
			)
			(layer "F.SilkS")
		)
		(fp_line
			(start 0.508 -0.9398)
			(end -0.508 -0.9398)
			(stroke
				(width 0.1524)
				(type default)
			)
			(layer "F.SilkS")
		)
		(fp_rect
			(start -0.508 0.9398)
			(end 0.508 -0.9398)
			(stroke
				(width 0)
				(type default)
			)
			(fill no)
			(layer "F.CrtYd")
		)
		(fp_rect
			(start -0.508 0.9398)
			(end 0.508 -0.9398)
			(stroke
				(width 0)
				(type default)
			)
			(fill no)
			(layer "F.Fab")
		)
		(pad "1" smd custom
			(at 0 -0.4445)
			(size 0.1397 0.1397)
			(layers "F.Cu" "F.Mask" "F.Paste")
			(net "SCC_FULL_PGOOD")
			(options
				(clearance outline)
				(anchor circle)
			)
			(primitives
				(gr_poly
					(pts
						(arc
							(start -0.1778 -0.2794)
							(mid -0.249642 -0.249642)
							(end -0.2794 -0.1778)
						)
						(arc
							(start -0.2794 0.1778)
							(mid -0.249642 0.249642)
							(end -0.1778 0.2794)
						)
						(arc
							(start 0.1778 0.2794)
							(mid 0.249642 0.249642)
							(end 0.2794 0.1778)
						)
						(arc
							(start 0.2794 -0.1778)
							(mid 0.249642 -0.249642)
							(end 0.1778 -0.2794)
						)
					)
					(width 0)
					(fill yes)
				)
			)
		)
		(pad "2" smd custom
			(at 0 0.4445)
			(size 0.1397 0.1397)
			(layers "F.Cu" "F.Mask" "F.Paste")
			(net "SCC_FULL_PGOOD_BUF_R")
			(options
				(clearance outline)
				(anchor circle)
			)
			(primitives
				(gr_poly
					(pts
						(arc
							(start -0.1778 -0.2794)
							(mid -0.249642 -0.249642)
							(end -0.2794 -0.1778)
						)
						(arc
							(start -0.2794 0.1778)
							(mid -0.249642 0.249642)
							(end -0.1778 0.2794)
						)
						(arc
							(start 0.1778 0.2794)
							(mid 0.249642 0.249642)
							(end 0.2794 0.1778)
						)
						(arc
							(start 0.2794 -0.1778)
							(mid 0.249642 -0.249642)
							(end 0.1778 -0.2794)
						)
					)
					(width 0)
					(fill yes)
				)
			)
		)
	)
	(footprint ""
		(layer "F.Cu")
		(at 188.84392 -110.20806)
		(property "Reference" "R538"
			(at 0 0 0)
			(layer "F.SilkS")
			(hide yes)
			(effects
				(font
					(size 1.27 1.27)
				)
			)
		)
		(property "Value" "0R2J-2-GP"
			(at 0.064008 -3.993896 0)
			(unlocked yes)
			(layer "F.Fab")
			(hide yes)
			(effects
				(font
					(size 1.016 1.016)
					(thickness 0.1524)
				)
			)
		)
		(property "Device Type" "R402H16"
			(at 0.064008 -5.517896 0)
			(unlocked yes)
			(layer "F.Fab")
			(hide yes)
			(effects
				(font
					(size 1.016 1.016)
					(thickness 0.1524)
				)
			)
		)
		(duplicate_pad_numbers_are_jumpers no)
		(fp_line
			(start -0.508 -0.9398)
			(end -0.508 0.9398)
			(stroke
				(width 0.1524)
				(type default)
			)
			(layer "F.SilkS")
		)
		(fp_line
			(start 0.508 -0.9398)
			(end -0.508 -0.9398)
			(stroke
				(width 0.1524)
				(type default)
			)
			(layer "F.SilkS")
		)
		(fp_rect
			(start -0.508 0.9398)
			(end 0.508 -0.9398)
			(stroke
				(width 0)
				(type default)
			)
			(fill no)
			(layer "F.CrtYd")
		)
		(fp_rect
			(start -0.508 0.9398)
			(end 0.508 -0.9398)
			(stroke
				(width 0)
				(type default)
			)
			(fill no)
			(layer "F.Fab")
		)
		(pad "1" smd custom
			(at 0 -0.4445)
			(size 0.1397 0.1397)
			(layers "F.Cu" "F.Mask" "F.Paste")
			(net "P0V9_PG")
			(options
				(clearance outline)
				(anchor circle)
			)
			(primitives
				(gr_poly
					(pts
						(arc
							(start -0.1778 -0.2794)
							(mid -0.249642 -0.249642)
							(end -0.2794 -0.1778)
						)
						(arc
							(start -0.2794 0.1778)
							(mid -0.249642 0.249642)
							(end -0.1778 0.2794)
						)
						(arc
							(start 0.1778 0.2794)
							(mid 0.249642 0.249642)
							(end 0.2794 0.1778)
						)
						(arc
							(start 0.2794 -0.1778)
							(mid 0.249642 -0.249642)
							(end 0.1778 -0.2794)
						)
					)
					(width 0)
					(fill yes)
				)
			)
		)
		(pad "2" smd custom
			(at 0 0.4445)
			(size 0.1397 0.1397)
			(layers "F.Cu" "F.Mask" "F.Paste")
			(net "P1V8_C_S")
			(options
				(clearance outline)
				(anchor circle)
			)
			(primitives
				(gr_poly
					(pts
						(arc
							(start -0.1778 -0.2794)
							(mid -0.249642 -0.249642)
							(end -0.2794 -0.1778)
						)
						(arc
							(start -0.2794 0.1778)
							(mid -0.249642 0.249642)
							(end -0.1778 0.2794)
						)
						(arc
							(start 0.1778 0.2794)
							(mid 0.249642 0.249642)
							(end 0.2794 0.1778)
						)
						(arc
							(start 0.2794 -0.1778)
							(mid 0.249642 -0.249642)
							(end 0.1778 -0.2794)
						)
					)
					(width 0)
					(fill yes)
				)
			)
		)
	)
	(footprint ""
		(layer "F.Cu")
		(at 17.907 -59.1312)
		(property "Reference" "R579"
			(at 0 0 0)
			(layer "F.SilkS")
			(hide yes)
			(effects
				(font
					(size 1.27 1.27)
				)
			)
		)
		(property "Value" "0R2J-2-GP"
			(at 0.064008 -3.993896 0)
			(unlocked yes)
			(layer "F.Fab")
			(hide yes)
			(effects
				(font
					(size 1.016 1.016)
					(thickness 0.1524)
				)
			)
		)
		(property "Device Type" "R402H16"
			(at 0.064008 -5.517896 0)
			(unlocked yes)
			(layer "F.Fab")
			(hide yes)
			(effects
				(font
					(size 1.016 1.016)
					(thickness 0.1524)
				)
			)
		)
		(duplicate_pad_numbers_are_jumpers no)
		(fp_line
			(start -0.508 -0.9398)
			(end -0.508 0.9398)
			(stroke
				(width 0.1524)
				(type default)
			)
			(layer "F.SilkS")
		)
		(fp_line
			(start 0.508 -0.9398)
			(end -0.508 -0.9398)
			(stroke
				(width 0.1524)
				(type default)
			)
			(layer "F.SilkS")
		)
		(fp_rect
			(start -0.508 0.9398)
			(end 0.508 -0.9398)
			(stroke
				(width 0)
				(type default)
			)
			(fill no)
			(layer "F.CrtYd")
		)
		(fp_rect
			(start -0.508 0.9398)
			(end 0.508 -0.9398)
			(stroke
				(width 0)
				(type default)
			)
			(fill no)
			(layer "F.Fab")
		)
		(pad "1" smd custom
			(at 0 -0.4445)
			(size 0.1397 0.1397)
			(layers "F.Cu" "F.Mask" "F.Paste")
			(net "AGND_CURRENT_MON")
			(options
				(clearance outline)
				(anchor circle)
			)
			(primitives
				(gr_poly
					(pts
						(arc
							(start -0.1778 -0.2794)
							(mid -0.249642 -0.249642)
							(end -0.2794 -0.1778)
						)
						(arc
							(start -0.2794 0.1778)
							(mid -0.249642 0.249642)
							(end -0.1778 0.2794)
						)
						(arc
							(start 0.1778 0.2794)
							(mid 0.249642 0.249642)
							(end 0.2794 0.1778)
						)
						(arc
							(start 0.2794 -0.1778)
							(mid 0.249642 -0.249642)
							(end 0.1778 -0.2794)
						)
					)
					(width 0)
					(fill yes)
				)
			)
		)
		(pad "2" smd custom
			(at 0 0.4445)
			(size 0.1397 0.1397)
			(layers "F.Cu" "F.Mask" "F.Paste")
			(net "MB0_CM_ADR2_R")
			(options
				(clearance outline)
				(anchor circle)
			)
			(primitives
				(gr_poly
					(pts
						(arc
							(start -0.1778 -0.2794)
							(mid -0.249642 -0.249642)
							(end -0.2794 -0.1778)
						)
						(arc
							(start -0.2794 0.1778)
							(mid -0.249642 0.249642)
							(end -0.1778 0.2794)
						)
						(arc
							(start 0.1778 0.2794)
							(mid 0.249642 0.249642)
							(end 0.2794 0.1778)
						)
						(arc
							(start 0.2794 -0.1778)
							(mid 0.249642 -0.249642)
							(end 0.1778 -0.2794)
						)
					)
					(width 0)
					(fill yes)
				)
			)
		)
	)
	(footprint ""
		(layer "F.Cu")
		(at 181.580282 -102.365556 90)
		(property "Reference" "C394"
			(at 0 0 90)
			(layer "F.SilkS")
			(hide yes)
			(effects
				(font
					(size 1.27 1.27)
				)
			)
		)
		(property "Value" "SC100U6D3V6MX-GP"
			(at -0.0762 -5.1308 90)
			(unlocked yes)
			(layer "F.Fab")
			(hide yes)
			(effects
				(font
					(size 1.016 1.016)
					(thickness 0.1524)
				)
			)
		)
		(property "Device Type" "C1206H71"
			(at -0.127 -6.6548 90)
			(unlocked yes)
			(layer "F.Fab")
			(hide yes)
			(effects
				(font
					(size 1.016 1.016)
					(thickness 0.1524)
				)
			)
		)
		(duplicate_pad_numbers_are_jumpers no)
		(fp_line
			(start 1.016 -2.2352)
			(end 1.016 -0.8382)
			(stroke
				(width 0.1524)
				(type default)
			)
			(layer "F.SilkS")
		)
		(fp_line
			(start -1.016 -2.2352)
			(end 1.016 -2.2352)
			(stroke
				(width 0.1524)
				(type default)
			)
			(layer "F.SilkS")
		)
		(fp_line
			(start -1.016 -0.8382)
			(end -1.016 -2.2352)
			(stroke
				(width 0.1524)
				(type default)
			)
			(layer "F.SilkS")
		)
		(fp_line
			(start 1.016 0.8382)
			(end 1.016 2.2352)
			(stroke
				(width 0.1524)
				(type default)
			)
			(layer "F.SilkS")
		)
		(fp_line
			(start 1.016 2.2352)
			(end -1.016 2.2352)
			(stroke
				(width 0.1524)
				(type default)
			)
			(layer "F.SilkS")
		)
		(fp_line
			(start -1.016 2.2352)
			(end -1.016 0.8382)
			(stroke
				(width 0.1524)
				(type default)
			)
			(layer "F.SilkS")
		)
		(fp_rect
			(start -1.0922 2.3114)
			(end 1.0922 -2.3114)
			(stroke
				(width 0)
				(type default)
			)
			(fill no)
			(layer "F.CrtYd")
		)
		(fp_poly
			(pts
				(xy 1.0922 -2.3114) (xy 1.0922 2.3114) (xy -1.0922 2.3114) (xy -1.0922 -2.3114)
			)
			(stroke
				(width 0)
				(type default)
			)
			(fill no)
			(layer "F.Fab")
		)
		(pad "1" smd rect
			(at 0 -1.397 90)
			(size 1.651 1.27)
			(layers "F.Cu" "F.Mask" "F.Paste")
			(net "GND")
		)
		(pad "2" smd rect
			(at 0 1.397 90)
			(size 1.651 1.27)
			(layers "F.Cu" "F.Mask" "F.Paste")
			(net "SAS0_AVDD")
		)
	)
	(footprint ""
		(layer "F.Cu")
		(at 7.0866 -56.769 90)
		(property "Reference" "R487"
			(at 0 0 90)
			(layer "F.SilkS")
			(hide yes)
			(effects
				(font
					(size 1.27 1.27)
				)
			)
		)
		(property "Value" "10KR2F-2-GP"
			(at 0.064008 -3.993896 90)
			(unlocked yes)
			(layer "F.Fab")
			(hide yes)
			(effects
				(font
					(size 1.016 1.016)
					(thickness 0.1524)
				)
			)
		)
		(property "Device Type" "R402H16"
			(at 0.064008 -5.517896 90)
			(unlocked yes)
			(layer "F.Fab")
			(hide yes)
			(effects
				(font
					(size 1.016 1.016)
					(thickness 0.1524)
				)
			)
		)
		(duplicate_pad_numbers_are_jumpers no)
		(fp_line
			(start 0.508 -0.9398)
			(end -0.508 -0.9398)
			(stroke
				(width 0.1524)
				(type default)
			)
			(layer "F.SilkS")
		)
		(fp_line
			(start -0.508 -0.9398)
			(end -0.508 0.9398)
			(stroke
				(width 0.1524)
				(type default)
			)
			(layer "F.SilkS")
		)
		(fp_rect
			(start -0.508 0.9398)
			(end 0.508 -0.9398)
			(stroke
				(width 0)
				(type default)
			)
			(fill no)
			(layer "F.CrtYd")
		)
		(fp_rect
			(start -0.508 0.9398)
			(end 0.508 -0.9398)
			(stroke
				(width 0)
				(type default)
			)
			(fill no)
			(layer "F.Fab")
		)
		(pad "1" smd custom
			(at 0 -0.4445 90)
			(size 0.1397 0.1397)
			(layers "F.Cu" "F.Mask" "F.Paste")
			(net "GND")
			(options
				(clearance outline)
				(anchor circle)
			)
			(primitives
				(gr_poly
					(pts
						(arc
							(start -0.1778 -0.2794)
							(mid -0.249642 -0.249642)
							(end -0.2794 -0.1778)
						)
						(arc
							(start -0.2794 0.1778)
							(mid -0.249642 0.249642)
							(end -0.1778 0.2794)
						)
						(arc
							(start 0.1778 0.2794)
							(mid 0.249642 0.249642)
							(end 0.2794 0.1778)
						)
						(arc
							(start 0.2794 -0.1778)
							(mid 0.249642 -0.249642)
							(end 0.1778 -0.2794)
						)
					)
					(width 0)
					(fill yes)
				)
			)
		)
		(pad "2" smd custom
			(at 0 0.4445 90)
			(size 0.1397 0.1397)
			(layers "F.Cu" "F.Mask" "F.Paste")
			(net "P12V_SCC_PGOOD")
			(options
				(clearance outline)
				(anchor circle)
			)
			(primitives
				(gr_poly
					(pts
						(arc
							(start -0.1778 -0.2794)
							(mid -0.249642 -0.249642)
							(end -0.2794 -0.1778)
						)
						(arc
							(start -0.2794 0.1778)
							(mid -0.249642 0.249642)
							(end -0.1778 0.2794)
						)
						(arc
							(start 0.1778 0.2794)
							(mid 0.249642 0.249642)
							(end 0.2794 0.1778)
						)
						(arc
							(start 0.2794 -0.1778)
							(mid 0.249642 -0.249642)
							(end 0.1778 -0.2794)
						)
					)
					(width 0)
					(fill yes)
				)
			)
		)
	)
	(footprint ""
		(layer "F.Cu")
		(at 169.336974 -101.646482 90)
		(property "Reference" "R493"
			(at 0 0 90)
			(layer "F.SilkS")
			(hide yes)
			(effects
				(font
					(size 1.27 1.27)
				)
			)
		)
		(property "Value" "453R2F-1-GP"
			(at 0.064008 -3.993896 90)
			(unlocked yes)
			(layer "F.Fab")
			(hide yes)
			(effects
				(font
					(size 1.016 1.016)
					(thickness 0.1524)
				)
			)
		)
		(property "Device Type" "R402H16"
			(at 0.064008 -5.517896 90)
			(unlocked yes)
			(layer "F.Fab")
			(hide yes)
			(effects
				(font
					(size 1.016 1.016)
					(thickness 0.1524)
				)
			)
		)
		(duplicate_pad_numbers_are_jumpers no)
		(fp_line
			(start 0.508 -0.9398)
			(end -0.508 -0.9398)
			(stroke
				(width 0.1524)
				(type default)
			)
			(layer "F.SilkS")
		)
		(fp_line
			(start -0.508 -0.9398)
			(end -0.508 0.9398)
			(stroke
				(width 0.1524)
				(type default)
			)
			(layer "F.SilkS")
		)
		(fp_rect
			(start -0.508 0.9398)
			(end 0.508 -0.9398)
			(stroke
				(width 0)
				(type default)
			)
			(fill no)
			(layer "F.CrtYd")
		)
		(fp_rect
			(start -0.508 0.9398)
			(end 0.508 -0.9398)
			(stroke
				(width 0)
				(type default)
			)
			(fill no)
			(layer "F.Fab")
		)
		(pad "1" smd custom
			(at 0 -0.4445 90)
			(size 0.1397 0.1397)
			(layers "F.Cu" "F.Mask" "F.Paste")
			(net "VT235_VDES_RR")
			(options
				(clearance outline)
				(anchor circle)
			)
			(primitives
				(gr_poly
					(pts
						(arc
							(start -0.1778 -0.2794)
							(mid -0.249642 -0.249642)
							(end -0.2794 -0.1778)
						)
						(arc
							(start -0.2794 0.1778)
							(mid -0.249642 0.249642)
							(end -0.1778 0.2794)
						)
						(arc
							(start 0.1778 0.2794)
							(mid 0.249642 0.249642)
							(end 0.2794 0.1778)
						)
						(arc
							(start 0.2794 -0.1778)
							(mid 0.249642 -0.249642)
							(end 0.1778 -0.2794)
						)
					)
					(width 0)
					(fill yes)
				)
			)
		)
		(pad "2" smd custom
			(at 0 0.4445 90)
			(size 0.1397 0.1397)
			(layers "F.Cu" "F.Mask" "F.Paste")
			(net "VT235_VDES_RCC")
			(options
				(clearance outline)
				(anchor circle)
			)
			(primitives
				(gr_poly
					(pts
						(arc
							(start -0.1778 -0.2794)
							(mid -0.249642 -0.249642)
							(end -0.2794 -0.1778)
						)
						(arc
							(start -0.2794 0.1778)
							(mid -0.249642 0.249642)
							(end -0.1778 0.2794)
						)
						(arc
							(start 0.1778 0.2794)
							(mid 0.249642 0.249642)
							(end 0.2794 0.1778)
						)
						(arc
							(start 0.2794 -0.1778)
							(mid 0.249642 -0.249642)
							(end 0.1778 -0.2794)
						)
					)
					(width 0)
					(fill yes)
				)
			)
		)
	)
	(footprint ""
		(layer "F.Cu")
		(at 7.2898 -73.0758 -90)
		(property "Reference" "R363"
			(at 0 0 270)
			(layer "F.SilkS")
			(hide yes)
			(effects
				(font
					(size 1.27 1.27)
				)
			)
		)
		(property "Value" "4K7R2F-GP"
			(at 0.064008 -3.993896 270)
			(unlocked yes)
			(layer "F.Fab")
			(hide yes)
			(effects
				(font
					(size 1.016 1.016)
					(thickness 0.1524)
				)
			)
		)
		(property "Device Type" "R402H16"
			(at 0.064008 -5.517896 270)
			(unlocked yes)
			(layer "F.Fab")
			(hide yes)
			(effects
				(font
					(size 1.016 1.016)
					(thickness 0.1524)
				)
			)
		)
		(duplicate_pad_numbers_are_jumpers no)
		(fp_line
			(start -0.508 -0.9398)
			(end -0.508 0.9398)
			(stroke
				(width 0.1524)
				(type default)
			)
			(layer "F.SilkS")
		)
		(fp_line
			(start 0.508 -0.9398)
			(end -0.508 -0.9398)
			(stroke
				(width 0.1524)
				(type default)
			)
			(layer "F.SilkS")
		)
		(fp_rect
			(start -0.508 0.9398)
			(end 0.508 -0.9398)
			(stroke
				(width 0)
				(type default)
			)
			(fill no)
			(layer "F.CrtYd")
		)
		(fp_rect
			(start -0.508 0.9398)
			(end 0.508 -0.9398)
			(stroke
				(width 0)
				(type default)
			)
			(fill no)
			(layer "F.Fab")
		)
		(pad "1" smd custom
			(at 0 -0.4445 270)
			(size 0.1397 0.1397)
			(layers "F.Cu" "F.Mask" "F.Paste")
			(net "FRU_EEPROM_A1")
			(options
				(clearance outline)
				(anchor circle)
			)
			(primitives
				(gr_poly
					(pts
						(arc
							(start -0.1778 -0.2794)
							(mid -0.249642 -0.249642)
							(end -0.2794 -0.1778)
						)
						(arc
							(start -0.2794 0.1778)
							(mid -0.249642 0.249642)
							(end -0.1778 0.2794)
						)
						(arc
							(start 0.1778 0.2794)
							(mid 0.249642 0.249642)
							(end 0.2794 0.1778)
						)
						(arc
							(start 0.2794 -0.1778)
							(mid 0.249642 -0.249642)
							(end 0.1778 -0.2794)
						)
					)
					(width 0)
					(fill yes)
				)
			)
		)
		(pad "2" smd custom
			(at 0 0.4445 270)
			(size 0.1397 0.1397)
			(layers "F.Cu" "F.Mask" "F.Paste")
			(net "GND")
			(options
				(clearance outline)
				(anchor circle)
			)
			(primitives
				(gr_poly
					(pts
						(arc
							(start -0.1778 -0.2794)
							(mid -0.249642 -0.249642)
							(end -0.2794 -0.1778)
						)
						(arc
							(start -0.2794 0.1778)
							(mid -0.249642 0.249642)
							(end -0.1778 0.2794)
						)
						(arc
							(start 0.1778 0.2794)
							(mid 0.249642 0.249642)
							(end 0.2794 0.1778)
						)
						(arc
							(start 0.2794 -0.1778)
							(mid 0.249642 -0.249642)
							(end 0.1778 -0.2794)
						)
					)
					(width 0)
					(fill yes)
				)
			)
		)
	)
	(footprint ""
		(layer "F.Cu")
		(at 19.05127 -89.104978)
		(property "Reference" "U35"
			(at 0 0 0)
			(layer "F.SilkS")
			(hide yes)
			(effects
				(font
					(size 1.27 1.27)
				)
			)
		)
		(property "Value" "PCA9306DCTR-GP"
			(at 0 -11.6332 0)
			(unlocked yes)
			(layer "F.Fab")
			(hide yes)
			(effects
				(font
					(size 1.016 1.016)
					(thickness 0.1524)
				)
			)
		)
		(property "Device Type" "SSOIC8H52"
			(at 0 -13.1572 0)
			(unlocked yes)
			(layer "F.Fab")
			(hide yes)
			(effects
				(font
					(size 1.016 1.016)
					(thickness 0.1524)
				)
			)
		)
		(duplicate_pad_numbers_are_jumpers no)
		(fp_line
			(start -1.7018 -0.5842)
			(end -1.7018 2.286)
			(stroke
				(width 0.1524)
				(type default)
			)
			(layer "F.SilkS")
		)
		(fp_line
			(start -1.7018 -0.5842)
			(end 1.0668 -0.5842)
			(stroke
				(width 0.1524)
				(type default)
			)
			(layer "F.SilkS")
		)
		(fp_line
			(start -1.524 0.5842)
			(end -1.524 2.286)
			(stroke
				(width 0.508)
				(type default)
			)
			(layer "F.SilkS")
		)
		(fp_line
			(start -1.397 0)
			(end -1.7018 -0.3048)
			(stroke
				(width 0.1524)
				(type default)
			)
			(layer "F.SilkS")
		)
		(fp_line
			(start -1.397 0)
			(end -1.7018 0.3048)
			(stroke
				(width 0.1524)
				(type default)
			)
			(layer "F.SilkS")
		)
		(fp_line
			(start 1.0668 -0.5842)
			(end 1.0668 0.5842)
			(stroke
				(width 0.1524)
				(type default)
			)
			(layer "F.SilkS")
		)
		(fp_line
			(start 1.0668 0.5842)
			(end -1.524 0.5842)
			(stroke
				(width 0.1524)
				(type default)
			)
			(layer "F.SilkS")
		)
		(fp_poly
			(pts
				(xy -1.1684 -0.5842) (xy 1.0668 -0.5842) (xy 1.0668 0.5842) (xy -1.1684 0.5842)
			)
			(stroke
				(width 0)
				(type default)
			)
			(fill yes)
			(layer "F.SilkS")
		)
		(fp_poly
			(pts
				(xy -1.778 2.54) (xy 1.778 2.54) (xy 1.778 -2.54) (xy -1.778 -2.54)
			)
			(stroke
				(width 0)
				(type default)
			)
			(fill no)
			(layer "F.CrtYd")
		)
		(fp_poly
			(pts
				(xy -1.778 -2.54) (xy 1.778 -2.54) (xy 1.778 2.54) (xy -1.778 2.54)
			)
			(stroke
				(width 0)
				(type default)
			)
			(fill no)
			(layer "F.Fab")
		)
		(pad "1" smd rect
			(at -0.97536 1.6256)
			(size 0.3556 1.524)
			(layers "F.Cu" "F.Mask" "F.Paste")
			(net "GND")
		)
		(pad "2" smd rect
			(at -0.32512 1.6256)
			(size 0.3556 1.524)
			(layers "F.Cu" "F.Mask" "F.Paste")
			(net "P1V8_E")
		)
		(pad "3" smd rect
			(at 0.32512 1.6256)
			(size 0.3556 1.524)
			(layers "F.Cu" "F.Mask" "F.Paste")
			(net "I2C_BMC_LOC_SCL0_LS")
		)
		(pad "4" smd rect
			(at 0.97536 1.6256)
			(size 0.3556 1.524)
			(layers "F.Cu" "F.Mask" "F.Paste")
			(net "I2C_BMC_LOC_SDA0_LS")
		)
		(pad "5" smd rect
			(at 0.97536 -1.6256)
			(size 0.3556 1.524)
			(layers "F.Cu" "F.Mask" "F.Paste")
			(net "I2C_BMC_LOC_SDA0")
		)
		(pad "6" smd rect
			(at 0.32512 -1.6256)
			(size 0.3556 1.524)
			(layers "F.Cu" "F.Mask" "F.Paste")
			(net "I2C_BMC_LOC_SCL0")
		)
		(pad "7" smd rect
			(at -0.32512 -1.6256)
			(size 0.3556 1.524)
			(layers "F.Cu" "F.Mask" "F.Paste")
			(net "VREF0")
		)
		(pad "8" smd rect
			(at -0.97536 -1.6256)
			(size 0.3556 1.524)
			(layers "F.Cu" "F.Mask" "F.Paste")
			(net "LS_EN_U35")
		)
	)
	(footprint ""
		(layer "F.Cu")
		(at 194.2846 -33.2232 -90)
		(property "Reference" "TP87"
			(at 0 0 270)
			(layer "F.SilkS")
			(hide yes)
			(effects
				(font
					(size 1.27 1.27)
				)
			)
		)
		(property "Value" "TPAD28-2-GP"
			(at -0.0127 -1.6637 270)
			(unlocked yes)
			(layer "F.Fab")
			(hide yes)
			(effects
				(font
					(size 1.016 1.016)
					(thickness 0.1524)
				)
			)
		)
		(property "Device Type" "TPAD28"
			(at -0.0127 -3.1877 270)
			(unlocked yes)
			(layer "F.Fab")
			(hide yes)
			(effects
				(font
					(size 1.016 1.016)
					(thickness 0.1524)
				)
			)
		)
		(duplicate_pad_numbers_are_jumpers no)
		(fp_poly
			(pts
				(arc
					(start 0 -0.3556)
					(mid 0 0.3556)
					(end 0 -0.3556)
				)
			)
			(stroke
				(width 0)
				(type default)
			)
			(fill no)
			(layer "F.CrtYd")
		)
		(fp_poly
			(pts
				(arc
					(start 0 -0.6096)
					(mid 0 0.6096)
					(end 0 -0.6096)
				)
			)
			(stroke
				(width 0)
				(type default)
			)
			(fill no)
			(layer "F.Fab")
		)
		(pad "1" smd circle
			(at 0 0 270)
			(size 0.7112 0.7112)
			(layers "F.Cu" "F.Mask" "F.Paste")
			(net "IOC_GPIO_30")
		)
	)
	(footprint ""
		(layer "F.Cu")
		(at 118.1862 -89.276174)
		(property "Reference" "TP50"
			(at 0 0 0)
			(layer "F.SilkS")
			(hide yes)
			(effects
				(font
					(size 1.27 1.27)
				)
			)
		)
		(property "Value" "TPAD28-2-GP"
			(at -0.0127 -1.6637 0)
			(unlocked yes)
			(layer "F.Fab")
			(hide yes)
			(effects
				(font
					(size 1.016 1.016)
					(thickness 0.1524)
				)
			)
		)
		(property "Device Type" "TPAD28"
			(at -0.0127 -3.1877 0)
			(unlocked yes)
			(layer "F.Fab")
			(hide yes)
			(effects
				(font
					(size 1.016 1.016)
					(thickness 0.1524)
				)
			)
		)
		(duplicate_pad_numbers_are_jumpers no)
		(fp_poly
			(pts
				(arc
					(start 0.3556 0)
					(mid -0.3556 0)
					(end 0.3556 0)
				)
			)
			(stroke
				(width 0)
				(type default)
			)
			(fill no)
			(layer "F.CrtYd")
		)
		(fp_poly
			(pts
				(arc
					(start 0.6096 0)
					(mid -0.6096 0)
					(end 0.6096 0)
				)
			)
			(stroke
				(width 0)
				(type default)
			)
			(fill no)
			(layer "F.Fab")
		)
		(pad "1" smd circle
			(at 0 0)
			(size 0.7112 0.7112)
			(layers "F.Cu" "F.Mask" "F.Paste")
			(net "EXP_XM_ADDR_0")
		)
	)
	(footprint ""
		(layer "F.Cu")
		(at 94.1832 -73.152 90)
		(property "Reference" "R34"
			(at 0 0 90)
			(layer "F.SilkS")
			(hide yes)
			(effects
				(font
					(size 1.27 1.27)
				)
			)
		)
		(property "Value" "4K75R2F-1-GP"
			(at 0.064008 -3.993896 90)
			(unlocked yes)
			(layer "F.Fab")
			(hide yes)
			(effects
				(font
					(size 1.016 1.016)
					(thickness 0.1524)
				)
			)
		)
		(property "Device Type" "R402H16"
			(at 0.064008 -5.517896 90)
			(unlocked yes)
			(layer "F.Fab")
			(hide yes)
			(effects
				(font
					(size 1.016 1.016)
					(thickness 0.1524)
				)
			)
		)
		(duplicate_pad_numbers_are_jumpers no)
		(fp_line
			(start 0.508 -0.9398)
			(end -0.508 -0.9398)
			(stroke
				(width 0.1524)
				(type default)
			)
			(layer "F.SilkS")
		)
		(fp_line
			(start -0.508 -0.9398)
			(end -0.508 0.9398)
			(stroke
				(width 0.1524)
				(type default)
			)
			(layer "F.SilkS")
		)
		(fp_rect
			(start -0.508 0.9398)
			(end 0.508 -0.9398)
			(stroke
				(width 0)
				(type default)
			)
			(fill no)
			(layer "F.CrtYd")
		)
		(fp_rect
			(start -0.508 0.9398)
			(end 0.508 -0.9398)
			(stroke
				(width 0)
				(type default)
			)
			(fill no)
			(layer "F.Fab")
		)
		(pad "1" smd custom
			(at 0 -0.4445 90)
			(size 0.1397 0.1397)
			(layers "F.Cu" "F.Mask" "F.Paste")
			(net "GND")
			(options
				(clearance outline)
				(anchor circle)
			)
			(primitives
				(gr_poly
					(pts
						(arc
							(start -0.1778 -0.2794)
							(mid -0.249642 -0.249642)
							(end -0.2794 -0.1778)
						)
						(arc
							(start -0.2794 0.1778)
							(mid -0.249642 0.249642)
							(end -0.1778 0.2794)
						)
						(arc
							(start 0.1778 0.2794)
							(mid 0.249642 0.249642)
							(end 0.2794 0.1778)
						)
						(arc
							(start 0.2794 -0.1778)
							(mid 0.249642 -0.249642)
							(end 0.1778 -0.2794)
						)
					)
					(width 0)
					(fill yes)
				)
			)
		)
		(pad "2" smd custom
			(at 0 0.4445 90)
			(size 0.1397 0.1397)
			(layers "F.Cu" "F.Mask" "F.Paste")
			(net "EXP_ADC_IN1")
			(options
				(clearance outline)
				(anchor circle)
			)
			(primitives
				(gr_poly
					(pts
						(arc
							(start -0.1778 -0.2794)
							(mid -0.249642 -0.249642)
							(end -0.2794 -0.1778)
						)
						(arc
							(start -0.2794 0.1778)
							(mid -0.249642 0.249642)
							(end -0.1778 0.2794)
						)
						(arc
							(start 0.1778 0.2794)
							(mid 0.249642 0.249642)
							(end 0.2794 0.1778)
						)
						(arc
							(start 0.2794 -0.1778)
							(mid 0.249642 -0.249642)
							(end 0.1778 -0.2794)
						)
					)
					(width 0)
					(fill yes)
				)
			)
		)
	)
	(footprint ""
		(layer "F.Cu")
		(at 19.5072 -46.9646)
		(property "Reference" "R16"
			(at 0 0 0)
			(layer "F.SilkS")
			(hide yes)
			(effects
				(font
					(size 1.27 1.27)
				)
			)
		)
		(property "Value" "5K1R2F-3-GP"
			(at 0.064008 -3.993896 0)
			(unlocked yes)
			(layer "F.Fab")
			(hide yes)
			(effects
				(font
					(size 1.016 1.016)
					(thickness 0.1524)
				)
			)
		)
		(property "Device Type" "R402H16"
			(at 0.064008 -5.517896 0)
			(unlocked yes)
			(layer "F.Fab")
			(hide yes)
			(effects
				(font
					(size 1.016 1.016)
					(thickness 0.1524)
				)
			)
		)
		(duplicate_pad_numbers_are_jumpers no)
		(fp_line
			(start -0.508 -0.9398)
			(end -0.508 0.9398)
			(stroke
				(width 0.1524)
				(type default)
			)
			(layer "F.SilkS")
		)
		(fp_line
			(start 0.508 -0.9398)
			(end -0.508 -0.9398)
			(stroke
				(width 0.1524)
				(type default)
			)
			(layer "F.SilkS")
		)
		(fp_rect
			(start -0.508 0.9398)
			(end 0.508 -0.9398)
			(stroke
				(width 0)
				(type default)
			)
			(fill no)
			(layer "F.CrtYd")
		)
		(fp_rect
			(start -0.508 0.9398)
			(end 0.508 -0.9398)
			(stroke
				(width 0)
				(type default)
			)
			(fill no)
			(layer "F.Fab")
		)
		(pad "1" smd custom
			(at 0 -0.4445)
			(size 0.1397 0.1397)
			(layers "F.Cu" "F.Mask" "F.Paste")
			(net "MB0_CM_UV_R")
			(options
				(clearance outline)
				(anchor circle)
			)
			(primitives
				(gr_poly
					(pts
						(arc
							(start -0.1778 -0.2794)
							(mid -0.249642 -0.249642)
							(end -0.2794 -0.1778)
						)
						(arc
							(start -0.2794 0.1778)
							(mid -0.249642 0.249642)
							(end -0.1778 0.2794)
						)
						(arc
							(start 0.1778 0.2794)
							(mid 0.249642 0.249642)
							(end 0.2794 0.1778)
						)
						(arc
							(start 0.2794 -0.1778)
							(mid 0.249642 -0.249642)
							(end 0.1778 -0.2794)
						)
					)
					(width 0)
					(fill yes)
				)
			)
		)
		(pad "2" smd custom
			(at 0 0.4445)
			(size 0.1397 0.1397)
			(layers "F.Cu" "F.Mask" "F.Paste")
			(net "AGND_CURRENT_MON")
			(options
				(clearance outline)
				(anchor circle)
			)
			(primitives
				(gr_poly
					(pts
						(arc
							(start -0.1778 -0.2794)
							(mid -0.249642 -0.249642)
							(end -0.2794 -0.1778)
						)
						(arc
							(start -0.2794 0.1778)
							(mid -0.249642 0.249642)
							(end -0.1778 0.2794)
						)
						(arc
							(start 0.1778 0.2794)
							(mid 0.249642 0.249642)
							(end 0.2794 0.1778)
						)
						(arc
							(start 0.2794 -0.1778)
							(mid 0.249642 -0.249642)
							(end 0.1778 -0.2794)
						)
					)
					(width 0)
					(fill yes)
				)
			)
		)
	)
	(footprint ""
		(layer "F.Cu")
		(at 170.33494 -105.95102 180)
		(property "Reference" "R376"
			(at 0 0 180)
			(layer "F.SilkS")
			(hide yes)
			(effects
				(font
					(size 1.27 1.27)
				)
			)
		)
		(property "Value" "4K7R2F-GP"
			(at 0.064008 -3.993896 180)
			(unlocked yes)
			(layer "F.Fab")
			(hide yes)
			(effects
				(font
					(size 1.016 1.016)
					(thickness 0.1524)
				)
			)
		)
		(property "Device Type" "R402H16"
			(at 0.064008 -5.517896 180)
			(unlocked yes)
			(layer "F.Fab")
			(hide yes)
			(effects
				(font
					(size 1.016 1.016)
					(thickness 0.1524)
				)
			)
		)
		(duplicate_pad_numbers_are_jumpers no)
		(fp_line
			(start 0.508 -0.9398)
			(end -0.508 -0.9398)
			(stroke
				(width 0.1524)
				(type default)
			)
			(layer "F.SilkS")
		)
		(fp_line
			(start -0.508 -0.9398)
			(end -0.508 0.9398)
			(stroke
				(width 0.1524)
				(type default)
			)
			(layer "F.SilkS")
		)
		(fp_rect
			(start -0.508 0.9398)
			(end 0.508 -0.9398)
			(stroke
				(width 0)
				(type default)
			)
			(fill no)
			(layer "F.CrtYd")
		)
		(fp_rect
			(start -0.508 0.9398)
			(end 0.508 -0.9398)
			(stroke
				(width 0)
				(type default)
			)
			(fill no)
			(layer "F.Fab")
		)
		(pad "1" smd custom
			(at 0 -0.4445 180)
			(size 0.1397 0.1397)
			(layers "F.Cu" "F.Mask" "F.Paste")
			(net "P1V8_C")
			(options
				(clearance outline)
				(anchor circle)
			)
			(primitives
				(gr_poly
					(pts
						(arc
							(start -0.1778 -0.2794)
							(mid -0.249642 -0.249642)
							(end -0.2794 -0.1778)
						)
						(arc
							(start -0.2794 0.1778)
							(mid -0.249642 0.249642)
							(end -0.1778 0.2794)
						)
						(arc
							(start 0.1778 0.2794)
							(mid 0.249642 0.249642)
							(end 0.2794 0.1778)
						)
						(arc
							(start 0.2794 -0.1778)
							(mid 0.249642 -0.249642)
							(end 0.1778 -0.2794)
						)
					)
					(width 0)
					(fill yes)
				)
			)
		)
		(pad "2" smd custom
			(at 0 0.4445 180)
			(size 0.1397 0.1397)
			(layers "F.Cu" "F.Mask" "F.Paste")
			(net "SCC_FULL_PGOOD_LS")
			(options
				(clearance outline)
				(anchor circle)
			)
			(primitives
				(gr_poly
					(pts
						(arc
							(start -0.1778 -0.2794)
							(mid -0.249642 -0.249642)
							(end -0.2794 -0.1778)
						)
						(arc
							(start -0.2794 0.1778)
							(mid -0.249642 0.249642)
							(end -0.1778 0.2794)
						)
						(arc
							(start 0.1778 0.2794)
							(mid 0.249642 0.249642)
							(end 0.2794 0.1778)
						)
						(arc
							(start 0.2794 -0.1778)
							(mid 0.249642 -0.249642)
							(end 0.1778 -0.2794)
						)
					)
					(width 0)
					(fill yes)
				)
			)
		)
	)
	(footprint ""
		(layer "F.Cu")
		(at 193.1543 -30.3657 -90)
		(property "Reference" "TP53"
			(at 0 0 270)
			(layer "F.SilkS")
			(hide yes)
			(effects
				(font
					(size 1.27 1.27)
				)
			)
		)
		(property "Value" "TPAD28-2-GP"
			(at -0.0127 -1.6637 270)
			(unlocked yes)
			(layer "F.Fab")
			(hide yes)
			(effects
				(font
					(size 1.016 1.016)
					(thickness 0.1524)
				)
			)
		)
		(property "Device Type" "TPAD28"
			(at -0.0127 -3.1877 270)
			(unlocked yes)
			(layer "F.Fab")
			(hide yes)
			(effects
				(font
					(size 1.016 1.016)
					(thickness 0.1524)
				)
			)
		)
		(duplicate_pad_numbers_are_jumpers no)
		(fp_poly
			(pts
				(arc
					(start 0 -0.3556)
					(mid 0 0.3556)
					(end 0 -0.3556)
				)
			)
			(stroke
				(width 0)
				(type default)
			)
			(fill no)
			(layer "F.CrtYd")
		)
		(fp_poly
			(pts
				(arc
					(start 0 -0.6096)
					(mid 0 0.6096)
					(end 0 -0.6096)
				)
			)
			(stroke
				(width 0)
				(type default)
			)
			(fill no)
			(layer "F.Fab")
		)
		(pad "1" smd circle
			(at 0 0 270)
			(size 0.7112 0.7112)
			(layers "F.Cu" "F.Mask" "F.Paste")
			(net "IOC_GPIO_0")
		)
	)
	(footprint ""
		(layer "F.Cu")
		(at 136.227312 -79.171292 90)
		(property "Reference" "C678"
			(at 0 0 90)
			(layer "F.SilkS")
			(hide yes)
			(effects
				(font
					(size 1.27 1.27)
				)
			)
		)
		(property "Value" "SCD01U16V1KX-GP"
			(at -2.8321 -1.7399 90)
			(unlocked yes)
			(layer "F.Fab")
			(hide yes)
			(effects
				(font
					(size 1.016 1.016)
					(thickness 0.1524)
				)
			)
		)
		(property "Device Type" "C0201H13"
			(at -2.8321 -3.2639 90)
			(unlocked yes)
			(layer "F.Fab")
			(hide yes)
			(effects
				(font
					(size 1.016 1.016)
					(thickness 0.1524)
				)
			)
		)
		(duplicate_pad_numbers_are_jumpers no)
		(fp_rect
			(start -0.2794 0.6477)
			(end 0.2794 -0.6477)
			(stroke
				(width 0)
				(type default)
			)
			(fill no)
			(layer "F.CrtYd")
		)
		(fp_rect
			(start -0.2794 0.6477)
			(end 0.2794 -0.6477)
			(stroke
				(width 0)
				(type default)
			)
			(fill no)
			(layer "F.Fab")
		)
		(pad "1" smd custom
			(at 0 -0.2794 90)
			(size 0.0762 0.0762)
			(layers "F.Cu" "F.Mask" "F.Paste")
			(net "PHY_EXP_TO_CONN_C_10_DP")
			(options
				(clearance outline)
				(anchor circle)
			)
			(primitives
				(gr_poly
					(pts
						(arc
							(start 0.1524 -0.127)
							(mid 0.137521 -0.162921)
							(end 0.1016 -0.1778)
						)
						(arc
							(start -0.1016 -0.1778)
							(mid -0.137521 -0.162921)
							(end -0.1524 -0.127)
						)
						(arc
							(start -0.1524 0.127)
							(mid -0.137521 0.162921)
							(end -0.1016 0.1778)
						)
						(arc
							(start 0.1016 0.1778)
							(mid 0.137521 0.162921)
							(end 0.1524 0.127)
						)
					)
					(width 0)
					(fill yes)
				)
			)
		)
		(pad "2" smd custom
			(at 0 0.2794 90)
			(size 0.0762 0.0762)
			(layers "F.Cu" "F.Mask" "F.Paste")
			(net "PHY_EXP_TO_CONN_10_DP")
			(options
				(clearance outline)
				(anchor circle)
			)
			(primitives
				(gr_poly
					(pts
						(arc
							(start 0.1524 -0.127)
							(mid 0.137521 -0.162921)
							(end 0.1016 -0.1778)
						)
						(arc
							(start -0.1016 -0.1778)
							(mid -0.137521 -0.162921)
							(end -0.1524 -0.127)
						)
						(arc
							(start -0.1524 0.127)
							(mid -0.137521 0.162921)
							(end -0.1016 0.1778)
						)
						(arc
							(start 0.1016 0.1778)
							(mid 0.137521 0.162921)
							(end 0.1524 0.127)
						)
					)
					(width 0)
					(fill yes)
				)
			)
		)
	)
	(footprint ""
		(layer "F.Cu")
		(at 134.341108 -86.79815)
		(property "Reference" "TP17"
			(at 0 0 0)
			(layer "F.SilkS")
			(hide yes)
			(effects
				(font
					(size 1.27 1.27)
				)
			)
		)
		(property "Value" "TPAD28-2-GP"
			(at -0.0127 -1.6637 0)
			(unlocked yes)
			(layer "F.Fab")
			(hide yes)
			(effects
				(font
					(size 1.016 1.016)
					(thickness 0.1524)
				)
			)
		)
		(property "Device Type" "TPAD28"
			(at -0.0127 -3.1877 0)
			(unlocked yes)
			(layer "F.Fab")
			(hide yes)
			(effects
				(font
					(size 1.016 1.016)
					(thickness 0.1524)
				)
			)
		)
		(duplicate_pad_numbers_are_jumpers no)
		(fp_poly
			(pts
				(arc
					(start 0.3556 0)
					(mid -0.3556 0)
					(end 0.3556 0)
				)
			)
			(stroke
				(width 0)
				(type default)
			)
			(fill no)
			(layer "F.CrtYd")
		)
		(fp_poly
			(pts
				(arc
					(start 0.6096 0)
					(mid -0.6096 0)
					(end 0.6096 0)
				)
			)
			(stroke
				(width 0)
				(type default)
			)
			(fill no)
			(layer "F.Fab")
		)
		(pad "1" smd circle
			(at 0 0)
			(size 0.7112 0.7112)
			(layers "F.Cu" "F.Mask" "F.Paste")
			(net "EXP_I2C_SDA10")
		)
	)
	(footprint ""
		(layer "F.Cu")
		(at 19.252184 -70.28053 90)
		(property "Reference" "R355"
			(at 0 0 90)
			(layer "F.SilkS")
			(hide yes)
			(effects
				(font
					(size 1.27 1.27)
				)
			)
		)
		(property "Value" "0R2J-2-GP"
			(at 0.064008 -3.993896 90)
			(unlocked yes)
			(layer "F.Fab")
			(hide yes)
			(effects
				(font
					(size 1.016 1.016)
					(thickness 0.1524)
				)
			)
		)
		(property "Device Type" "R402H16"
			(at 0.064008 -5.517896 90)
			(unlocked yes)
			(layer "F.Fab")
			(hide yes)
			(effects
				(font
					(size 1.016 1.016)
					(thickness 0.1524)
				)
			)
		)
		(duplicate_pad_numbers_are_jumpers no)
		(fp_line
			(start 0.508 -0.9398)
			(end -0.508 -0.9398)
			(stroke
				(width 0.1524)
				(type default)
			)
			(layer "F.SilkS")
		)
		(fp_line
			(start -0.508 -0.9398)
			(end -0.508 0.9398)
			(stroke
				(width 0.1524)
				(type default)
			)
			(layer "F.SilkS")
		)
		(fp_rect
			(start -0.508 0.9398)
			(end 0.508 -0.9398)
			(stroke
				(width 0)
				(type default)
			)
			(fill no)
			(layer "F.CrtYd")
		)
		(fp_rect
			(start -0.508 0.9398)
			(end 0.508 -0.9398)
			(stroke
				(width 0)
				(type default)
			)
			(fill no)
			(layer "F.Fab")
		)
		(pad "1" smd custom
			(at 0 -0.4445 90)
			(size 0.1397 0.1397)
			(layers "F.Cu" "F.Mask" "F.Paste")
			(net "EEPROM_SDA")
			(options
				(clearance outline)
				(anchor circle)
			)
			(primitives
				(gr_poly
					(pts
						(arc
							(start -0.1778 -0.2794)
							(mid -0.249642 -0.249642)
							(end -0.2794 -0.1778)
						)
						(arc
							(start -0.2794 0.1778)
							(mid -0.249642 0.249642)
							(end -0.1778 0.2794)
						)
						(arc
							(start 0.1778 0.2794)
							(mid 0.249642 0.249642)
							(end 0.2794 0.1778)
						)
						(arc
							(start 0.2794 -0.1778)
							(mid 0.249642 -0.249642)
							(end 0.1778 -0.2794)
						)
					)
					(width 0)
					(fill yes)
				)
			)
		)
		(pad "2" smd custom
			(at 0 0.4445 90)
			(size 0.1397 0.1397)
			(layers "F.Cu" "F.Mask" "F.Paste")
			(net "I2C_SCC_SDA2")
			(options
				(clearance outline)
				(anchor circle)
			)
			(primitives
				(gr_poly
					(pts
						(arc
							(start -0.1778 -0.2794)
							(mid -0.249642 -0.249642)
							(end -0.2794 -0.1778)
						)
						(arc
							(start -0.2794 0.1778)
							(mid -0.249642 0.249642)
							(end -0.1778 0.2794)
						)
						(arc
							(start 0.1778 0.2794)
							(mid 0.249642 0.249642)
							(end 0.2794 0.1778)
						)
						(arc
							(start 0.2794 -0.1778)
							(mid 0.249642 -0.249642)
							(end 0.1778 -0.2794)
						)
					)
					(width 0)
					(fill yes)
				)
			)
		)
	)
	(footprint ""
		(layer "F.Cu")
		(at 87.221314 -81.208118 90)
		(property "Reference" "R132"
			(at 0 0 90)
			(layer "F.SilkS")
			(hide yes)
			(effects
				(font
					(size 1.27 1.27)
				)
			)
		)
		(property "Value" "0R2J-2-GP"
			(at 0.064008 -3.993896 90)
			(unlocked yes)
			(layer "F.Fab")
			(hide yes)
			(effects
				(font
					(size 1.016 1.016)
					(thickness 0.1524)
				)
			)
		)
		(property "Device Type" "R402H16"
			(at 0.064008 -5.517896 90)
			(unlocked yes)
			(layer "F.Fab")
			(hide yes)
			(effects
				(font
					(size 1.016 1.016)
					(thickness 0.1524)
				)
			)
		)
		(duplicate_pad_numbers_are_jumpers no)
		(fp_line
			(start 0.508 -0.9398)
			(end -0.508 -0.9398)
			(stroke
				(width 0.1524)
				(type default)
			)
			(layer "F.SilkS")
		)
		(fp_line
			(start -0.508 -0.9398)
			(end -0.508 0.9398)
			(stroke
				(width 0.1524)
				(type default)
			)
			(layer "F.SilkS")
		)
		(fp_rect
			(start -0.508 0.9398)
			(end 0.508 -0.9398)
			(stroke
				(width 0)
				(type default)
			)
			(fill no)
			(layer "F.CrtYd")
		)
		(fp_rect
			(start -0.508 0.9398)
			(end 0.508 -0.9398)
			(stroke
				(width 0)
				(type default)
			)
			(fill no)
			(layer "F.Fab")
		)
		(pad "1" smd custom
			(at 0 -0.4445 90)
			(size 0.1397 0.1397)
			(layers "F.Cu" "F.Mask" "F.Paste")
			(net "P0V9_PG")
			(options
				(clearance outline)
				(anchor circle)
			)
			(primitives
				(gr_poly
					(pts
						(arc
							(start -0.1778 -0.2794)
							(mid -0.249642 -0.249642)
							(end -0.2794 -0.1778)
						)
						(arc
							(start -0.2794 0.1778)
							(mid -0.249642 0.249642)
							(end -0.1778 0.2794)
						)
						(arc
							(start 0.1778 0.2794)
							(mid 0.249642 0.249642)
							(end 0.2794 0.1778)
						)
						(arc
							(start 0.2794 -0.1778)
							(mid 0.249642 -0.249642)
							(end 0.1778 -0.2794)
						)
					)
					(width 0)
					(fill yes)
				)
			)
		)
		(pad "2" smd custom
			(at 0 0.4445 90)
			(size 0.1397 0.1397)
			(layers "F.Cu" "F.Mask" "F.Paste")
			(net "RESET_MR#")
			(options
				(clearance outline)
				(anchor circle)
			)
			(primitives
				(gr_poly
					(pts
						(arc
							(start -0.1778 -0.2794)
							(mid -0.249642 -0.249642)
							(end -0.2794 -0.1778)
						)
						(arc
							(start -0.2794 0.1778)
							(mid -0.249642 0.249642)
							(end -0.1778 0.2794)
						)
						(arc
							(start 0.1778 0.2794)
							(mid 0.249642 0.249642)
							(end 0.2794 0.1778)
						)
						(arc
							(start 0.2794 -0.1778)
							(mid 0.249642 -0.249642)
							(end 0.1778 -0.2794)
						)
					)
					(width 0)
					(fill yes)
				)
			)
		)
	)
	(footprint ""
		(layer "F.Cu")
		(at 164.52088 -100.4062 -90)
		(property "Reference" "R486"
			(at 0 0 270)
			(layer "F.SilkS")
			(hide yes)
			(effects
				(font
					(size 1.27 1.27)
				)
			)
		)
		(property "Value" "0R2J-2-GP"
			(at 0.064008 -3.993896 270)
			(unlocked yes)
			(layer "F.Fab")
			(hide yes)
			(effects
				(font
					(size 1.016 1.016)
					(thickness 0.1524)
				)
			)
		)
		(property "Device Type" "R402H16"
			(at 0.064008 -5.517896 270)
			(unlocked yes)
			(layer "F.Fab")
			(hide yes)
			(effects
				(font
					(size 1.016 1.016)
					(thickness 0.1524)
				)
			)
		)
		(duplicate_pad_numbers_are_jumpers no)
		(fp_line
			(start -0.508 -0.9398)
			(end -0.508 0.9398)
			(stroke
				(width 0.1524)
				(type default)
			)
			(layer "F.SilkS")
		)
		(fp_line
			(start 0.508 -0.9398)
			(end -0.508 -0.9398)
			(stroke
				(width 0.1524)
				(type default)
			)
			(layer "F.SilkS")
		)
		(fp_rect
			(start -0.508 0.9398)
			(end 0.508 -0.9398)
			(stroke
				(width 0)
				(type default)
			)
			(fill no)
			(layer "F.CrtYd")
		)
		(fp_rect
			(start -0.508 0.9398)
			(end 0.508 -0.9398)
			(stroke
				(width 0)
				(type default)
			)
			(fill no)
			(layer "F.Fab")
		)
		(pad "1" smd custom
			(at 0 -0.4445 270)
			(size 0.1397 0.1397)
			(layers "F.Cu" "F.Mask" "F.Paste")
			(net "VT235_EN")
			(options
				(clearance outline)
				(anchor circle)
			)
			(primitives
				(gr_poly
					(pts
						(arc
							(start -0.1778 -0.2794)
							(mid -0.249642 -0.249642)
							(end -0.2794 -0.1778)
						)
						(arc
							(start -0.2794 0.1778)
							(mid -0.249642 0.249642)
							(end -0.1778 0.2794)
						)
						(arc
							(start 0.1778 0.2794)
							(mid 0.249642 0.249642)
							(end 0.2794 0.1778)
						)
						(arc
							(start 0.2794 -0.1778)
							(mid 0.249642 -0.249642)
							(end 0.1778 -0.2794)
						)
					)
					(width 0)
					(fill yes)
				)
			)
		)
		(pad "2" smd custom
			(at 0 0.4445 270)
			(size 0.1397 0.1397)
			(layers "F.Cu" "F.Mask" "F.Paste")
			(net "P1V5_C_PG")
			(options
				(clearance outline)
				(anchor circle)
			)
			(primitives
				(gr_poly
					(pts
						(arc
							(start -0.1778 -0.2794)
							(mid -0.249642 -0.249642)
							(end -0.2794 -0.1778)
						)
						(arc
							(start -0.2794 0.1778)
							(mid -0.249642 0.249642)
							(end -0.1778 0.2794)
						)
						(arc
							(start 0.1778 0.2794)
							(mid 0.249642 0.249642)
							(end 0.2794 0.1778)
						)
						(arc
							(start 0.2794 -0.1778)
							(mid 0.249642 -0.249642)
							(end 0.1778 -0.2794)
						)
					)
					(width 0)
					(fill yes)
				)
			)
		)
	)
	(footprint ""
		(layer "F.Cu")
		(at 158.64078 -93.80728 90)
		(property "Reference" "C504"
			(at 0 0 90)
			(layer "F.SilkS")
			(hide yes)
			(effects
				(font
					(size 1.27 1.27)
				)
			)
		)
		(property "Value" "SCD1U16V2KX-3GP"
			(at 1.1811 -2.7051 90)
			(unlocked yes)
			(layer "F.Fab")
			(hide yes)
			(effects
				(font
					(size 1.016 1.016)
					(thickness 0.1524)
				)
			)
		)
		(property "Device Type" "C402H22"
			(at 1.1811 -4.2291 90)
			(unlocked yes)
			(layer "F.Fab")
			(hide yes)
			(effects
				(font
					(size 1.016 1.016)
					(thickness 0.1524)
				)
			)
		)
		(duplicate_pad_numbers_are_jumpers no)
		(fp_rect
			(start -0.4318 0.9525)
			(end 0.4318 -0.9525)
			(stroke
				(width 0)
				(type default)
			)
			(fill no)
			(layer "F.CrtYd")
		)
		(fp_rect
			(start -0.4318 0.9525)
			(end 0.4318 -0.9525)
			(stroke
				(width 0)
				(type default)
			)
			(fill no)
			(layer "F.Fab")
		)
		(pad "1" smd custom
			(at 0 -0.4445 90)
			(size 0.1524 0.1524)
			(layers "F.Cu" "F.Mask" "F.Paste")
			(net "P3V3")
			(options
				(clearance outline)
				(anchor circle)
			)
			(primitives
				(gr_poly
					(pts
						(arc
							(start 0.3048 -0.2032)
							(mid 0.275042 -0.275042)
							(end 0.2032 -0.3048)
						)
						(arc
							(start -0.2032 -0.3048)
							(mid -0.275042 -0.275042)
							(end -0.3048 -0.2032)
						)
						(arc
							(start -0.3048 0.2032)
							(mid -0.275042 0.275042)
							(end -0.2032 0.3048)
						)
						(arc
							(start 0.2032 0.3048)
							(mid 0.275042 0.275042)
							(end 0.3048 0.2032)
						)
					)
					(width 0)
					(fill yes)
				)
			)
		)
		(pad "2" smd custom
			(at 0 0.4445 90)
			(size 0.1524 0.1524)
			(layers "F.Cu" "F.Mask" "F.Paste")
			(net "GND")
			(options
				(clearance outline)
				(anchor circle)
			)
			(primitives
				(gr_poly
					(pts
						(arc
							(start 0.3048 -0.2032)
							(mid 0.275042 -0.275042)
							(end 0.2032 -0.3048)
						)
						(arc
							(start -0.2032 -0.3048)
							(mid -0.275042 -0.275042)
							(end -0.3048 -0.2032)
						)
						(arc
							(start -0.3048 0.2032)
							(mid -0.275042 0.275042)
							(end -0.2032 0.3048)
						)
						(arc
							(start 0.2032 0.3048)
							(mid 0.275042 0.275042)
							(end 0.3048 0.2032)
						)
					)
					(width 0)
					(fill yes)
				)
			)
		)
	)
	(footprint ""
		(layer "F.Cu")
		(at 70.866 -103.505 180)
		(property "Reference" "C642"
			(at 0 0 180)
			(layer "F.SilkS")
			(hide yes)
			(effects
				(font
					(size 1.27 1.27)
				)
			)
		)
		(property "Value" "SC68P50V2JN-2-GP"
			(at 1.1811 -2.7051 180)
			(unlocked yes)
			(layer "F.Fab")
			(hide yes)
			(effects
				(font
					(size 1.016 1.016)
					(thickness 0.1524)
				)
			)
		)
		(property "Device Type" "C402H22"
			(at 1.1811 -4.2291 180)
			(unlocked yes)
			(layer "F.Fab")
			(hide yes)
			(effects
				(font
					(size 1.016 1.016)
					(thickness 0.1524)
				)
			)
		)
		(duplicate_pad_numbers_are_jumpers no)
		(fp_rect
			(start -0.4318 0.9525)
			(end 0.4318 -0.9525)
			(stroke
				(width 0)
				(type default)
			)
			(fill no)
			(layer "F.CrtYd")
		)
		(fp_rect
			(start -0.4318 0.9525)
			(end 0.4318 -0.9525)
			(stroke
				(width 0)
				(type default)
			)
			(fill no)
			(layer "F.Fab")
		)
		(pad "1" smd custom
			(at 0 -0.4445 180)
			(size 0.1524 0.1524)
			(layers "F.Cu" "F.Mask" "F.Paste")
			(net "P3V3_VFB")
			(options
				(clearance outline)
				(anchor circle)
			)
			(primitives
				(gr_poly
					(pts
						(arc
							(start 0.3048 -0.2032)
							(mid 0.275042 -0.275042)
							(end 0.2032 -0.3048)
						)
						(arc
							(start -0.2032 -0.3048)
							(mid -0.275042 -0.275042)
							(end -0.3048 -0.2032)
						)
						(arc
							(start -0.3048 0.2032)
							(mid -0.275042 0.275042)
							(end -0.2032 0.3048)
						)
						(arc
							(start 0.2032 0.3048)
							(mid 0.275042 0.275042)
							(end 0.3048 0.2032)
						)
					)
					(width 0)
					(fill yes)
				)
			)
		)
		(pad "2" smd custom
			(at 0 0.4445 180)
			(size 0.1524 0.1524)
			(layers "F.Cu" "F.Mask" "F.Paste")
			(net "P3V3_VFB_R")
			(options
				(clearance outline)
				(anchor circle)
			)
			(primitives
				(gr_poly
					(pts
						(arc
							(start 0.3048 -0.2032)
							(mid 0.275042 -0.275042)
							(end 0.2032 -0.3048)
						)
						(arc
							(start -0.2032 -0.3048)
							(mid -0.275042 -0.275042)
							(end -0.3048 -0.2032)
						)
						(arc
							(start -0.3048 0.2032)
							(mid -0.275042 0.275042)
							(end -0.2032 0.3048)
						)
						(arc
							(start 0.2032 0.3048)
							(mid 0.275042 0.275042)
							(end 0.3048 0.2032)
						)
					)
					(width 0)
					(fill yes)
				)
			)
		)
	)
	(footprint ""
		(layer "F.Cu")
		(at 19.6088 -93.6752)
		(property "Reference" "R409"
			(at 0 0 0)
			(layer "F.SilkS")
			(hide yes)
			(effects
				(font
					(size 1.27 1.27)
				)
			)
		)
		(property "Value" "1KR2F-3-GP"
			(at 0.064008 -3.993896 0)
			(unlocked yes)
			(layer "F.Fab")
			(hide yes)
			(effects
				(font
					(size 1.016 1.016)
					(thickness 0.1524)
				)
			)
		)
		(property "Device Type" "R402H16"
			(at 0.064008 -5.517896 0)
			(unlocked yes)
			(layer "F.Fab")
			(hide yes)
			(effects
				(font
					(size 1.016 1.016)
					(thickness 0.1524)
				)
			)
		)
		(duplicate_pad_numbers_are_jumpers no)
		(fp_line
			(start -0.508 -0.9398)
			(end -0.508 0.9398)
			(stroke
				(width 0.1524)
				(type default)
			)
			(layer "F.SilkS")
		)
		(fp_line
			(start 0.508 -0.9398)
			(end -0.508 -0.9398)
			(stroke
				(width 0.1524)
				(type default)
			)
			(layer "F.SilkS")
		)
		(fp_rect
			(start -0.508 0.9398)
			(end 0.508 -0.9398)
			(stroke
				(width 0)
				(type default)
			)
			(fill no)
			(layer "F.CrtYd")
		)
		(fp_rect
			(start -0.508 0.9398)
			(end 0.508 -0.9398)
			(stroke
				(width 0)
				(type default)
			)
			(fill no)
			(layer "F.Fab")
		)
		(pad "1" smd custom
			(at 0 -0.4445)
			(size 0.1397 0.1397)
			(layers "F.Cu" "F.Mask" "F.Paste")
			(net "P3V3")
			(options
				(clearance outline)
				(anchor circle)
			)
			(primitives
				(gr_poly
					(pts
						(arc
							(start -0.1778 -0.2794)
							(mid -0.249642 -0.249642)
							(end -0.2794 -0.1778)
						)
						(arc
							(start -0.2794 0.1778)
							(mid -0.249642 0.249642)
							(end -0.1778 0.2794)
						)
						(arc
							(start 0.1778 0.2794)
							(mid 0.249642 0.249642)
							(end 0.2794 0.1778)
						)
						(arc
							(start 0.2794 -0.1778)
							(mid 0.249642 -0.249642)
							(end 0.1778 -0.2794)
						)
					)
					(width 0)
					(fill yes)
				)
			)
		)
		(pad "2" smd custom
			(at 0 0.4445)
			(size 0.1397 0.1397)
			(layers "F.Cu" "F.Mask" "F.Paste")
			(net "I2C_BMC_LOC_SCL0")
			(options
				(clearance outline)
				(anchor circle)
			)
			(primitives
				(gr_poly
					(pts
						(arc
							(start -0.1778 -0.2794)
							(mid -0.249642 -0.249642)
							(end -0.2794 -0.1778)
						)
						(arc
							(start -0.2794 0.1778)
							(mid -0.249642 0.249642)
							(end -0.1778 0.2794)
						)
						(arc
							(start 0.1778 0.2794)
							(mid 0.249642 0.249642)
							(end 0.2794 0.1778)
						)
						(arc
							(start 0.2794 -0.1778)
							(mid 0.249642 -0.249642)
							(end 0.1778 -0.2794)
						)
					)
					(width 0)
					(fill yes)
				)
			)
		)
	)
	(footprint ""
		(layer "F.Cu")
		(at 185.3946 -117.8306 -90)
		(property "Reference" "C692"
			(at 0 0 270)
			(layer "F.SilkS")
			(hide yes)
			(effects
				(font
					(size 1.27 1.27)
				)
			)
		)
		(property "Value" "SCD1U16V2KX-3GP"
			(at 1.1811 -2.7051 270)
			(unlocked yes)
			(layer "F.Fab")
			(hide yes)
			(effects
				(font
					(size 1.016 1.016)
					(thickness 0.1524)
				)
			)
		)
		(property "Device Type" "C402H22"
			(at 1.1811 -4.2291 270)
			(unlocked yes)
			(layer "F.Fab")
			(hide yes)
			(effects
				(font
					(size 1.016 1.016)
					(thickness 0.1524)
				)
			)
		)
		(duplicate_pad_numbers_are_jumpers no)
		(fp_rect
			(start -0.4318 0.9525)
			(end 0.4318 -0.9525)
			(stroke
				(width 0)
				(type default)
			)
			(fill no)
			(layer "F.CrtYd")
		)
		(fp_rect
			(start -0.4318 0.9525)
			(end 0.4318 -0.9525)
			(stroke
				(width 0)
				(type default)
			)
			(fill no)
			(layer "F.Fab")
		)
		(pad "1" smd custom
			(at 0 -0.4445 270)
			(size 0.1524 0.1524)
			(layers "F.Cu" "F.Mask" "F.Paste")
			(net "P1V8_C")
			(options
				(clearance outline)
				(anchor circle)
			)
			(primitives
				(gr_poly
					(pts
						(arc
							(start 0.3048 -0.2032)
							(mid 0.275042 -0.275042)
							(end 0.2032 -0.3048)
						)
						(arc
							(start -0.2032 -0.3048)
							(mid -0.275042 -0.275042)
							(end -0.3048 -0.2032)
						)
						(arc
							(start -0.3048 0.2032)
							(mid -0.275042 0.275042)
							(end -0.2032 0.3048)
						)
						(arc
							(start 0.2032 0.3048)
							(mid 0.275042 0.275042)
							(end 0.3048 0.2032)
						)
					)
					(width 0)
					(fill yes)
				)
			)
		)
		(pad "2" smd custom
			(at 0 0.4445 270)
			(size 0.1524 0.1524)
			(layers "F.Cu" "F.Mask" "F.Paste")
			(net "GND")
			(options
				(clearance outline)
				(anchor circle)
			)
			(primitives
				(gr_poly
					(pts
						(arc
							(start 0.3048 -0.2032)
							(mid 0.275042 -0.275042)
							(end 0.2032 -0.3048)
						)
						(arc
							(start -0.2032 -0.3048)
							(mid -0.275042 -0.275042)
							(end -0.3048 -0.2032)
						)
						(arc
							(start -0.3048 0.2032)
							(mid -0.275042 0.275042)
							(end -0.2032 0.3048)
						)
						(arc
							(start 0.2032 0.3048)
							(mid 0.275042 0.275042)
							(end 0.3048 0.2032)
						)
					)
					(width 0)
					(fill yes)
				)
			)
		)
	)
	(footprint ""
		(layer "F.Cu")
		(at 167.28694 -58.08345)
		(property "Reference" "R265"
			(at 0 0 0)
			(layer "F.SilkS")
			(hide yes)
			(effects
				(font
					(size 1.27 1.27)
				)
			)
		)
		(property "Value" "4K7R2F-GP"
			(at 0.064008 -3.993896 0)
			(unlocked yes)
			(layer "F.Fab")
			(hide yes)
			(effects
				(font
					(size 1.016 1.016)
					(thickness 0.1524)
				)
			)
		)
		(property "Device Type" "R402H16"
			(at 0.064008 -5.517896 0)
			(unlocked yes)
			(layer "F.Fab")
			(hide yes)
			(effects
				(font
					(size 1.016 1.016)
					(thickness 0.1524)
				)
			)
		)
		(duplicate_pad_numbers_are_jumpers no)
		(fp_line
			(start -0.508 -0.9398)
			(end -0.508 0.9398)
			(stroke
				(width 0.1524)
				(type default)
			)
			(layer "F.SilkS")
		)
		(fp_line
			(start 0.508 -0.9398)
			(end -0.508 -0.9398)
			(stroke
				(width 0.1524)
				(type default)
			)
			(layer "F.SilkS")
		)
		(fp_rect
			(start -0.508 0.9398)
			(end 0.508 -0.9398)
			(stroke
				(width 0)
				(type default)
			)
			(fill no)
			(layer "F.CrtYd")
		)
		(fp_rect
			(start -0.508 0.9398)
			(end 0.508 -0.9398)
			(stroke
				(width 0)
				(type default)
			)
			(fill no)
			(layer "F.Fab")
		)
		(pad "1" smd custom
			(at 0 -0.4445)
			(size 0.1397 0.1397)
			(layers "F.Cu" "F.Mask" "F.Paste")
			(net "P1V8_C")
			(options
				(clearance outline)
				(anchor circle)
			)
			(primitives
				(gr_poly
					(pts
						(arc
							(start -0.1778 -0.2794)
							(mid -0.249642 -0.249642)
							(end -0.2794 -0.1778)
						)
						(arc
							(start -0.2794 0.1778)
							(mid -0.249642 0.249642)
							(end -0.1778 0.2794)
						)
						(arc
							(start 0.1778 0.2794)
							(mid 0.249642 0.249642)
							(end 0.2794 0.1778)
						)
						(arc
							(start 0.2794 -0.1778)
							(mid 0.249642 -0.249642)
							(end 0.1778 -0.2794)
						)
					)
					(width 0)
					(fill yes)
				)
			)
		)
		(pad "2" smd custom
			(at 0 0.4445)
			(size 0.1397 0.1397)
			(layers "F.Cu" "F.Mask" "F.Paste")
			(net "ICE0_TDI")
			(options
				(clearance outline)
				(anchor circle)
			)
			(primitives
				(gr_poly
					(pts
						(arc
							(start -0.1778 -0.2794)
							(mid -0.249642 -0.249642)
							(end -0.2794 -0.1778)
						)
						(arc
							(start -0.2794 0.1778)
							(mid -0.249642 0.249642)
							(end -0.1778 0.2794)
						)
						(arc
							(start 0.1778 0.2794)
							(mid 0.249642 0.249642)
							(end 0.2794 0.1778)
						)
						(arc
							(start 0.2794 -0.1778)
							(mid 0.249642 -0.249642)
							(end 0.1778 -0.2794)
						)
					)
					(width 0)
					(fill yes)
				)
			)
		)
	)
	(footprint ""
		(layer "F.Cu")
		(at 59.6392 -72.6694)
		(property "Reference" "R424"
			(at 0 0 0)
			(layer "F.SilkS")
			(hide yes)
			(effects
				(font
					(size 1.27 1.27)
				)
			)
		)
		(property "Value" "0R2J-2-GP"
			(at 0.064008 -3.993896 0)
			(unlocked yes)
			(layer "F.Fab")
			(hide yes)
			(effects
				(font
					(size 1.016 1.016)
					(thickness 0.1524)
				)
			)
		)
		(property "Device Type" "R402H16"
			(at 0.064008 -5.517896 0)
			(unlocked yes)
			(layer "F.Fab")
			(hide yes)
			(effects
				(font
					(size 1.016 1.016)
					(thickness 0.1524)
				)
			)
		)
		(duplicate_pad_numbers_are_jumpers no)
		(fp_line
			(start -0.508 -0.9398)
			(end -0.508 0.9398)
			(stroke
				(width 0.1524)
				(type default)
			)
			(layer "F.SilkS")
		)
		(fp_line
			(start 0.508 -0.9398)
			(end -0.508 -0.9398)
			(stroke
				(width 0.1524)
				(type default)
			)
			(layer "F.SilkS")
		)
		(fp_rect
			(start -0.508 0.9398)
			(end 0.508 -0.9398)
			(stroke
				(width 0)
				(type default)
			)
			(fill no)
			(layer "F.CrtYd")
		)
		(fp_rect
			(start -0.508 0.9398)
			(end 0.508 -0.9398)
			(stroke
				(width 0)
				(type default)
			)
			(fill no)
			(layer "F.Fab")
		)
		(pad "1" smd custom
			(at 0 -0.4445)
			(size 0.1397 0.1397)
			(layers "F.Cu" "F.Mask" "F.Paste")
			(net "LS_EN_U37")
			(options
				(clearance outline)
				(anchor circle)
			)
			(primitives
				(gr_poly
					(pts
						(arc
							(start -0.1778 -0.2794)
							(mid -0.249642 -0.249642)
							(end -0.2794 -0.1778)
						)
						(arc
							(start -0.2794 0.1778)
							(mid -0.249642 0.249642)
							(end -0.1778 0.2794)
						)
						(arc
							(start 0.1778 0.2794)
							(mid 0.249642 0.249642)
							(end 0.2794 0.1778)
						)
						(arc
							(start 0.2794 -0.1778)
							(mid 0.249642 -0.249642)
							(end 0.1778 -0.2794)
						)
					)
					(width 0)
					(fill yes)
				)
			)
		)
		(pad "2" smd custom
			(at 0 0.4445)
			(size 0.1397 0.1397)
			(layers "F.Cu" "F.Mask" "F.Paste")
			(net "VREF4")
			(options
				(clearance outline)
				(anchor circle)
			)
			(primitives
				(gr_poly
					(pts
						(arc
							(start -0.1778 -0.2794)
							(mid -0.249642 -0.249642)
							(end -0.2794 -0.1778)
						)
						(arc
							(start -0.2794 0.1778)
							(mid -0.249642 0.249642)
							(end -0.1778 0.2794)
						)
						(arc
							(start 0.1778 0.2794)
							(mid 0.249642 0.249642)
							(end 0.2794 0.1778)
						)
						(arc
							(start 0.2794 -0.1778)
							(mid 0.249642 -0.249642)
							(end 0.1778 -0.2794)
						)
					)
					(width 0)
					(fill yes)
				)
			)
		)
	)
	(footprint ""
		(layer "F.Cu")
		(at 71.882 -103.505 180)
		(property "Reference" "R513"
			(at 0 0 180)
			(layer "F.SilkS")
			(hide yes)
			(effects
				(font
					(size 1.27 1.27)
				)
			)
		)
		(property "Value" "44K2R2F-1-GP"
			(at 0.064008 -3.993896 180)
			(unlocked yes)
			(layer "F.Fab")
			(hide yes)
			(effects
				(font
					(size 1.016 1.016)
					(thickness 0.1524)
				)
			)
		)
		(property "Device Type" "R402H16"
			(at 0.064008 -5.517896 180)
			(unlocked yes)
			(layer "F.Fab")
			(hide yes)
			(effects
				(font
					(size 1.016 1.016)
					(thickness 0.1524)
				)
			)
		)
		(duplicate_pad_numbers_are_jumpers no)
		(fp_line
			(start 0.508 -0.9398)
			(end -0.508 -0.9398)
			(stroke
				(width 0.1524)
				(type default)
			)
			(layer "F.SilkS")
		)
		(fp_line
			(start -0.508 -0.9398)
			(end -0.508 0.9398)
			(stroke
				(width 0.1524)
				(type default)
			)
			(layer "F.SilkS")
		)
		(fp_rect
			(start -0.508 0.9398)
			(end 0.508 -0.9398)
			(stroke
				(width 0)
				(type default)
			)
			(fill no)
			(layer "F.CrtYd")
		)
		(fp_rect
			(start -0.508 0.9398)
			(end 0.508 -0.9398)
			(stroke
				(width 0)
				(type default)
			)
			(fill no)
			(layer "F.Fab")
		)
		(pad "1" smd custom
			(at 0 -0.4445 180)
			(size 0.1397 0.1397)
			(layers "F.Cu" "F.Mask" "F.Paste")
			(net "P3V3_VFB")
			(options
				(clearance outline)
				(anchor circle)
			)
			(primitives
				(gr_poly
					(pts
						(arc
							(start -0.1778 -0.2794)
							(mid -0.249642 -0.249642)
							(end -0.2794 -0.1778)
						)
						(arc
							(start -0.2794 0.1778)
							(mid -0.249642 0.249642)
							(end -0.1778 0.2794)
						)
						(arc
							(start 0.1778 0.2794)
							(mid 0.249642 0.249642)
							(end 0.2794 0.1778)
						)
						(arc
							(start 0.2794 -0.1778)
							(mid 0.249642 -0.249642)
							(end 0.1778 -0.2794)
						)
					)
					(width 0)
					(fill yes)
				)
			)
		)
		(pad "2" smd custom
			(at 0 0.4445 180)
			(size 0.1397 0.1397)
			(layers "F.Cu" "F.Mask" "F.Paste")
			(net "P3V3_VFB_R")
			(options
				(clearance outline)
				(anchor circle)
			)
			(primitives
				(gr_poly
					(pts
						(arc
							(start -0.1778 -0.2794)
							(mid -0.249642 -0.249642)
							(end -0.2794 -0.1778)
						)
						(arc
							(start -0.2794 0.1778)
							(mid -0.249642 0.249642)
							(end -0.1778 0.2794)
						)
						(arc
							(start 0.1778 0.2794)
							(mid 0.249642 0.249642)
							(end 0.2794 0.1778)
						)
						(arc
							(start 0.2794 -0.1778)
							(mid 0.249642 -0.249642)
							(end 0.1778 -0.2794)
						)
					)
					(width 0)
					(fill yes)
				)
			)
		)
	)
	(footprint ""
		(layer "F.Cu")
		(at 191.902842 -23.32101 180)
		(property "Reference" "R259"
			(at 0 0 180)
			(layer "F.SilkS")
			(hide yes)
			(effects
				(font
					(size 1.27 1.27)
				)
			)
		)
		(property "Value" "4K7R2F-GP"
			(at 0.064008 -3.993896 180)
			(unlocked yes)
			(layer "F.Fab")
			(hide yes)
			(effects
				(font
					(size 1.016 1.016)
					(thickness 0.1524)
				)
			)
		)
		(property "Device Type" "R402H16"
			(at 0.064008 -5.517896 180)
			(unlocked yes)
			(layer "F.Fab")
			(hide yes)
			(effects
				(font
					(size 1.016 1.016)
					(thickness 0.1524)
				)
			)
		)
		(duplicate_pad_numbers_are_jumpers no)
		(fp_line
			(start 0.508 -0.9398)
			(end -0.508 -0.9398)
			(stroke
				(width 0.1524)
				(type default)
			)
			(layer "F.SilkS")
		)
		(fp_line
			(start -0.508 -0.9398)
			(end -0.508 0.9398)
			(stroke
				(width 0.1524)
				(type default)
			)
			(layer "F.SilkS")
		)
		(fp_rect
			(start -0.508 0.9398)
			(end 0.508 -0.9398)
			(stroke
				(width 0)
				(type default)
			)
			(fill no)
			(layer "F.CrtYd")
		)
		(fp_rect
			(start -0.508 0.9398)
			(end 0.508 -0.9398)
			(stroke
				(width 0)
				(type default)
			)
			(fill no)
			(layer "F.Fab")
		)
		(pad "1" smd custom
			(at 0 -0.4445 180)
			(size 0.1397 0.1397)
			(layers "F.Cu" "F.Mask" "F.Paste")
			(net "P1V8_C")
			(options
				(clearance outline)
				(anchor circle)
			)
			(primitives
				(gr_poly
					(pts
						(arc
							(start -0.1778 -0.2794)
							(mid -0.249642 -0.249642)
							(end -0.2794 -0.1778)
						)
						(arc
							(start -0.2794 0.1778)
							(mid -0.249642 0.249642)
							(end -0.1778 0.2794)
						)
						(arc
							(start 0.1778 0.2794)
							(mid 0.249642 0.249642)
							(end 0.2794 0.1778)
						)
						(arc
							(start 0.2794 -0.1778)
							(mid 0.249642 -0.249642)
							(end 0.1778 -0.2794)
						)
					)
					(width 0)
					(fill yes)
				)
			)
		)
		(pad "2" smd custom
			(at 0 0.4445 180)
			(size 0.1397 0.1397)
			(layers "F.Cu" "F.Mask" "F.Paste")
			(net "SYS_HALT1#")
			(options
				(clearance outline)
				(anchor circle)
			)
			(primitives
				(gr_poly
					(pts
						(arc
							(start -0.1778 -0.2794)
							(mid -0.249642 -0.249642)
							(end -0.2794 -0.1778)
						)
						(arc
							(start -0.2794 0.1778)
							(mid -0.249642 0.249642)
							(end -0.1778 0.2794)
						)
						(arc
							(start 0.1778 0.2794)
							(mid 0.249642 0.249642)
							(end 0.2794 0.1778)
						)
						(arc
							(start 0.2794 -0.1778)
							(mid 0.249642 -0.249642)
							(end 0.1778 -0.2794)
						)
					)
					(width 0)
					(fill yes)
				)
			)
		)
	)
	(footprint ""
		(layer "F.Cu")
		(at 174.645574 -100.109782)
		(property "Reference" "R492"
			(at 0 0 0)
			(layer "F.SilkS")
			(hide yes)
			(effects
				(font
					(size 1.27 1.27)
				)
			)
		)
		(property "Value" "19K1R2F-GP"
			(at 0.064008 -3.993896 0)
			(unlocked yes)
			(layer "F.Fab")
			(hide yes)
			(effects
				(font
					(size 1.016 1.016)
					(thickness 0.1524)
				)
			)
		)
		(property "Device Type" "R402H16"
			(at 0.064008 -5.517896 0)
			(unlocked yes)
			(layer "F.Fab")
			(hide yes)
			(effects
				(font
					(size 1.016 1.016)
					(thickness 0.1524)
				)
			)
		)
		(duplicate_pad_numbers_are_jumpers no)
		(fp_line
			(start -0.508 -0.9398)
			(end -0.508 0.9398)
			(stroke
				(width 0.1524)
				(type default)
			)
			(layer "F.SilkS")
		)
		(fp_line
			(start 0.508 -0.9398)
			(end -0.508 -0.9398)
			(stroke
				(width 0.1524)
				(type default)
			)
			(layer "F.SilkS")
		)
		(fp_rect
			(start -0.508 0.9398)
			(end 0.508 -0.9398)
			(stroke
				(width 0)
				(type default)
			)
			(fill no)
			(layer "F.CrtYd")
		)
		(fp_rect
			(start -0.508 0.9398)
			(end 0.508 -0.9398)
			(stroke
				(width 0)
				(type default)
			)
			(fill no)
			(layer "F.Fab")
		)
		(pad "1" smd custom
			(at 0 -0.4445)
			(size 0.1397 0.1397)
			(layers "F.Cu" "F.Mask" "F.Paste")
			(net "P0V975")
			(options
				(clearance outline)
				(anchor circle)
			)
			(primitives
				(gr_poly
					(pts
						(arc
							(start -0.1778 -0.2794)
							(mid -0.249642 -0.249642)
							(end -0.2794 -0.1778)
						)
						(arc
							(start -0.2794 0.1778)
							(mid -0.249642 0.249642)
							(end -0.1778 0.2794)
						)
						(arc
							(start 0.1778 0.2794)
							(mid 0.249642 0.249642)
							(end 0.2794 0.1778)
						)
						(arc
							(start 0.2794 -0.1778)
							(mid 0.249642 -0.249642)
							(end 0.1778 -0.2794)
						)
					)
					(width 0)
					(fill yes)
				)
			)
		)
		(pad "2" smd custom
			(at 0 0.4445)
			(size 0.1397 0.1397)
			(layers "F.Cu" "F.Mask" "F.Paste")
			(net "VT235_PGIN")
			(options
				(clearance outline)
				(anchor circle)
			)
			(primitives
				(gr_poly
					(pts
						(arc
							(start -0.1778 -0.2794)
							(mid -0.249642 -0.249642)
							(end -0.2794 -0.1778)
						)
						(arc
							(start -0.2794 0.1778)
							(mid -0.249642 0.249642)
							(end -0.1778 0.2794)
						)
						(arc
							(start 0.1778 0.2794)
							(mid 0.249642 0.249642)
							(end 0.2794 0.1778)
						)
						(arc
							(start 0.2794 -0.1778)
							(mid 0.249642 -0.249642)
							(end 0.1778 -0.2794)
						)
					)
					(width 0)
					(fill yes)
				)
			)
		)
	)
	(footprint ""
		(layer "F.Cu")
		(at 189.2808 -21.9202 -90)
		(property "Reference" "R250"
			(at 0 0 270)
			(layer "F.SilkS")
			(hide yes)
			(effects
				(font
					(size 1.27 1.27)
				)
			)
		)
		(property "Value" "10KR2F-2-GP"
			(at 0.064008 -3.993896 270)
			(unlocked yes)
			(layer "F.Fab")
			(hide yes)
			(effects
				(font
					(size 1.016 1.016)
					(thickness 0.1524)
				)
			)
		)
		(property "Device Type" "R402H16"
			(at 0.064008 -5.517896 270)
			(unlocked yes)
			(layer "F.Fab")
			(hide yes)
			(effects
				(font
					(size 1.016 1.016)
					(thickness 0.1524)
				)
			)
		)
		(duplicate_pad_numbers_are_jumpers no)
		(fp_line
			(start -0.508 -0.9398)
			(end -0.508 0.9398)
			(stroke
				(width 0.1524)
				(type default)
			)
			(layer "F.SilkS")
		)
		(fp_line
			(start 0.508 -0.9398)
			(end -0.508 -0.9398)
			(stroke
				(width 0.1524)
				(type default)
			)
			(layer "F.SilkS")
		)
		(fp_rect
			(start -0.508 0.9398)
			(end 0.508 -0.9398)
			(stroke
				(width 0)
				(type default)
			)
			(fill no)
			(layer "F.CrtYd")
		)
		(fp_rect
			(start -0.508 0.9398)
			(end 0.508 -0.9398)
			(stroke
				(width 0)
				(type default)
			)
			(fill no)
			(layer "F.Fab")
		)
		(pad "1" smd custom
			(at 0 -0.4445 270)
			(size 0.1397 0.1397)
			(layers "F.Cu" "F.Mask" "F.Paste")
			(net "P1V8_C")
			(options
				(clearance outline)
				(anchor circle)
			)
			(primitives
				(gr_poly
					(pts
						(arc
							(start -0.1778 -0.2794)
							(mid -0.249642 -0.249642)
							(end -0.2794 -0.1778)
						)
						(arc
							(start -0.2794 0.1778)
							(mid -0.249642 0.249642)
							(end -0.1778 0.2794)
						)
						(arc
							(start 0.1778 0.2794)
							(mid 0.249642 0.249642)
							(end 0.2794 0.1778)
						)
						(arc
							(start 0.2794 -0.1778)
							(mid 0.249642 -0.249642)
							(end 0.1778 -0.2794)
						)
					)
					(width 0)
					(fill yes)
				)
			)
		)
		(pad "2" smd custom
			(at 0 0.4445 270)
			(size 0.1397 0.1397)
			(layers "F.Cu" "F.Mask" "F.Paste")
			(net "SYS_DBMODE1")
			(options
				(clearance outline)
				(anchor circle)
			)
			(primitives
				(gr_poly
					(pts
						(arc
							(start -0.1778 -0.2794)
							(mid -0.249642 -0.249642)
							(end -0.2794 -0.1778)
						)
						(arc
							(start -0.2794 0.1778)
							(mid -0.249642 0.249642)
							(end -0.1778 0.2794)
						)
						(arc
							(start 0.1778 0.2794)
							(mid 0.249642 0.249642)
							(end 0.2794 0.1778)
						)
						(arc
							(start 0.2794 -0.1778)
							(mid 0.249642 -0.249642)
							(end 0.1778 -0.2794)
						)
					)
					(width 0)
					(fill yes)
				)
			)
		)
	)
	(footprint ""
		(layer "F.Cu")
		(at 147.591526 -40.237664 102)
		(property "Reference" "C336"
			(at 0 0 102)
			(layer "F.SilkS")
			(hide yes)
			(effects
				(font
					(size 1.27 1.27)
				)
			)
		)
		(property "Value" "SCD01U16V1KX-GP"
			(at -2.832296 -1.73983 102)
			(unlocked yes)
			(layer "F.Fab")
			(hide yes)
			(effects
				(font
					(size 1.016 1.016)
					(thickness 0.1524)
				)
			)
		)
		(property "Device Type" "C0201H13"
			(at -2.832174 -3.263834 102)
			(unlocked yes)
			(layer "F.Fab")
			(hide yes)
			(effects
				(font
					(size 1.016 1.016)
					(thickness 0.1524)
				)
			)
		)
		(duplicate_pad_numbers_are_jumpers no)
		(fp_poly
			(pts
				(xy -0.279454 -0.647706) (xy 0.279346 -0.647706) (xy 0.279346 0.647694) (xy -0.279454 0.647694)
			)
			(stroke
				(width 0)
				(type default)
			)
			(fill no)
			(layer "F.CrtYd")
		)
		(fp_poly
			(pts
				(xy -0.279454 -0.647706) (xy 0.279346 -0.647706) (xy 0.279346 0.647694) (xy -0.279454 0.647694)
			)
			(stroke
				(width 0)
				(type default)
			)
			(fill no)
			(layer "F.Fab")
		)
		(pad "1" smd custom
			(at -0.000001 -0.2794 102)
			(size 0.0762 0.0762)
			(layers "F.Cu" "F.Mask" "F.Paste")
			(net "PHY_SCC_TO_IOC_43_DN")
			(options
				(clearance outline)
				(anchor circle)
			)
			(primitives
				(gr_poly
					(pts
						(arc
							(start 0.1524 -0.127)
							(mid 0.137521 -0.162921)
							(end 0.1016 -0.1778)
						)
						(arc
							(start -0.1016 -0.1778)
							(mid -0.137521 -0.162921)
							(end -0.1524 -0.127)
						)
						(arc
							(start -0.1524 0.127)
							(mid -0.137521 0.162921)
							(end -0.1016 0.1778)
						)
						(arc
							(start 0.1016 0.1778)
							(mid 0.137521 0.162921)
							(end 0.1524 0.127)
						)
					)
					(width 0)
					(fill yes)
				)
			)
		)
		(pad "2" smd custom
			(at 0.000001 0.2794 102)
			(size 0.0762 0.0762)
			(layers "F.Cu" "F.Mask" "F.Paste")
			(net "PHY_SCC_TO_IOC_C_43_DN")
			(options
				(clearance outline)
				(anchor circle)
			)
			(primitives
				(gr_poly
					(pts
						(arc
							(start 0.1524 -0.127)
							(mid 0.137521 -0.162921)
							(end 0.1016 -0.1778)
						)
						(arc
							(start -0.1016 -0.1778)
							(mid -0.137521 -0.162921)
							(end -0.1524 -0.127)
						)
						(arc
							(start -0.1524 0.127)
							(mid -0.137521 0.162921)
							(end -0.1016 0.1778)
						)
						(arc
							(start 0.1016 0.1778)
							(mid 0.137521 0.162921)
							(end 0.1524 0.127)
						)
					)
					(width 0)
					(fill yes)
				)
			)
		)
	)
	(footprint ""
		(layer "F.Cu")
		(at 67.3735 -94.6023)
		(property "Reference" "R508"
			(at 0 0 0)
			(layer "F.SilkS")
			(hide yes)
			(effects
				(font
					(size 1.27 1.27)
				)
			)
		)
		(property "Value" "475KR2F-GP"
			(at 0.064008 -3.993896 0)
			(unlocked yes)
			(layer "F.Fab")
			(hide yes)
			(effects
				(font
					(size 1.016 1.016)
					(thickness 0.1524)
				)
			)
		)
		(property "Device Type" "R402H16"
			(at 0.064008 -5.517896 0)
			(unlocked yes)
			(layer "F.Fab")
			(hide yes)
			(effects
				(font
					(size 1.016 1.016)
					(thickness 0.1524)
				)
			)
		)
		(duplicate_pad_numbers_are_jumpers no)
		(fp_line
			(start -0.508 -0.9398)
			(end -0.508 0.9398)
			(stroke
				(width 0.1524)
				(type default)
			)
			(layer "F.SilkS")
		)
		(fp_line
			(start 0.508 -0.9398)
			(end -0.508 -0.9398)
			(stroke
				(width 0.1524)
				(type default)
			)
			(layer "F.SilkS")
		)
		(fp_rect
			(start -0.508 0.9398)
			(end 0.508 -0.9398)
			(stroke
				(width 0)
				(type default)
			)
			(fill no)
			(layer "F.CrtYd")
		)
		(fp_rect
			(start -0.508 0.9398)
			(end 0.508 -0.9398)
			(stroke
				(width 0)
				(type default)
			)
			(fill no)
			(layer "F.Fab")
		)
		(pad "1" smd custom
			(at 0 -0.4445)
			(size 0.1397 0.1397)
			(layers "F.Cu" "F.Mask" "F.Paste")
			(net "P3V3_MODE")
			(options
				(clearance outline)
				(anchor circle)
			)
			(primitives
				(gr_poly
					(pts
						(arc
							(start -0.1778 -0.2794)
							(mid -0.249642 -0.249642)
							(end -0.2794 -0.1778)
						)
						(arc
							(start -0.2794 0.1778)
							(mid -0.249642 0.249642)
							(end -0.1778 0.2794)
						)
						(arc
							(start 0.1778 0.2794)
							(mid 0.249642 0.249642)
							(end 0.2794 0.1778)
						)
						(arc
							(start 0.2794 -0.1778)
							(mid 0.249642 -0.249642)
							(end 0.1778 -0.2794)
						)
					)
					(width 0)
					(fill yes)
				)
			)
		)
		(pad "2" smd custom
			(at 0 0.4445)
			(size 0.1397 0.1397)
			(layers "F.Cu" "F.Mask" "F.Paste")
			(net "SCC_STBY_PGOOD_BUF")
			(options
				(clearance outline)
				(anchor circle)
			)
			(primitives
				(gr_poly
					(pts
						(arc
							(start -0.1778 -0.2794)
							(mid -0.249642 -0.249642)
							(end -0.2794 -0.1778)
						)
						(arc
							(start -0.2794 0.1778)
							(mid -0.249642 0.249642)
							(end -0.1778 0.2794)
						)
						(arc
							(start 0.1778 0.2794)
							(mid 0.249642 0.249642)
							(end 0.2794 0.1778)
						)
						(arc
							(start 0.2794 -0.1778)
							(mid 0.249642 -0.249642)
							(end 0.1778 -0.2794)
						)
					)
					(width 0)
					(fill yes)
				)
			)
		)
	)
	(footprint ""
		(layer "F.Cu")
		(at 80.7847 -74.9046 180)
		(property "Reference" "R94"
			(at 0 0 180)
			(layer "F.SilkS")
			(hide yes)
			(effects
				(font
					(size 1.27 1.27)
				)
			)
		)
		(property "Value" "150R2F-1-GP"
			(at 0.064008 -3.993896 180)
			(unlocked yes)
			(layer "F.Fab")
			(hide yes)
			(effects
				(font
					(size 1.016 1.016)
					(thickness 0.1524)
				)
			)
		)
		(property "Device Type" "R402H16"
			(at 0.064008 -5.517896 180)
			(unlocked yes)
			(layer "F.Fab")
			(hide yes)
			(effects
				(font
					(size 1.016 1.016)
					(thickness 0.1524)
				)
			)
		)
		(duplicate_pad_numbers_are_jumpers no)
		(fp_line
			(start 0.508 -0.9398)
			(end -0.508 -0.9398)
			(stroke
				(width 0.1524)
				(type default)
			)
			(layer "F.SilkS")
		)
		(fp_line
			(start -0.508 -0.9398)
			(end -0.508 0.9398)
			(stroke
				(width 0.1524)
				(type default)
			)
			(layer "F.SilkS")
		)
		(fp_rect
			(start -0.508 0.9398)
			(end 0.508 -0.9398)
			(stroke
				(width 0)
				(type default)
			)
			(fill no)
			(layer "F.CrtYd")
		)
		(fp_rect
			(start -0.508 0.9398)
			(end 0.508 -0.9398)
			(stroke
				(width 0)
				(type default)
			)
			(fill no)
			(layer "F.Fab")
		)
		(pad "1" smd custom
			(at 0 -0.4445 180)
			(size 0.1397 0.1397)
			(layers "F.Cu" "F.Mask" "F.Paste")
			(net "P3V3")
			(options
				(clearance outline)
				(anchor circle)
			)
			(primitives
				(gr_poly
					(pts
						(arc
							(start -0.1778 -0.2794)
							(mid -0.249642 -0.249642)
							(end -0.2794 -0.1778)
						)
						(arc
							(start -0.2794 0.1778)
							(mid -0.249642 0.249642)
							(end -0.1778 0.2794)
						)
						(arc
							(start 0.1778 0.2794)
							(mid 0.249642 0.249642)
							(end 0.2794 0.1778)
						)
						(arc
							(start 0.2794 -0.1778)
							(mid 0.249642 -0.249642)
							(end 0.1778 -0.2794)
						)
					)
					(width 0)
					(fill yes)
				)
			)
		)
		(pad "2" smd custom
			(at 0 0.4445 180)
			(size 0.1397 0.1397)
			(layers "F.Cu" "F.Mask" "F.Paste")
			(net "EXP_HW_LED_R")
			(options
				(clearance outline)
				(anchor circle)
			)
			(primitives
				(gr_poly
					(pts
						(arc
							(start -0.1778 -0.2794)
							(mid -0.249642 -0.249642)
							(end -0.2794 -0.1778)
						)
						(arc
							(start -0.2794 0.1778)
							(mid -0.249642 0.249642)
							(end -0.1778 0.2794)
						)
						(arc
							(start 0.1778 0.2794)
							(mid 0.249642 0.249642)
							(end 0.2794 0.1778)
						)
						(arc
							(start 0.2794 -0.1778)
							(mid 0.249642 -0.249642)
							(end 0.1778 -0.2794)
						)
					)
					(width 0)
					(fill yes)
				)
			)
		)
	)
	(footprint ""
		(layer "F.Cu")
		(at 43.0022 -43.4086)
		(property "Reference" "C666"
			(at 0 0 0)
			(layer "F.SilkS")
			(hide yes)
			(effects
				(font
					(size 1.27 1.27)
				)
			)
		)
		(property "Value" "SC10U16V5KX-7-GP-U"
			(at -0.0762 -6.1214 0)
			(unlocked yes)
			(layer "F.Fab")
			(hide yes)
			(effects
				(font
					(size 1.016 1.016)
					(thickness 0.1524)
				)
			)
		)
		(property "Device Type" "C805H58"
			(at -0.0762 -8.1534 0)
			(unlocked yes)
			(layer "F.Fab")
			(hide yes)
			(effects
				(font
					(size 1.016 1.016)
					(thickness 0.1524)
				)
			)
		)
		(duplicate_pad_numbers_are_jumpers no)
		(fp_line
			(start 0.635 0)
			(end -0.635 0)
			(stroke
				(width 0.508)
				(type default)
			)
			(layer "F.SilkS")
		)
		(fp_rect
			(start -0.9652 1.778)
			(end 0.9652 -1.778)
			(stroke
				(width 0)
				(type default)
			)
			(fill no)
			(layer "F.CrtYd")
		)
		(fp_poly
			(pts
				(xy -0.9652 -1.778) (xy 0.9652 -1.778) (xy 0.9652 1.778) (xy -0.9652 1.778)
			)
			(stroke
				(width 0)
				(type default)
			)
			(fill no)
			(layer "F.Fab")
		)
		(pad "1" smd rect
			(at 0 -0.9652)
			(size 1.397 1.143)
			(layers "F.Cu" "F.Mask" "F.Paste")
			(net "P12V_STBY_VIN_Q7")
		)
		(pad "2" smd rect
			(at 0 0.9652)
			(size 1.397 1.143)
			(layers "F.Cu" "F.Mask" "F.Paste")
			(net "GND")
		)
	)
	(footprint ""
		(layer "F.Cu")
		(at 19.177 -59.1312)
		(property "Reference" "R536"
			(at 0 0 0)
			(layer "F.SilkS")
			(hide yes)
			(effects
				(font
					(size 1.27 1.27)
				)
			)
		)
		(property "Value" "0R2J-2-GP"
			(at 0.064008 -3.993896 0)
			(unlocked yes)
			(layer "F.Fab")
			(hide yes)
			(effects
				(font
					(size 1.016 1.016)
					(thickness 0.1524)
				)
			)
		)
		(property "Device Type" "R402H16"
			(at 0.064008 -5.517896 0)
			(unlocked yes)
			(layer "F.Fab")
			(hide yes)
			(effects
				(font
					(size 1.016 1.016)
					(thickness 0.1524)
				)
			)
		)
		(duplicate_pad_numbers_are_jumpers no)
		(fp_line
			(start -0.508 -0.9398)
			(end -0.508 0.9398)
			(stroke
				(width 0.1524)
				(type default)
			)
			(layer "F.SilkS")
		)
		(fp_line
			(start 0.508 -0.9398)
			(end -0.508 -0.9398)
			(stroke
				(width 0.1524)
				(type default)
			)
			(layer "F.SilkS")
		)
		(fp_rect
			(start -0.508 0.9398)
			(end 0.508 -0.9398)
			(stroke
				(width 0)
				(type default)
			)
			(fill no)
			(layer "F.CrtYd")
		)
		(fp_rect
			(start -0.508 0.9398)
			(end 0.508 -0.9398)
			(stroke
				(width 0)
				(type default)
			)
			(fill no)
			(layer "F.Fab")
		)
		(pad "1" smd custom
			(at 0 -0.4445)
			(size 0.1397 0.1397)
			(layers "F.Cu" "F.Mask" "F.Paste")
			(net "AGND_CURRENT_MON")
			(options
				(clearance outline)
				(anchor circle)
			)
			(primitives
				(gr_poly
					(pts
						(arc
							(start -0.1778 -0.2794)
							(mid -0.249642 -0.249642)
							(end -0.2794 -0.1778)
						)
						(arc
							(start -0.2794 0.1778)
							(mid -0.249642 0.249642)
							(end -0.1778 0.2794)
						)
						(arc
							(start 0.1778 0.2794)
							(mid 0.249642 0.249642)
							(end 0.2794 0.1778)
						)
						(arc
							(start 0.2794 -0.1778)
							(mid 0.249642 -0.249642)
							(end 0.1778 -0.2794)
						)
					)
					(width 0)
					(fill yes)
				)
			)
		)
		(pad "2" smd custom
			(at 0 0.4445)
			(size 0.1397 0.1397)
			(layers "F.Cu" "F.Mask" "F.Paste")
			(net "MB0_CM_ADR1_R")
			(options
				(clearance outline)
				(anchor circle)
			)
			(primitives
				(gr_poly
					(pts
						(arc
							(start -0.1778 -0.2794)
							(mid -0.249642 -0.249642)
							(end -0.2794 -0.1778)
						)
						(arc
							(start -0.2794 0.1778)
							(mid -0.249642 0.249642)
							(end -0.1778 0.2794)
						)
						(arc
							(start 0.1778 0.2794)
							(mid 0.249642 0.249642)
							(end 0.2794 0.1778)
						)
						(arc
							(start 0.2794 -0.1778)
							(mid 0.249642 -0.249642)
							(end 0.1778 -0.2794)
						)
					)
					(width 0)
					(fill yes)
				)
			)
		)
	)
	(footprint ""
		(layer "F.Cu")
		(at 194.01536 -67.31254 180)
		(property "Reference" "R299"
			(at 0 0 180)
			(layer "F.SilkS")
			(hide yes)
			(effects
				(font
					(size 1.27 1.27)
				)
			)
		)
		(property "Value" "0R2J-2-GP"
			(at 0.064008 -3.993896 180)
			(unlocked yes)
			(layer "F.Fab")
			(hide yes)
			(effects
				(font
					(size 1.016 1.016)
					(thickness 0.1524)
				)
			)
		)
		(property "Device Type" "R402H16"
			(at 0.064008 -5.517896 180)
			(unlocked yes)
			(layer "F.Fab")
			(hide yes)
			(effects
				(font
					(size 1.016 1.016)
					(thickness 0.1524)
				)
			)
		)
		(duplicate_pad_numbers_are_jumpers no)
		(fp_line
			(start 0.508 -0.9398)
			(end -0.508 -0.9398)
			(stroke
				(width 0.1524)
				(type default)
			)
			(layer "F.SilkS")
		)
		(fp_line
			(start -0.508 -0.9398)
			(end -0.508 0.9398)
			(stroke
				(width 0.1524)
				(type default)
			)
			(layer "F.SilkS")
		)
		(fp_rect
			(start -0.508 0.9398)
			(end 0.508 -0.9398)
			(stroke
				(width 0)
				(type default)
			)
			(fill no)
			(layer "F.CrtYd")
		)
		(fp_rect
			(start -0.508 0.9398)
			(end 0.508 -0.9398)
			(stroke
				(width 0)
				(type default)
			)
			(fill no)
			(layer "F.Fab")
		)
		(pad "1" smd custom
			(at 0 -0.4445 180)
			(size 0.1397 0.1397)
			(layers "F.Cu" "F.Mask" "F.Paste")
			(net "UART_IOC_RX")
			(options
				(clearance outline)
				(anchor circle)
			)
			(primitives
				(gr_poly
					(pts
						(arc
							(start -0.1778 -0.2794)
							(mid -0.249642 -0.249642)
							(end -0.2794 -0.1778)
						)
						(arc
							(start -0.2794 0.1778)
							(mid -0.249642 0.249642)
							(end -0.1778 0.2794)
						)
						(arc
							(start 0.1778 0.2794)
							(mid 0.249642 0.249642)
							(end 0.2794 0.1778)
						)
						(arc
							(start 0.2794 -0.1778)
							(mid 0.249642 -0.249642)
							(end 0.1778 -0.2794)
						)
					)
					(width 0)
					(fill yes)
				)
			)
		)
		(pad "2" smd custom
			(at 0 0.4445 180)
			(size 0.1397 0.1397)
			(layers "F.Cu" "F.Mask" "F.Paste")
			(net "IOC_UART_R_RX")
			(options
				(clearance outline)
				(anchor circle)
			)
			(primitives
				(gr_poly
					(pts
						(arc
							(start -0.1778 -0.2794)
							(mid -0.249642 -0.249642)
							(end -0.2794 -0.1778)
						)
						(arc
							(start -0.2794 0.1778)
							(mid -0.249642 0.249642)
							(end -0.1778 0.2794)
						)
						(arc
							(start 0.1778 0.2794)
							(mid 0.249642 0.249642)
							(end 0.2794 0.1778)
						)
						(arc
							(start 0.2794 -0.1778)
							(mid 0.249642 -0.249642)
							(end 0.1778 -0.2794)
						)
					)
					(width 0)
					(fill yes)
				)
			)
		)
	)
	(footprint ""
		(layer "F.Cu")
		(at 74.4474 -83.3882 90)
		(property "Reference" "C598"
			(at 0 0 90)
			(layer "F.SilkS")
			(hide yes)
			(effects
				(font
					(size 1.27 1.27)
				)
			)
		)
		(property "Value" "SCD1U16V2KX-3GP"
			(at 1.1811 -2.7051 90)
			(unlocked yes)
			(layer "F.Fab")
			(hide yes)
			(effects
				(font
					(size 1.016 1.016)
					(thickness 0.1524)
				)
			)
		)
		(property "Device Type" "C402H22"
			(at 1.1811 -4.2291 90)
			(unlocked yes)
			(layer "F.Fab")
			(hide yes)
			(effects
				(font
					(size 1.016 1.016)
					(thickness 0.1524)
				)
			)
		)
		(duplicate_pad_numbers_are_jumpers no)
		(fp_rect
			(start -0.4318 0.9525)
			(end 0.4318 -0.9525)
			(stroke
				(width 0)
				(type default)
			)
			(fill no)
			(layer "F.CrtYd")
		)
		(fp_rect
			(start -0.4318 0.9525)
			(end 0.4318 -0.9525)
			(stroke
				(width 0)
				(type default)
			)
			(fill no)
			(layer "F.Fab")
		)
		(pad "1" smd custom
			(at 0 -0.4445 90)
			(size 0.1524 0.1524)
			(layers "F.Cu" "F.Mask" "F.Paste")
			(net "P1V8_E")
			(options
				(clearance outline)
				(anchor circle)
			)
			(primitives
				(gr_poly
					(pts
						(arc
							(start 0.3048 -0.2032)
							(mid 0.275042 -0.275042)
							(end 0.2032 -0.3048)
						)
						(arc
							(start -0.2032 -0.3048)
							(mid -0.275042 -0.275042)
							(end -0.3048 -0.2032)
						)
						(arc
							(start -0.3048 0.2032)
							(mid -0.275042 0.275042)
							(end -0.2032 0.3048)
						)
						(arc
							(start 0.2032 0.3048)
							(mid 0.275042 0.275042)
							(end 0.3048 0.2032)
						)
					)
					(width 0)
					(fill yes)
				)
			)
		)
		(pad "2" smd custom
			(at 0 0.4445 90)
			(size 0.1524 0.1524)
			(layers "F.Cu" "F.Mask" "F.Paste")
			(net "GND")
			(options
				(clearance outline)
				(anchor circle)
			)
			(primitives
				(gr_poly
					(pts
						(arc
							(start 0.3048 -0.2032)
							(mid 0.275042 -0.275042)
							(end 0.2032 -0.3048)
						)
						(arc
							(start -0.2032 -0.3048)
							(mid -0.275042 -0.275042)
							(end -0.3048 -0.2032)
						)
						(arc
							(start -0.3048 0.2032)
							(mid -0.275042 0.275042)
							(end -0.2032 0.3048)
						)
						(arc
							(start 0.2032 0.3048)
							(mid 0.275042 0.275042)
							(end 0.3048 0.2032)
						)
					)
					(width 0)
					(fill yes)
				)
			)
		)
	)
	(footprint ""
		(layer "F.Cu")
		(at 171.661074 -100.160582 180)
		(property "Reference" "R495"
			(at 0 0 180)
			(layer "F.SilkS")
			(hide yes)
			(effects
				(font
					(size 1.27 1.27)
				)
			)
		)
		(property "Value" "100KR2F-L1-GP"
			(at 0.064008 -3.993896 180)
			(unlocked yes)
			(layer "F.Fab")
			(hide yes)
			(effects
				(font
					(size 1.016 1.016)
					(thickness 0.1524)
				)
			)
		)
		(property "Device Type" "R402H16"
			(at 0.064008 -5.517896 180)
			(unlocked yes)
			(layer "F.Fab")
			(hide yes)
			(effects
				(font
					(size 1.016 1.016)
					(thickness 0.1524)
				)
			)
		)
		(duplicate_pad_numbers_are_jumpers no)
		(fp_line
			(start 0.508 -0.9398)
			(end -0.508 -0.9398)
			(stroke
				(width 0.1524)
				(type default)
			)
			(layer "F.SilkS")
		)
		(fp_line
			(start -0.508 -0.9398)
			(end -0.508 0.9398)
			(stroke
				(width 0.1524)
				(type default)
			)
			(layer "F.SilkS")
		)
		(fp_rect
			(start -0.508 0.9398)
			(end 0.508 -0.9398)
			(stroke
				(width 0)
				(type default)
			)
			(fill no)
			(layer "F.CrtYd")
		)
		(fp_rect
			(start -0.508 0.9398)
			(end 0.508 -0.9398)
			(stroke
				(width 0)
				(type default)
			)
			(fill no)
			(layer "F.Fab")
		)
		(pad "1" smd custom
			(at 0 -0.4445 180)
			(size 0.1397 0.1397)
			(layers "F.Cu" "F.Mask" "F.Paste")
			(net "VT235_VDES")
			(options
				(clearance outline)
				(anchor circle)
			)
			(primitives
				(gr_poly
					(pts
						(arc
							(start -0.1778 -0.2794)
							(mid -0.249642 -0.249642)
							(end -0.2794 -0.1778)
						)
						(arc
							(start -0.2794 0.1778)
							(mid -0.249642 0.249642)
							(end -0.1778 0.2794)
						)
						(arc
							(start 0.1778 0.2794)
							(mid 0.249642 0.249642)
							(end 0.2794 0.1778)
						)
						(arc
							(start 0.2794 -0.1778)
							(mid 0.249642 -0.249642)
							(end 0.1778 -0.2794)
						)
					)
					(width 0)
					(fill yes)
				)
			)
		)
		(pad "2" smd custom
			(at 0 0.4445 180)
			(size 0.1397 0.1397)
			(layers "F.Cu" "F.Mask" "F.Paste")
			(net "VT235_VREF")
			(options
				(clearance outline)
				(anchor circle)
			)
			(primitives
				(gr_poly
					(pts
						(arc
							(start -0.1778 -0.2794)
							(mid -0.249642 -0.249642)
							(end -0.2794 -0.1778)
						)
						(arc
							(start -0.2794 0.1778)
							(mid -0.249642 0.249642)
							(end -0.1778 0.2794)
						)
						(arc
							(start 0.1778 0.2794)
							(mid 0.249642 0.249642)
							(end 0.2794 0.1778)
						)
						(arc
							(start 0.2794 -0.1778)
							(mid 0.249642 -0.249642)
							(end 0.1778 -0.2794)
						)
					)
					(width 0)
					(fill yes)
				)
			)
		)
	)
	(footprint ""
		(layer "F.Cu")
		(at 148.0058 -116.9162 -90)
		(property "Reference" "R372"
			(at 0 0 270)
			(layer "F.SilkS")
			(hide yes)
			(effects
				(font
					(size 1.27 1.27)
				)
			)
		)
		(property "Value" "0R2J-2-GP"
			(at 0.064008 -3.993896 270)
			(unlocked yes)
			(layer "F.Fab")
			(hide yes)
			(effects
				(font
					(size 1.016 1.016)
					(thickness 0.1524)
				)
			)
		)
		(property "Device Type" "R402H16"
			(at 0.064008 -5.517896 270)
			(unlocked yes)
			(layer "F.Fab")
			(hide yes)
			(effects
				(font
					(size 1.016 1.016)
					(thickness 0.1524)
				)
			)
		)
		(duplicate_pad_numbers_are_jumpers no)
		(fp_line
			(start -0.508 -0.9398)
			(end -0.508 0.9398)
			(stroke
				(width 0.1524)
				(type default)
			)
			(layer "F.SilkS")
		)
		(fp_line
			(start 0.508 -0.9398)
			(end -0.508 -0.9398)
			(stroke
				(width 0.1524)
				(type default)
			)
			(layer "F.SilkS")
		)
		(fp_rect
			(start -0.508 0.9398)
			(end 0.508 -0.9398)
			(stroke
				(width 0)
				(type default)
			)
			(fill no)
			(layer "F.CrtYd")
		)
		(fp_rect
			(start -0.508 0.9398)
			(end 0.508 -0.9398)
			(stroke
				(width 0)
				(type default)
			)
			(fill no)
			(layer "F.Fab")
		)
		(pad "1" smd custom
			(at 0 -0.4445 270)
			(size 0.1397 0.1397)
			(layers "F.Cu" "F.Mask" "F.Paste")
			(net "P1V5_E_ROVP")
			(options
				(clearance outline)
				(anchor circle)
			)
			(primitives
				(gr_poly
					(pts
						(arc
							(start -0.1778 -0.2794)
							(mid -0.249642 -0.249642)
							(end -0.2794 -0.1778)
						)
						(arc
							(start -0.2794 0.1778)
							(mid -0.249642 0.249642)
							(end -0.1778 0.2794)
						)
						(arc
							(start 0.1778 0.2794)
							(mid 0.249642 0.249642)
							(end 0.2794 0.1778)
						)
						(arc
							(start 0.2794 -0.1778)
							(mid 0.249642 -0.249642)
							(end 0.1778 -0.2794)
						)
					)
					(width 0)
					(fill yes)
				)
			)
		)
		(pad "2" smd custom
			(at 0 0.4445 270)
			(size 0.1397 0.1397)
			(layers "F.Cu" "F.Mask" "F.Paste")
			(net "AGND_P1V5_E")
			(options
				(clearance outline)
				(anchor circle)
			)
			(primitives
				(gr_poly
					(pts
						(arc
							(start -0.1778 -0.2794)
							(mid -0.249642 -0.249642)
							(end -0.2794 -0.1778)
						)
						(arc
							(start -0.2794 0.1778)
							(mid -0.249642 0.249642)
							(end -0.1778 0.2794)
						)
						(arc
							(start 0.1778 0.2794)
							(mid 0.249642 0.249642)
							(end 0.2794 0.1778)
						)
						(arc
							(start 0.2794 -0.1778)
							(mid 0.249642 -0.249642)
							(end 0.1778 -0.2794)
						)
					)
					(width 0)
					(fill yes)
				)
			)
		)
	)
	(footprint ""
		(layer "F.Cu")
		(at 175.3362 -79.5528 -90)
		(property "Reference" "C383"
			(at 0 0 270)
			(layer "F.SilkS")
			(hide yes)
			(effects
				(font
					(size 1.27 1.27)
				)
			)
		)
		(property "Value" "SC100U6D3V6MX-GP"
			(at -0.0762 -5.1308 270)
			(unlocked yes)
			(layer "F.Fab")
			(hide yes)
			(effects
				(font
					(size 1.016 1.016)
					(thickness 0.1524)
				)
			)
		)
		(property "Device Type" "C1206H71"
			(at -0.127 -6.6548 270)
			(unlocked yes)
			(layer "F.Fab")
			(hide yes)
			(effects
				(font
					(size 1.016 1.016)
					(thickness 0.1524)
				)
			)
		)
		(duplicate_pad_numbers_are_jumpers no)
		(fp_line
			(start -1.016 2.2352)
			(end -1.016 0.8382)
			(stroke
				(width 0.1524)
				(type default)
			)
			(layer "F.SilkS")
		)
		(fp_line
			(start 1.016 2.2352)
			(end -1.016 2.2352)
			(stroke
				(width 0.1524)
				(type default)
			)
			(layer "F.SilkS")
		)
		(fp_line
			(start 1.016 0.8382)
			(end 1.016 2.2352)
			(stroke
				(width 0.1524)
				(type default)
			)
			(layer "F.SilkS")
		)
		(fp_line
			(start -1.016 -0.8382)
			(end -1.016 -2.2352)
			(stroke
				(width 0.1524)
				(type default)
			)
			(layer "F.SilkS")
		)
		(fp_line
			(start -1.016 -2.2352)
			(end 1.016 -2.2352)
			(stroke
				(width 0.1524)
				(type default)
			)
			(layer "F.SilkS")
		)
		(fp_line
			(start 1.016 -2.2352)
			(end 1.016 -0.8382)
			(stroke
				(width 0.1524)
				(type default)
			)
			(layer "F.SilkS")
		)
		(fp_rect
			(start -1.0922 2.3114)
			(end 1.0922 -2.3114)
			(stroke
				(width 0)
				(type default)
			)
			(fill no)
			(layer "F.CrtYd")
		)
		(fp_poly
			(pts
				(xy 1.0922 -2.3114) (xy 1.0922 2.3114) (xy -1.0922 2.3114) (xy -1.0922 -2.3114)
			)
			(stroke
				(width 0)
				(type default)
			)
			(fill no)
			(layer "F.Fab")
		)
		(pad "1" smd rect
			(at 0 -1.397 270)
			(size 1.651 1.27)
			(layers "F.Cu" "F.Mask" "F.Paste")
			(net "GND")
		)
		(pad "2" smd rect
			(at 0 1.397 270)
			(size 1.651 1.27)
			(layers "F.Cu" "F.Mask" "F.Paste")
			(net "PCE_AVDD")
		)
	)
	(footprint ""
		(layer "F.Cu")
		(at 166.751 -17.018 180)
		(property "Reference" "Q20"
			(at 0 0 180)
			(layer "F.SilkS")
			(hide yes)
			(effects
				(font
					(size 1.27 1.27)
				)
			)
		)
		(property "Value" "2N7002K-1-GP"
			(at 0.127 -8.9662 180)
			(unlocked yes)
			(layer "F.Fab")
			(hide yes)
			(effects
				(font
					(size 1.016 1.016)
					(thickness 0.1524)
				)
			)
		)
		(property "Device Type" "SOT23DGS2D4H44"
			(at 0.127 -10.4902 180)
			(unlocked yes)
			(layer "F.Fab")
			(hide yes)
			(effects
				(font
					(size 1.016 1.016)
					(thickness 0.1524)
				)
			)
		)
		(duplicate_pad_numbers_are_jumpers no)
		(fp_line
			(start 1.651 1.778)
			(end 1.651 -1.778)
			(stroke
				(width 0.1524)
				(type default)
			)
			(layer "F.SilkS")
		)
		(fp_line
			(start 1.651 -1.778)
			(end -1.651 -1.778)
			(stroke
				(width 0.1524)
				(type default)
			)
			(layer "F.SilkS")
		)
		(fp_line
			(start -1.651 1.778)
			(end 1.651 1.778)
			(stroke
				(width 0.1524)
				(type default)
			)
			(layer "F.SilkS")
		)
		(fp_line
			(start -1.651 -1.778)
			(end -1.651 1.778)
			(stroke
				(width 0.1524)
				(type default)
			)
			(layer "F.SilkS")
		)
		(fp_poly
			(pts
				(xy -1.778 1.8796) (xy -1.778 -1.8796) (xy 1.778 -1.8796) (xy 1.778 1.8796)
			)
			(stroke
				(width 0)
				(type default)
			)
			(fill no)
			(layer "F.CrtYd")
		)
		(fp_poly
			(pts
				(xy -1.778 1.8796) (xy -1.778 -1.8796) (xy 1.778 -1.8796) (xy 1.778 1.8796)
			)
			(stroke
				(width 0)
				(type default)
			)
			(fill no)
			(layer "F.Fab")
		)
		(pad "D" smd custom
			(at 0 -0.9525 180)
			(size 0.1905 0.1905)
			(layers "F.Cu" "F.Mask" "F.Paste")
			(net "LS_EN_N")
			(options
				(clearance outline)
				(anchor circle)
			)
			(primitives
				(gr_poly
					(pts
						(arc
							(start -0.1778 0.5715)
							(mid -0.321484 0.511984)
							(end -0.381 0.3683)
						)
						(arc
							(start -0.381 -0.3683)
							(mid -0.321484 -0.511984)
							(end -0.1778 -0.5715)
						)
						(arc
							(start 0.1778 -0.5715)
							(mid 0.321484 -0.511984)
							(end 0.381 -0.3683)
						)
						(arc
							(start 0.381 0.3683)
							(mid 0.321484 0.511984)
							(end 0.1778 0.5715)
						)
					)
					(width 0)
					(fill yes)
				)
			)
		)
		(pad "G" smd custom
			(at -0.98425 0.9525 180)
			(size 0.1905 0.1905)
			(layers "F.Cu" "F.Mask" "F.Paste")
			(net "P0V9_PG_Q")
			(options
				(clearance outline)
				(anchor circle)
			)
			(primitives
				(gr_poly
					(pts
						(arc
							(start -0.1778 0.5715)
							(mid -0.321484 0.511984)
							(end -0.381 0.3683)
						)
						(arc
							(start -0.381 -0.3683)
							(mid -0.321484 -0.511984)
							(end -0.1778 -0.5715)
						)
						(arc
							(start 0.1778 -0.5715)
							(mid 0.321484 -0.511984)
							(end 0.381 -0.3683)
						)
						(arc
							(start 0.381 0.3683)
							(mid 0.321484 0.511984)
							(end 0.1778 0.5715)
						)
					)
					(width 0)
					(fill yes)
				)
			)
		)
		(pad "S" smd custom
			(at 0.98425 0.9525 180)
			(size 0.1905 0.1905)
			(layers "F.Cu" "F.Mask" "F.Paste")
			(net "GND")
			(options
				(clearance outline)
				(anchor circle)
			)
			(primitives
				(gr_poly
					(pts
						(arc
							(start -0.1778 0.5715)
							(mid -0.321484 0.511984)
							(end -0.381 0.3683)
						)
						(arc
							(start -0.381 -0.3683)
							(mid -0.321484 -0.511984)
							(end -0.1778 -0.5715)
						)
						(arc
							(start 0.1778 -0.5715)
							(mid 0.321484 -0.511984)
							(end 0.381 -0.3683)
						)
						(arc
							(start 0.381 0.3683)
							(mid 0.321484 0.511984)
							(end 0.1778 0.5715)
						)
					)
					(width 0)
					(fill yes)
				)
			)
		)
	)
	(footprint ""
		(layer "F.Cu")
		(at 191.850772 -46.520862 -90)
		(property "Reference" "R217"
			(at 0 0 270)
			(layer "F.SilkS")
			(hide yes)
			(effects
				(font
					(size 1.27 1.27)
				)
			)
		)
		(property "Value" "10KR2F-2-GP"
			(at 0.064008 -3.993896 270)
			(unlocked yes)
			(layer "F.Fab")
			(hide yes)
			(effects
				(font
					(size 1.016 1.016)
					(thickness 0.1524)
				)
			)
		)
		(property "Device Type" "R402H16"
			(at 0.064008 -5.517896 270)
			(unlocked yes)
			(layer "F.Fab")
			(hide yes)
			(effects
				(font
					(size 1.016 1.016)
					(thickness 0.1524)
				)
			)
		)
		(duplicate_pad_numbers_are_jumpers no)
		(fp_line
			(start -0.508 -0.9398)
			(end -0.508 0.9398)
			(stroke
				(width 0.1524)
				(type default)
			)
			(layer "F.SilkS")
		)
		(fp_line
			(start 0.508 -0.9398)
			(end -0.508 -0.9398)
			(stroke
				(width 0.1524)
				(type default)
			)
			(layer "F.SilkS")
		)
		(fp_rect
			(start -0.508 0.9398)
			(end 0.508 -0.9398)
			(stroke
				(width 0)
				(type default)
			)
			(fill no)
			(layer "F.CrtYd")
		)
		(fp_rect
			(start -0.508 0.9398)
			(end 0.508 -0.9398)
			(stroke
				(width 0)
				(type default)
			)
			(fill no)
			(layer "F.Fab")
		)
		(pad "1" smd custom
			(at 0 -0.4445 270)
			(size 0.1397 0.1397)
			(layers "F.Cu" "F.Mask" "F.Paste")
			(net "P1V8_C")
			(options
				(clearance outline)
				(anchor circle)
			)
			(primitives
				(gr_poly
					(pts
						(arc
							(start -0.1778 -0.2794)
							(mid -0.249642 -0.249642)
							(end -0.2794 -0.1778)
						)
						(arc
							(start -0.2794 0.1778)
							(mid -0.249642 0.249642)
							(end -0.1778 0.2794)
						)
						(arc
							(start 0.1778 0.2794)
							(mid 0.249642 0.249642)
							(end 0.2794 0.1778)
						)
						(arc
							(start 0.2794 -0.1778)
							(mid 0.249642 -0.249642)
							(end 0.1778 -0.2794)
						)
					)
					(width 0)
					(fill yes)
				)
			)
		)
		(pad "2" smd custom
			(at 0 0.4445 270)
			(size 0.1397 0.1397)
			(layers "F.Cu" "F.Mask" "F.Paste")
			(net "XM_ADDR_23")
			(options
				(clearance outline)
				(anchor circle)
			)
			(primitives
				(gr_poly
					(pts
						(arc
							(start -0.1778 -0.2794)
							(mid -0.249642 -0.249642)
							(end -0.2794 -0.1778)
						)
						(arc
							(start -0.2794 0.1778)
							(mid -0.249642 0.249642)
							(end -0.1778 0.2794)
						)
						(arc
							(start 0.1778 0.2794)
							(mid 0.249642 0.249642)
							(end 0.2794 0.1778)
						)
						(arc
							(start 0.2794 -0.1778)
							(mid 0.249642 -0.249642)
							(end 0.1778 -0.2794)
						)
					)
					(width 0)
					(fill yes)
				)
			)
		)
	)
	(footprint ""
		(layer "F.Cu")
		(at 49.558702 -29.119576 90)
		(property "Reference" "R474"
			(at 0 0 90)
			(layer "F.SilkS")
			(hide yes)
			(effects
				(font
					(size 1.27 1.27)
				)
			)
		)
		(property "Value" "10R2J-2-GP"
			(at 0.064008 -3.993896 90)
			(unlocked yes)
			(layer "F.Fab")
			(hide yes)
			(effects
				(font
					(size 1.016 1.016)
					(thickness 0.1524)
				)
			)
		)
		(property "Device Type" "R402H14"
			(at 0.064008 -5.517896 90)
			(unlocked yes)
			(layer "F.Fab")
			(hide yes)
			(effects
				(font
					(size 1.016 1.016)
					(thickness 0.1524)
				)
			)
		)
		(duplicate_pad_numbers_are_jumpers no)
		(fp_line
			(start 0.508 -0.9398)
			(end -0.508 -0.9398)
			(stroke
				(width 0.1524)
				(type default)
			)
			(layer "F.SilkS")
		)
		(fp_line
			(start -0.508 -0.9398)
			(end -0.508 0.9398)
			(stroke
				(width 0.1524)
				(type default)
			)
			(layer "F.SilkS")
		)
		(fp_rect
			(start -0.508 0.9398)
			(end 0.508 -0.9398)
			(stroke
				(width 0)
				(type default)
			)
			(fill no)
			(layer "F.CrtYd")
		)
		(fp_rect
			(start -0.508 0.9398)
			(end 0.508 -0.9398)
			(stroke
				(width 0)
				(type default)
			)
			(fill no)
			(layer "F.Fab")
		)
		(pad "1" smd custom
			(at 0 -0.4445 90)
			(size 0.1397 0.1397)
			(layers "F.Cu" "F.Mask" "F.Paste")
			(net "P0V9_VSNS")
			(options
				(clearance outline)
				(anchor circle)
			)
			(primitives
				(gr_poly
					(pts
						(arc
							(start -0.1778 -0.2794)
							(mid -0.249642 -0.249642)
							(end -0.2794 -0.1778)
						)
						(arc
							(start -0.2794 0.1778)
							(mid -0.249642 0.249642)
							(end -0.1778 0.2794)
						)
						(arc
							(start 0.1778 0.2794)
							(mid 0.249642 0.249642)
							(end 0.2794 0.1778)
						)
						(arc
							(start 0.2794 -0.1778)
							(mid 0.249642 -0.249642)
							(end 0.1778 -0.2794)
						)
					)
					(width 0)
					(fill yes)
				)
			)
		)
		(pad "2" smd custom
			(at 0 0.4445 90)
			(size 0.1397 0.1397)
			(layers "F.Cu" "F.Mask" "F.Paste")
			(net "P0V9_VFB")
			(options
				(clearance outline)
				(anchor circle)
			)
			(primitives
				(gr_poly
					(pts
						(arc
							(start -0.1778 -0.2794)
							(mid -0.249642 -0.249642)
							(end -0.2794 -0.1778)
						)
						(arc
							(start -0.2794 0.1778)
							(mid -0.249642 0.249642)
							(end -0.1778 0.2794)
						)
						(arc
							(start 0.1778 0.2794)
							(mid 0.249642 0.249642)
							(end 0.2794 0.1778)
						)
						(arc
							(start 0.2794 -0.1778)
							(mid 0.249642 -0.249642)
							(end 0.1778 -0.2794)
						)
					)
					(width 0)
					(fill yes)
				)
			)
		)
	)
	(footprint ""
		(layer "F.Cu")
		(at 164.496242 -96.847406 180)
		(property "Reference" "C620"
			(at 0 0 180)
			(layer "F.SilkS")
			(hide yes)
			(effects
				(font
					(size 1.27 1.27)
				)
			)
		)
		(property "Value" "SC1U25V3KX-GP"
			(at 0 -2.8194 180)
			(unlocked yes)
			(layer "F.Fab")
			(hide yes)
			(effects
				(font
					(size 1.016 1.016)
					(thickness 0.1524)
				)
			)
		)
		(property "Device Type" "C603H36"
			(at 0 -4.3434 180)
			(unlocked yes)
			(layer "F.Fab")
			(hide yes)
			(effects
				(font
					(size 1.016 1.016)
					(thickness 0.1524)
				)
			)
		)
		(duplicate_pad_numbers_are_jumpers no)
		(fp_line
			(start 0.508 0)
			(end -0.508 0)
			(stroke
				(width 0.2032)
				(type default)
			)
			(layer "F.SilkS")
		)
		(fp_rect
			(start -0.5842 1.3335)
			(end 0.5842 -1.3335)
			(stroke
				(width 0)
				(type default)
			)
			(fill no)
			(layer "F.CrtYd")
		)
		(fp_rect
			(start -0.5842 1.3335)
			(end 0.5842 -1.3335)
			(stroke
				(width 0)
				(type default)
			)
			(fill no)
			(layer "F.Fab")
		)
		(pad "1" smd custom
			(at 0 -0.762 180)
			(size 0.2159 0.2159)
			(layers "F.Cu" "F.Mask" "F.Paste")
			(net "VT235_AVDD")
			(options
				(clearance outline)
				(anchor circle)
			)
			(primitives
				(gr_poly
					(pts
						(arc
							(start -0.3302 -0.4318)
							(mid -0.402042 -0.402042)
							(end -0.4318 -0.3302)
						)
						(arc
							(start -0.4318 0.3302)
							(mid -0.402042 0.402042)
							(end -0.3302 0.4318)
						)
						(arc
							(start 0.3302 0.4318)
							(mid 0.402042 0.402042)
							(end 0.4318 0.3302)
						)
						(arc
							(start 0.4318 -0.3302)
							(mid 0.402042 -0.402042)
							(end 0.3302 -0.4318)
						)
					)
					(width 0)
					(fill yes)
				)
			)
		)
		(pad "2" smd custom
			(at 0 0.762 180)
			(size 0.2159 0.2159)
			(layers "F.Cu" "F.Mask" "F.Paste")
			(net "AGND_P0V975")
			(options
				(clearance outline)
				(anchor circle)
			)
			(primitives
				(gr_poly
					(pts
						(arc
							(start -0.3302 -0.4318)
							(mid -0.402042 -0.402042)
							(end -0.4318 -0.3302)
						)
						(arc
							(start -0.4318 0.3302)
							(mid -0.402042 0.402042)
							(end -0.3302 0.4318)
						)
						(arc
							(start 0.3302 0.4318)
							(mid 0.402042 0.402042)
							(end 0.4318 0.3302)
						)
						(arc
							(start 0.4318 -0.3302)
							(mid 0.402042 -0.402042)
							(end 0.3302 -0.4318)
						)
					)
					(width 0)
					(fill yes)
				)
			)
		)
	)
	(footprint ""
		(layer "F.Cu")
		(at 136.525 -106.2736 -90)
		(property "Reference" "C693"
			(at 0 0 270)
			(layer "F.SilkS")
			(hide yes)
			(effects
				(font
					(size 1.27 1.27)
				)
			)
		)
		(property "Value" "SCD1U16V2KX-3GP"
			(at 1.1811 -2.7051 270)
			(unlocked yes)
			(layer "F.Fab")
			(hide yes)
			(effects
				(font
					(size 1.016 1.016)
					(thickness 0.1524)
				)
			)
		)
		(property "Device Type" "C402H22"
			(at 1.1811 -4.2291 270)
			(unlocked yes)
			(layer "F.Fab")
			(hide yes)
			(effects
				(font
					(size 1.016 1.016)
					(thickness 0.1524)
				)
			)
		)
		(duplicate_pad_numbers_are_jumpers no)
		(fp_rect
			(start -0.4318 0.9525)
			(end 0.4318 -0.9525)
			(stroke
				(width 0)
				(type default)
			)
			(fill no)
			(layer "F.CrtYd")
		)
		(fp_rect
			(start -0.4318 0.9525)
			(end 0.4318 -0.9525)
			(stroke
				(width 0)
				(type default)
			)
			(fill no)
			(layer "F.Fab")
		)
		(pad "1" smd custom
			(at 0 -0.4445 270)
			(size 0.1524 0.1524)
			(layers "F.Cu" "F.Mask" "F.Paste")
			(net "P1V5_E_OUT")
			(options
				(clearance outline)
				(anchor circle)
			)
			(primitives
				(gr_poly
					(pts
						(arc
							(start 0.3048 -0.2032)
							(mid 0.275042 -0.275042)
							(end 0.2032 -0.3048)
						)
						(arc
							(start -0.2032 -0.3048)
							(mid -0.275042 -0.275042)
							(end -0.3048 -0.2032)
						)
						(arc
							(start -0.3048 0.2032)
							(mid -0.275042 0.275042)
							(end -0.2032 0.3048)
						)
						(arc
							(start 0.2032 0.3048)
							(mid 0.275042 0.275042)
							(end 0.3048 0.2032)
						)
					)
					(width 0)
					(fill yes)
				)
			)
		)
		(pad "2" smd custom
			(at 0 0.4445 270)
			(size 0.1524 0.1524)
			(layers "F.Cu" "F.Mask" "F.Paste")
			(net "GND")
			(options
				(clearance outline)
				(anchor circle)
			)
			(primitives
				(gr_poly
					(pts
						(arc
							(start 0.3048 -0.2032)
							(mid 0.275042 -0.275042)
							(end 0.2032 -0.3048)
						)
						(arc
							(start -0.2032 -0.3048)
							(mid -0.275042 -0.275042)
							(end -0.3048 -0.2032)
						)
						(arc
							(start -0.3048 0.2032)
							(mid -0.275042 0.275042)
							(end -0.2032 0.3048)
						)
						(arc
							(start 0.2032 0.3048)
							(mid 0.275042 0.275042)
							(end 0.3048 0.2032)
						)
					)
					(width 0)
					(fill yes)
				)
			)
		)
	)
	(footprint ""
		(layer "F.Cu")
		(at 185.3946 -119.2276 -90)
		(property "Reference" "C597"
			(at 0 0 270)
			(layer "F.SilkS")
			(hide yes)
			(effects
				(font
					(size 1.27 1.27)
				)
			)
		)
		(property "Value" "SC10U6D3V5KX-4GP"
			(at -0.0762 -6.1214 270)
			(unlocked yes)
			(layer "F.Fab")
			(hide yes)
			(effects
				(font
					(size 1.016 1.016)
					(thickness 0.1524)
				)
			)
		)
		(property "Device Type" "C805H58"
			(at -0.0762 -8.1534 270)
			(unlocked yes)
			(layer "F.Fab")
			(hide yes)
			(effects
				(font
					(size 1.016 1.016)
					(thickness 0.1524)
				)
			)
		)
		(duplicate_pad_numbers_are_jumpers no)
		(fp_line
			(start 0.635 0)
			(end -0.635 0)
			(stroke
				(width 0.508)
				(type default)
			)
			(layer "F.SilkS")
		)
		(fp_rect
			(start -0.9652 1.778)
			(end 0.9652 -1.778)
			(stroke
				(width 0)
				(type default)
			)
			(fill no)
			(layer "F.CrtYd")
		)
		(fp_poly
			(pts
				(xy -0.9652 -1.778) (xy 0.9652 -1.778) (xy 0.9652 1.778) (xy -0.9652 1.778)
			)
			(stroke
				(width 0)
				(type default)
			)
			(fill no)
			(layer "F.Fab")
		)
		(pad "1" smd rect
			(at 0 -0.9652 270)
			(size 1.397 1.143)
			(layers "F.Cu" "F.Mask" "F.Paste")
			(net "P1V8_C")
		)
		(pad "2" smd rect
			(at 0 0.9652 270)
			(size 1.397 1.143)
			(layers "F.Cu" "F.Mask" "F.Paste")
			(net "GND")
		)
	)
	(footprint ""
		(layer "F.Cu")
		(at 181.9529 -113.34242 90)
		(property "Reference" "R98"
			(at 0 0 90)
			(layer "F.SilkS")
			(hide yes)
			(effects
				(font
					(size 1.27 1.27)
				)
			)
		)
		(property "Value" "2K87R2F-1-GP"
			(at 0.064008 -3.993896 90)
			(unlocked yes)
			(layer "F.Fab")
			(hide yes)
			(effects
				(font
					(size 1.016 1.016)
					(thickness 0.1524)
				)
			)
		)
		(property "Device Type" "R402H16"
			(at 0.064008 -5.517896 90)
			(unlocked yes)
			(layer "F.Fab")
			(hide yes)
			(effects
				(font
					(size 1.016 1.016)
					(thickness 0.1524)
				)
			)
		)
		(duplicate_pad_numbers_are_jumpers no)
		(fp_line
			(start 0.508 -0.9398)
			(end -0.508 -0.9398)
			(stroke
				(width 0.1524)
				(type default)
			)
			(layer "F.SilkS")
		)
		(fp_line
			(start -0.508 -0.9398)
			(end -0.508 0.9398)
			(stroke
				(width 0.1524)
				(type default)
			)
			(layer "F.SilkS")
		)
		(fp_rect
			(start -0.508 0.9398)
			(end 0.508 -0.9398)
			(stroke
				(width 0)
				(type default)
			)
			(fill no)
			(layer "F.CrtYd")
		)
		(fp_rect
			(start -0.508 0.9398)
			(end 0.508 -0.9398)
			(stroke
				(width 0)
				(type default)
			)
			(fill no)
			(layer "F.Fab")
		)
		(pad "1" smd custom
			(at 0 -0.4445 90)
			(size 0.1397 0.1397)
			(layers "F.Cu" "F.Mask" "F.Paste")
			(net "P1V8_E_FB")
			(options
				(clearance outline)
				(anchor circle)
			)
			(primitives
				(gr_poly
					(pts
						(arc
							(start -0.1778 -0.2794)
							(mid -0.249642 -0.249642)
							(end -0.2794 -0.1778)
						)
						(arc
							(start -0.2794 0.1778)
							(mid -0.249642 0.249642)
							(end -0.1778 0.2794)
						)
						(arc
							(start 0.1778 0.2794)
							(mid 0.249642 0.249642)
							(end 0.2794 0.1778)
						)
						(arc
							(start 0.2794 -0.1778)
							(mid 0.249642 -0.249642)
							(end 0.1778 -0.2794)
						)
					)
					(width 0)
					(fill yes)
				)
			)
		)
		(pad "2" smd custom
			(at 0 0.4445 90)
			(size 0.1397 0.1397)
			(layers "F.Cu" "F.Mask" "F.Paste")
			(net "GND")
			(options
				(clearance outline)
				(anchor circle)
			)
			(primitives
				(gr_poly
					(pts
						(arc
							(start -0.1778 -0.2794)
							(mid -0.249642 -0.249642)
							(end -0.2794 -0.1778)
						)
						(arc
							(start -0.2794 0.1778)
							(mid -0.249642 0.249642)
							(end -0.1778 0.2794)
						)
						(arc
							(start 0.1778 0.2794)
							(mid 0.249642 0.249642)
							(end 0.2794 0.1778)
						)
						(arc
							(start 0.2794 -0.1778)
							(mid 0.249642 -0.249642)
							(end 0.1778 -0.2794)
						)
					)
					(width 0)
					(fill yes)
				)
			)
		)
	)
	(footprint ""
		(layer "F.Cu")
		(at 121.031 -86.995)
		(property "Reference" "R83"
			(at 0 0 0)
			(layer "F.SilkS")
			(hide yes)
			(effects
				(font
					(size 1.27 1.27)
				)
			)
		)
		(property "Value" "4K7R2F-GP"
			(at 0.064008 -3.993896 0)
			(unlocked yes)
			(layer "F.Fab")
			(hide yes)
			(effects
				(font
					(size 1.016 1.016)
					(thickness 0.1524)
				)
			)
		)
		(property "Device Type" "R402H16"
			(at 0.064008 -5.517896 0)
			(unlocked yes)
			(layer "F.Fab")
			(hide yes)
			(effects
				(font
					(size 1.016 1.016)
					(thickness 0.1524)
				)
			)
		)
		(duplicate_pad_numbers_are_jumpers no)
		(fp_line
			(start -0.508 -0.9398)
			(end -0.508 0.9398)
			(stroke
				(width 0.1524)
				(type default)
			)
			(layer "F.SilkS")
		)
		(fp_line
			(start 0.508 -0.9398)
			(end -0.508 -0.9398)
			(stroke
				(width 0.1524)
				(type default)
			)
			(layer "F.SilkS")
		)
		(fp_rect
			(start -0.508 0.9398)
			(end 0.508 -0.9398)
			(stroke
				(width 0)
				(type default)
			)
			(fill no)
			(layer "F.CrtYd")
		)
		(fp_rect
			(start -0.508 0.9398)
			(end 0.508 -0.9398)
			(stroke
				(width 0)
				(type default)
			)
			(fill no)
			(layer "F.Fab")
		)
		(pad "1" smd custom
			(at 0 -0.4445)
			(size 0.1397 0.1397)
			(layers "F.Cu" "F.Mask" "F.Paste")
			(net "P1V8_E")
			(options
				(clearance outline)
				(anchor circle)
			)
			(primitives
				(gr_poly
					(pts
						(arc
							(start -0.1778 -0.2794)
							(mid -0.249642 -0.249642)
							(end -0.2794 -0.1778)
						)
						(arc
							(start -0.2794 0.1778)
							(mid -0.249642 0.249642)
							(end -0.1778 0.2794)
						)
						(arc
							(start 0.1778 0.2794)
							(mid 0.249642 0.249642)
							(end 0.2794 0.1778)
						)
						(arc
							(start 0.2794 -0.1778)
							(mid 0.249642 -0.249642)
							(end 0.1778 -0.2794)
						)
					)
					(width 0)
					(fill yes)
				)
			)
		)
		(pad "2" smd custom
			(at 0 0.4445)
			(size 0.1397 0.1397)
			(layers "F.Cu" "F.Mask" "F.Paste")
			(net "SCC_TYPE_3_LS")
			(options
				(clearance outline)
				(anchor circle)
			)
			(primitives
				(gr_poly
					(pts
						(arc
							(start -0.1778 -0.2794)
							(mid -0.249642 -0.249642)
							(end -0.2794 -0.1778)
						)
						(arc
							(start -0.2794 0.1778)
							(mid -0.249642 0.249642)
							(end -0.1778 0.2794)
						)
						(arc
							(start 0.1778 0.2794)
							(mid 0.249642 0.249642)
							(end 0.2794 0.1778)
						)
						(arc
							(start 0.2794 -0.1778)
							(mid 0.249642 -0.249642)
							(end 0.1778 -0.2794)
						)
					)
					(width 0)
					(fill yes)
				)
			)
		)
	)
	(footprint ""
		(layer "F.Cu")
		(at 162.961066 -56.32958)
		(property "Reference" "TP120"
			(at 0 0 0)
			(layer "F.SilkS")
			(hide yes)
			(effects
				(font
					(size 1.27 1.27)
				)
			)
		)
		(property "Value" "TPAD28-2-GP"
			(at -0.0127 -1.6637 0)
			(unlocked yes)
			(layer "F.Fab")
			(hide yes)
			(effects
				(font
					(size 1.016 1.016)
					(thickness 0.1524)
				)
			)
		)
		(property "Device Type" "TPAD28"
			(at -0.0127 -3.1877 0)
			(unlocked yes)
			(layer "F.Fab")
			(hide yes)
			(effects
				(font
					(size 1.016 1.016)
					(thickness 0.1524)
				)
			)
		)
		(duplicate_pad_numbers_are_jumpers no)
		(fp_poly
			(pts
				(arc
					(start 0.3556 0)
					(mid -0.3556 0)
					(end 0.3556 0)
				)
			)
			(stroke
				(width 0)
				(type default)
			)
			(fill no)
			(layer "F.CrtYd")
		)
		(fp_poly
			(pts
				(arc
					(start 0.6096 0)
					(mid -0.6096 0)
					(end 0.6096 0)
				)
			)
			(stroke
				(width 0)
				(type default)
			)
			(fill no)
			(layer "F.Fab")
		)
		(pad "1" smd circle
			(at 0 0)
			(size 0.7112 0.7112)
			(layers "F.Cu" "F.Mask" "F.Paste")
			(net "ICE0_TMS")
		)
	)
	(footprint ""
		(layer "F.Cu")
		(at 178.181 -55.626)
		(property "Reference" "TP135"
			(at 0 0 0)
			(layer "F.SilkS")
			(hide yes)
			(effects
				(font
					(size 1.27 1.27)
				)
			)
		)
		(property "Value" "TPAD28-2-GP"
			(at -0.0127 -1.6637 0)
			(unlocked yes)
			(layer "F.Fab")
			(hide yes)
			(effects
				(font
					(size 1.016 1.016)
					(thickness 0.1524)
				)
			)
		)
		(property "Device Type" "TPAD28"
			(at -0.0127 -3.1877 0)
			(unlocked yes)
			(layer "F.Fab")
			(hide yes)
			(effects
				(font
					(size 1.016 1.016)
					(thickness 0.1524)
				)
			)
		)
		(duplicate_pad_numbers_are_jumpers no)
		(fp_poly
			(pts
				(arc
					(start 0.3556 0)
					(mid -0.3556 0)
					(end 0.3556 0)
				)
			)
			(stroke
				(width 0)
				(type default)
			)
			(fill no)
			(layer "F.CrtYd")
		)
		(fp_poly
			(pts
				(arc
					(start 0.6096 0)
					(mid -0.6096 0)
					(end 0.6096 0)
				)
			)
			(stroke
				(width 0)
				(type default)
			)
			(fill no)
			(layer "F.Fab")
		)
		(pad "1" smd circle
			(at 0 0)
			(size 0.7112 0.7112)
			(layers "F.Cu" "F.Mask" "F.Paste")
			(net "JTAG_IOC_TMS")
		)
	)
	(footprint ""
		(layer "F.Cu")
		(at 152.164542 -95.23857 -90)
		(property "Reference" "R295"
			(at 0 0 270)
			(layer "F.SilkS")
			(hide yes)
			(effects
				(font
					(size 1.27 1.27)
				)
			)
		)
		(property "Value" "0R2J-2-GP"
			(at 0.064008 -3.993896 270)
			(unlocked yes)
			(layer "F.Fab")
			(hide yes)
			(effects
				(font
					(size 1.016 1.016)
					(thickness 0.1524)
				)
			)
		)
		(property "Device Type" "R402H16"
			(at 0.064008 -5.517896 270)
			(unlocked yes)
			(layer "F.Fab")
			(hide yes)
			(effects
				(font
					(size 1.016 1.016)
					(thickness 0.1524)
				)
			)
		)
		(duplicate_pad_numbers_are_jumpers no)
		(fp_line
			(start -0.508 -0.9398)
			(end -0.508 0.9398)
			(stroke
				(width 0.1524)
				(type default)
			)
			(layer "F.SilkS")
		)
		(fp_line
			(start 0.508 -0.9398)
			(end -0.508 -0.9398)
			(stroke
				(width 0.1524)
				(type default)
			)
			(layer "F.SilkS")
		)
		(fp_rect
			(start -0.508 0.9398)
			(end 0.508 -0.9398)
			(stroke
				(width 0)
				(type default)
			)
			(fill no)
			(layer "F.CrtYd")
		)
		(fp_rect
			(start -0.508 0.9398)
			(end 0.508 -0.9398)
			(stroke
				(width 0)
				(type default)
			)
			(fill no)
			(layer "F.Fab")
		)
		(pad "1" smd custom
			(at 0 -0.4445 270)
			(size 0.1397 0.1397)
			(layers "F.Cu" "F.Mask" "F.Paste")
			(net "SDB_TX_R")
			(options
				(clearance outline)
				(anchor circle)
			)
			(primitives
				(gr_poly
					(pts
						(arc
							(start -0.1778 -0.2794)
							(mid -0.249642 -0.249642)
							(end -0.2794 -0.1778)
						)
						(arc
							(start -0.2794 0.1778)
							(mid -0.249642 0.249642)
							(end -0.1778 0.2794)
						)
						(arc
							(start 0.1778 0.2794)
							(mid 0.249642 0.249642)
							(end 0.2794 0.1778)
						)
						(arc
							(start 0.2794 -0.1778)
							(mid 0.249642 -0.249642)
							(end 0.1778 -0.2794)
						)
					)
					(width 0)
					(fill yes)
				)
			)
		)
		(pad "2" smd custom
			(at 0 0.4445 270)
			(size 0.1397 0.1397)
			(layers "F.Cu" "F.Mask" "F.Paste")
			(net "SDB_TX")
			(options
				(clearance outline)
				(anchor circle)
			)
			(primitives
				(gr_poly
					(pts
						(arc
							(start -0.1778 -0.2794)
							(mid -0.249642 -0.249642)
							(end -0.2794 -0.1778)
						)
						(arc
							(start -0.2794 0.1778)
							(mid -0.249642 0.249642)
							(end -0.1778 0.2794)
						)
						(arc
							(start 0.1778 0.2794)
							(mid 0.249642 0.249642)
							(end 0.2794 0.1778)
						)
						(arc
							(start 0.2794 -0.1778)
							(mid 0.249642 -0.249642)
							(end 0.1778 -0.2794)
						)
					)
					(width 0)
					(fill yes)
				)
			)
		)
	)
	(footprint ""
		(layer "F.Cu")
		(at 193.167 -32.004 -90)
		(property "Reference" "TP89"
			(at 0 0 270)
			(layer "F.SilkS")
			(hide yes)
			(effects
				(font
					(size 1.27 1.27)
				)
			)
		)
		(property "Value" "TPAD28-2-GP"
			(at -0.0127 -1.6637 270)
			(unlocked yes)
			(layer "F.Fab")
			(hide yes)
			(effects
				(font
					(size 1.016 1.016)
					(thickness 0.1524)
				)
			)
		)
		(property "Device Type" "TPAD28"
			(at -0.0127 -3.1877 270)
			(unlocked yes)
			(layer "F.Fab")
			(hide yes)
			(effects
				(font
					(size 1.016 1.016)
					(thickness 0.1524)
				)
			)
		)
		(duplicate_pad_numbers_are_jumpers no)
		(fp_poly
			(pts
				(arc
					(start 0 -0.3556)
					(mid 0 0.3556)
					(end 0 -0.3556)
				)
			)
			(stroke
				(width 0)
				(type default)
			)
			(fill no)
			(layer "F.CrtYd")
		)
		(fp_poly
			(pts
				(arc
					(start 0 -0.6096)
					(mid 0 0.6096)
					(end 0 -0.6096)
				)
			)
			(stroke
				(width 0)
				(type default)
			)
			(fill no)
			(layer "F.Fab")
		)
		(pad "1" smd circle
			(at 0 0 270)
			(size 0.7112 0.7112)
			(layers "F.Cu" "F.Mask" "F.Paste")
			(net "IOC_GPIO_31")
		)
	)
	(footprint ""
		(layer "F.Cu")
		(at 136.2456 -81.1276 90)
		(property "Reference" "C677"
			(at 0 0 90)
			(layer "F.SilkS")
			(hide yes)
			(effects
				(font
					(size 1.27 1.27)
				)
			)
		)
		(property "Value" "SCD01U16V1KX-GP"
			(at -2.8321 -1.7399 90)
			(unlocked yes)
			(layer "F.Fab")
			(hide yes)
			(effects
				(font
					(size 1.016 1.016)
					(thickness 0.1524)
				)
			)
		)
		(property "Device Type" "C0201H13"
			(at -2.8321 -3.2639 90)
			(unlocked yes)
			(layer "F.Fab")
			(hide yes)
			(effects
				(font
					(size 1.016 1.016)
					(thickness 0.1524)
				)
			)
		)
		(duplicate_pad_numbers_are_jumpers no)
		(fp_rect
			(start -0.2794 0.6477)
			(end 0.2794 -0.6477)
			(stroke
				(width 0)
				(type default)
			)
			(fill no)
			(layer "F.CrtYd")
		)
		(fp_rect
			(start -0.2794 0.6477)
			(end 0.2794 -0.6477)
			(stroke
				(width 0)
				(type default)
			)
			(fill no)
			(layer "F.Fab")
		)
		(pad "1" smd custom
			(at 0 -0.2794 90)
			(size 0.0762 0.0762)
			(layers "F.Cu" "F.Mask" "F.Paste")
			(net "PHY_EXP_TO_CONN_C_11_DN")
			(options
				(clearance outline)
				(anchor circle)
			)
			(primitives
				(gr_poly
					(pts
						(arc
							(start 0.1524 -0.127)
							(mid 0.137521 -0.162921)
							(end 0.1016 -0.1778)
						)
						(arc
							(start -0.1016 -0.1778)
							(mid -0.137521 -0.162921)
							(end -0.1524 -0.127)
						)
						(arc
							(start -0.1524 0.127)
							(mid -0.137521 0.162921)
							(end -0.1016 0.1778)
						)
						(arc
							(start 0.1016 0.1778)
							(mid 0.137521 0.162921)
							(end 0.1524 0.127)
						)
					)
					(width 0)
					(fill yes)
				)
			)
		)
		(pad "2" smd custom
			(at 0 0.2794 90)
			(size 0.0762 0.0762)
			(layers "F.Cu" "F.Mask" "F.Paste")
			(net "PHY_EXP_TO_CONN_11_DN")
			(options
				(clearance outline)
				(anchor circle)
			)
			(primitives
				(gr_poly
					(pts
						(arc
							(start 0.1524 -0.127)
							(mid 0.137521 -0.162921)
							(end 0.1016 -0.1778)
						)
						(arc
							(start -0.1016 -0.1778)
							(mid -0.137521 -0.162921)
							(end -0.1524 -0.127)
						)
						(arc
							(start -0.1524 0.127)
							(mid -0.137521 0.162921)
							(end -0.1016 0.1778)
						)
						(arc
							(start 0.1016 0.1778)
							(mid 0.137521 0.162921)
							(end 0.1524 0.127)
						)
					)
					(width 0)
					(fill yes)
				)
			)
		)
	)
	(footprint ""
		(layer "F.Cu")
		(at 89.281 -78.232 -90)
		(property "Reference" "R461"
			(at 0 0 270)
			(layer "F.SilkS")
			(hide yes)
			(effects
				(font
					(size 1.27 1.27)
				)
			)
		)
		(property "Value" "0R2J-2-GP"
			(at 0.064008 -3.993896 270)
			(unlocked yes)
			(layer "F.Fab")
			(hide yes)
			(effects
				(font
					(size 1.016 1.016)
					(thickness 0.1524)
				)
			)
		)
		(property "Device Type" "R402H16"
			(at 0.064008 -5.517896 270)
			(unlocked yes)
			(layer "F.Fab")
			(hide yes)
			(effects
				(font
					(size 1.016 1.016)
					(thickness 0.1524)
				)
			)
		)
		(duplicate_pad_numbers_are_jumpers no)
		(fp_line
			(start -0.508 -0.9398)
			(end -0.508 0.9398)
			(stroke
				(width 0.1524)
				(type default)
			)
			(layer "F.SilkS")
		)
		(fp_line
			(start 0.508 -0.9398)
			(end -0.508 -0.9398)
			(stroke
				(width 0.1524)
				(type default)
			)
			(layer "F.SilkS")
		)
		(fp_rect
			(start -0.508 0.9398)
			(end 0.508 -0.9398)
			(stroke
				(width 0)
				(type default)
			)
			(fill no)
			(layer "F.CrtYd")
		)
		(fp_rect
			(start -0.508 0.9398)
			(end 0.508 -0.9398)
			(stroke
				(width 0)
				(type default)
			)
			(fill no)
			(layer "F.Fab")
		)
		(pad "1" smd custom
			(at 0 -0.4445 270)
			(size 0.1397 0.1397)
			(layers "F.Cu" "F.Mask" "F.Paste")
			(net "EXP_RESET_N")
			(options
				(clearance outline)
				(anchor circle)
			)
			(primitives
				(gr_poly
					(pts
						(arc
							(start -0.1778 -0.2794)
							(mid -0.249642 -0.249642)
							(end -0.2794 -0.1778)
						)
						(arc
							(start -0.2794 0.1778)
							(mid -0.249642 0.249642)
							(end -0.1778 0.2794)
						)
						(arc
							(start 0.1778 0.2794)
							(mid 0.249642 0.249642)
							(end 0.2794 0.1778)
						)
						(arc
							(start 0.2794 -0.1778)
							(mid 0.249642 -0.249642)
							(end 0.1778 -0.2794)
						)
					)
					(width 0)
					(fill yes)
				)
			)
		)
		(pad "2" smd custom
			(at 0 0.4445 270)
			(size 0.1397 0.1397)
			(layers "F.Cu" "F.Mask" "F.Paste")
			(net "EXP_RESET_R_U23_N")
			(options
				(clearance outline)
				(anchor circle)
			)
			(primitives
				(gr_poly
					(pts
						(arc
							(start -0.1778 -0.2794)
							(mid -0.249642 -0.249642)
							(end -0.2794 -0.1778)
						)
						(arc
							(start -0.2794 0.1778)
							(mid -0.249642 0.249642)
							(end -0.1778 0.2794)
						)
						(arc
							(start 0.1778 0.2794)
							(mid 0.249642 0.249642)
							(end 0.2794 0.1778)
						)
						(arc
							(start 0.2794 -0.1778)
							(mid 0.249642 -0.249642)
							(end 0.1778 -0.2794)
						)
					)
					(width 0)
					(fill yes)
				)
			)
		)
	)
	(footprint ""
		(layer "F.Cu")
		(at 52.8574 -41.8846)
		(property "Reference" "R480"
			(at 0 0 0)
			(layer "F.SilkS")
			(hide yes)
			(effects
				(font
					(size 1.27 1.27)
				)
			)
		)
		(property "Value" "0R3J-0-U-GP"
			(at -0.0254 -2.5146 0)
			(unlocked yes)
			(layer "F.Fab")
			(hide yes)
			(effects
				(font
					(size 1.016 1.016)
					(thickness 0.1524)
				)
			)
		)
		(property "Device Type" "R603H22"
			(at -0.0254 -4.0386 0)
			(unlocked yes)
			(layer "F.Fab")
			(hide yes)
			(effects
				(font
					(size 1.016 1.016)
					(thickness 0.1524)
				)
			)
		)
		(duplicate_pad_numbers_are_jumpers no)
		(fp_line
			(start -0.4826 0)
			(end -0.2032 0)
			(stroke
				(width 0.2032)
				(type default)
			)
			(layer "F.SilkS")
		)
		(fp_line
			(start 0.2032 0)
			(end 0.4826 0)
			(stroke
				(width 0.2032)
				(type default)
			)
			(layer "F.SilkS")
		)
		(fp_rect
			(start -0.5842 1.3335)
			(end 0.5842 -1.3335)
			(stroke
				(width 0)
				(type default)
			)
			(fill no)
			(layer "F.CrtYd")
		)
		(fp_rect
			(start -0.5842 1.3335)
			(end 0.5842 -1.3335)
			(stroke
				(width 0)
				(type default)
			)
			(fill no)
			(layer "F.Fab")
		)
		(pad "1" smd custom
			(at 0 -0.762)
			(size 0.2159 0.2159)
			(layers "F.Cu" "F.Mask" "F.Paste")
			(net "P0V9_BG")
			(options
				(clearance outline)
				(anchor circle)
			)
			(primitives
				(gr_poly
					(pts
						(arc
							(start -0.3302 -0.4318)
							(mid -0.402042 -0.402042)
							(end -0.4318 -0.3302)
						)
						(arc
							(start -0.4318 0.3302)
							(mid -0.402042 0.402042)
							(end -0.3302 0.4318)
						)
						(arc
							(start 0.3302 0.4318)
							(mid 0.402042 0.402042)
							(end 0.4318 0.3302)
						)
						(arc
							(start 0.4318 -0.3302)
							(mid 0.402042 -0.402042)
							(end 0.3302 -0.4318)
						)
					)
					(width 0)
					(fill yes)
				)
			)
		)
		(pad "2" smd custom
			(at 0 0.762)
			(size 0.2159 0.2159)
			(layers "F.Cu" "F.Mask" "F.Paste")
			(net "P0V9_DL")
			(options
				(clearance outline)
				(anchor circle)
			)
			(primitives
				(gr_poly
					(pts
						(arc
							(start -0.3302 -0.4318)
							(mid -0.402042 -0.402042)
							(end -0.4318 -0.3302)
						)
						(arc
							(start -0.4318 0.3302)
							(mid -0.402042 0.402042)
							(end -0.3302 0.4318)
						)
						(arc
							(start 0.3302 0.4318)
							(mid 0.402042 0.402042)
							(end 0.4318 0.3302)
						)
						(arc
							(start 0.4318 -0.3302)
							(mid 0.402042 -0.402042)
							(end 0.3302 -0.4318)
						)
					)
					(width 0)
					(fill yes)
				)
			)
		)
	)
	(footprint ""
		(layer "F.Cu")
		(at 15.195804 -63.535306 -90)
		(property "Reference" "C115"
			(at 0 0 270)
			(layer "F.SilkS")
			(hide yes)
			(effects
				(font
					(size 1.27 1.27)
				)
			)
		)
		(property "Value" "SC2D2U25V5KX-2-GP"
			(at -0.0762 -6.1214 270)
			(unlocked yes)
			(layer "F.Fab")
			(hide yes)
			(effects
				(font
					(size 1.016 1.016)
					(thickness 0.1524)
				)
			)
		)
		(property "Device Type" "C805H54"
			(at -0.0762 -8.1534 270)
			(unlocked yes)
			(layer "F.Fab")
			(hide yes)
			(effects
				(font
					(size 1.016 1.016)
					(thickness 0.1524)
				)
			)
		)
		(duplicate_pad_numbers_are_jumpers no)
		(fp_line
			(start 0.635 0)
			(end -0.635 0)
			(stroke
				(width 0.508)
				(type default)
			)
			(layer "F.SilkS")
		)
		(fp_rect
			(start -0.9652 1.778)
			(end 0.9652 -1.778)
			(stroke
				(width 0)
				(type default)
			)
			(fill no)
			(layer "F.CrtYd")
		)
		(fp_poly
			(pts
				(xy -0.9652 -1.778) (xy 0.9652 -1.778) (xy 0.9652 1.778) (xy -0.9652 1.778)
			)
			(stroke
				(width 0)
				(type default)
			)
			(fill no)
			(layer "F.Fab")
		)
		(pad "1" smd rect
			(at 0 -0.9652 270)
			(size 1.397 1.143)
			(layers "F.Cu" "F.Mask" "F.Paste")
			(net "MB0_HS_ENABLE")
		)
		(pad "2" smd rect
			(at 0 0.9652 270)
			(size 1.397 1.143)
			(layers "F.Cu" "F.Mask" "F.Paste")
			(net "GND")
		)
	)
	(footprint ""
		(layer "F.Cu")
		(at 170.563032 -56.089296)
		(property "Reference" "TP127"
			(at 0 0 0)
			(layer "F.SilkS")
			(hide yes)
			(effects
				(font
					(size 1.27 1.27)
				)
			)
		)
		(property "Value" "TPAD28-2-GP"
			(at -0.0127 -1.6637 0)
			(unlocked yes)
			(layer "F.Fab")
			(hide yes)
			(effects
				(font
					(size 1.016 1.016)
					(thickness 0.1524)
				)
			)
		)
		(property "Device Type" "TPAD28"
			(at -0.0127 -3.1877 0)
			(unlocked yes)
			(layer "F.Fab")
			(hide yes)
			(effects
				(font
					(size 1.016 1.016)
					(thickness 0.1524)
				)
			)
		)
		(duplicate_pad_numbers_are_jumpers no)
		(fp_poly
			(pts
				(arc
					(start 0.3556 0)
					(mid -0.3556 0)
					(end 0.3556 0)
				)
			)
			(stroke
				(width 0)
				(type default)
			)
			(fill no)
			(layer "F.CrtYd")
		)
		(fp_poly
			(pts
				(arc
					(start 0.6096 0)
					(mid -0.6096 0)
					(end 0.6096 0)
				)
			)
			(stroke
				(width 0)
				(type default)
			)
			(fill no)
			(layer "F.Fab")
		)
		(pad "1" smd circle
			(at 0 0)
			(size 0.7112 0.7112)
			(layers "F.Cu" "F.Mask" "F.Paste")
			(net "ICE1_TDO")
		)
	)
	(footprint ""
		(layer "F.Cu")
		(at 47.0662 -27.94 90)
		(property "Reference" "R477"
			(at 0 0 90)
			(layer "F.SilkS")
			(hide yes)
			(effects
				(font
					(size 1.27 1.27)
				)
			)
		)
		(property "Value" "0R2F-1-GP"
			(at 0.064008 -3.993896 90)
			(unlocked yes)
			(layer "F.Fab")
			(hide yes)
			(effects
				(font
					(size 1.016 1.016)
					(thickness 0.1524)
				)
			)
		)
		(property "Device Type" "R402H16"
			(at 0.064008 -5.517896 90)
			(unlocked yes)
			(layer "F.Fab")
			(hide yes)
			(effects
				(font
					(size 1.016 1.016)
					(thickness 0.1524)
				)
			)
		)
		(duplicate_pad_numbers_are_jumpers no)
		(fp_line
			(start 0.508 -0.9398)
			(end -0.508 -0.9398)
			(stroke
				(width 0.1524)
				(type default)
			)
			(layer "F.SilkS")
		)
		(fp_line
			(start -0.508 -0.9398)
			(end -0.508 0.9398)
			(stroke
				(width 0.1524)
				(type default)
			)
			(layer "F.SilkS")
		)
		(fp_rect
			(start -0.508 0.9398)
			(end 0.508 -0.9398)
			(stroke
				(width 0)
				(type default)
			)
			(fill no)
			(layer "F.CrtYd")
		)
		(fp_rect
			(start -0.508 0.9398)
			(end 0.508 -0.9398)
			(stroke
				(width 0)
				(type default)
			)
			(fill no)
			(layer "F.Fab")
		)
		(pad "1" smd custom
			(at 0 -0.4445 90)
			(size 0.1397 0.1397)
			(layers "F.Cu" "F.Mask" "F.Paste")
			(net "P0V9_GSNS")
			(options
				(clearance outline)
				(anchor circle)
			)
			(primitives
				(gr_poly
					(pts
						(arc
							(start -0.1778 -0.2794)
							(mid -0.249642 -0.249642)
							(end -0.2794 -0.1778)
						)
						(arc
							(start -0.2794 0.1778)
							(mid -0.249642 0.249642)
							(end -0.1778 0.2794)
						)
						(arc
							(start 0.1778 0.2794)
							(mid 0.249642 0.249642)
							(end 0.2794 0.1778)
						)
						(arc
							(start 0.2794 -0.1778)
							(mid 0.249642 -0.249642)
							(end 0.1778 -0.2794)
						)
					)
					(width 0)
					(fill yes)
				)
			)
		)
		(pad "2" smd custom
			(at 0 0.4445 90)
			(size 0.1397 0.1397)
			(layers "F.Cu" "F.Mask" "F.Paste")
			(net "GND")
			(options
				(clearance outline)
				(anchor circle)
			)
			(primitives
				(gr_poly
					(pts
						(arc
							(start -0.1778 -0.2794)
							(mid -0.249642 -0.249642)
							(end -0.2794 -0.1778)
						)
						(arc
							(start -0.2794 0.1778)
							(mid -0.249642 0.249642)
							(end -0.1778 0.2794)
						)
						(arc
							(start 0.1778 0.2794)
							(mid 0.249642 0.249642)
							(end 0.2794 0.1778)
						)
						(arc
							(start 0.2794 -0.1778)
							(mid 0.249642 -0.249642)
							(end 0.1778 -0.2794)
						)
					)
					(width 0)
					(fill yes)
				)
			)
		)
	)
	(footprint ""
		(layer "F.Cu")
		(at 158.5087 -88.6206 -90)
		(property "Reference" "R329"
			(at 0 0 270)
			(layer "F.SilkS")
			(hide yes)
			(effects
				(font
					(size 1.27 1.27)
				)
			)
		)
		(property "Value" "4K7R2F-GP"
			(at 0.064008 -3.993896 270)
			(unlocked yes)
			(layer "F.Fab")
			(hide yes)
			(effects
				(font
					(size 1.016 1.016)
					(thickness 0.1524)
				)
			)
		)
		(property "Device Type" "R402H16"
			(at 0.064008 -5.517896 270)
			(unlocked yes)
			(layer "F.Fab")
			(hide yes)
			(effects
				(font
					(size 1.016 1.016)
					(thickness 0.1524)
				)
			)
		)
		(duplicate_pad_numbers_are_jumpers no)
		(fp_line
			(start -0.508 -0.9398)
			(end -0.508 0.9398)
			(stroke
				(width 0.1524)
				(type default)
			)
			(layer "F.SilkS")
		)
		(fp_line
			(start 0.508 -0.9398)
			(end -0.508 -0.9398)
			(stroke
				(width 0.1524)
				(type default)
			)
			(layer "F.SilkS")
		)
		(fp_rect
			(start -0.508 0.9398)
			(end 0.508 -0.9398)
			(stroke
				(width 0)
				(type default)
			)
			(fill no)
			(layer "F.CrtYd")
		)
		(fp_rect
			(start -0.508 0.9398)
			(end 0.508 -0.9398)
			(stroke
				(width 0)
				(type default)
			)
			(fill no)
			(layer "F.Fab")
		)
		(pad "1" smd custom
			(at 0 -0.4445 270)
			(size 0.1397 0.1397)
			(layers "F.Cu" "F.Mask" "F.Paste")
			(net "P3V3")
			(options
				(clearance outline)
				(anchor circle)
			)
			(primitives
				(gr_poly
					(pts
						(arc
							(start -0.1778 -0.2794)
							(mid -0.249642 -0.249642)
							(end -0.2794 -0.1778)
						)
						(arc
							(start -0.2794 0.1778)
							(mid -0.249642 0.249642)
							(end -0.1778 0.2794)
						)
						(arc
							(start 0.1778 0.2794)
							(mid 0.249642 0.249642)
							(end 0.2794 0.1778)
						)
						(arc
							(start 0.2794 -0.1778)
							(mid 0.249642 -0.249642)
							(end 0.1778 -0.2794)
						)
					)
					(width 0)
					(fill yes)
				)
			)
		)
		(pad "2" smd custom
			(at 0 0.4445 270)
			(size 0.1397 0.1397)
			(layers "F.Cu" "F.Mask" "F.Paste")
			(net "VOL_SEN1_ALERT")
			(options
				(clearance outline)
				(anchor circle)
			)
			(primitives
				(gr_poly
					(pts
						(arc
							(start -0.1778 -0.2794)
							(mid -0.249642 -0.249642)
							(end -0.2794 -0.1778)
						)
						(arc
							(start -0.2794 0.1778)
							(mid -0.249642 0.249642)
							(end -0.1778 0.2794)
						)
						(arc
							(start 0.1778 0.2794)
							(mid 0.249642 0.249642)
							(end 0.2794 0.1778)
						)
						(arc
							(start 0.2794 -0.1778)
							(mid 0.249642 -0.249642)
							(end 0.1778 -0.2794)
						)
					)
					(width 0)
					(fill yes)
				)
			)
		)
	)
	(footprint ""
		(layer "F.Cu")
		(at 202.47737 -74.997818 180)
		(property "Reference" "C349"
			(at 0 0 180)
			(layer "F.SilkS")
			(hide yes)
			(effects
				(font
					(size 1.27 1.27)
				)
			)
		)
		(property "Value" "SCD1U16V2KX-3GP"
			(at 1.1811 -2.7051 180)
			(unlocked yes)
			(layer "F.Fab")
			(hide yes)
			(effects
				(font
					(size 1.016 1.016)
					(thickness 0.1524)
				)
			)
		)
		(property "Device Type" "C402H22"
			(at 1.1811 -4.2291 180)
			(unlocked yes)
			(layer "F.Fab")
			(hide yes)
			(effects
				(font
					(size 1.016 1.016)
					(thickness 0.1524)
				)
			)
		)
		(duplicate_pad_numbers_are_jumpers no)
		(fp_rect
			(start -0.4318 0.9525)
			(end 0.4318 -0.9525)
			(stroke
				(width 0)
				(type default)
			)
			(fill no)
			(layer "F.CrtYd")
		)
		(fp_rect
			(start -0.4318 0.9525)
			(end 0.4318 -0.9525)
			(stroke
				(width 0)
				(type default)
			)
			(fill no)
			(layer "F.Fab")
		)
		(pad "1" smd custom
			(at 0 -0.4445 180)
			(size 0.1524 0.1524)
			(layers "F.Cu" "F.Mask" "F.Paste")
			(net "P1V8_C")
			(options
				(clearance outline)
				(anchor circle)
			)
			(primitives
				(gr_poly
					(pts
						(arc
							(start 0.3048 -0.2032)
							(mid 0.275042 -0.275042)
							(end 0.2032 -0.3048)
						)
						(arc
							(start -0.2032 -0.3048)
							(mid -0.275042 -0.275042)
							(end -0.3048 -0.2032)
						)
						(arc
							(start -0.3048 0.2032)
							(mid -0.275042 0.275042)
							(end -0.2032 0.3048)
						)
						(arc
							(start 0.2032 0.3048)
							(mid 0.275042 0.275042)
							(end 0.3048 0.2032)
						)
					)
					(width 0)
					(fill yes)
				)
			)
		)
		(pad "2" smd custom
			(at 0 0.4445 180)
			(size 0.1524 0.1524)
			(layers "F.Cu" "F.Mask" "F.Paste")
			(net "GND")
			(options
				(clearance outline)
				(anchor circle)
			)
			(primitives
				(gr_poly
					(pts
						(arc
							(start 0.3048 -0.2032)
							(mid 0.275042 -0.275042)
							(end 0.2032 -0.3048)
						)
						(arc
							(start -0.2032 -0.3048)
							(mid -0.275042 -0.275042)
							(end -0.3048 -0.2032)
						)
						(arc
							(start -0.3048 0.2032)
							(mid -0.275042 0.275042)
							(end -0.2032 0.3048)
						)
						(arc
							(start 0.2032 0.3048)
							(mid 0.275042 0.275042)
							(end 0.3048 0.2032)
						)
					)
					(width 0)
					(fill yes)
				)
			)
		)
	)
	(footprint ""
		(layer "F.Cu")
		(at 191.8462 -33.3121 -90)
		(property "Reference" "TP68"
			(at 0 0 270)
			(layer "F.SilkS")
			(hide yes)
			(effects
				(font
					(size 1.27 1.27)
				)
			)
		)
		(property "Value" "TPAD28-2-GP"
			(at -0.0127 -1.6637 270)
			(unlocked yes)
			(layer "F.Fab")
			(hide yes)
			(effects
				(font
					(size 1.016 1.016)
					(thickness 0.1524)
				)
			)
		)
		(property "Device Type" "TPAD28"
			(at -0.0127 -3.1877 270)
			(unlocked yes)
			(layer "F.Fab")
			(hide yes)
			(effects
				(font
					(size 1.016 1.016)
					(thickness 0.1524)
				)
			)
		)
		(duplicate_pad_numbers_are_jumpers no)
		(fp_poly
			(pts
				(arc
					(start 0 -0.3556)
					(mid 0 0.3556)
					(end 0 -0.3556)
				)
			)
			(stroke
				(width 0)
				(type default)
			)
			(fill no)
			(layer "F.CrtYd")
		)
		(fp_poly
			(pts
				(arc
					(start 0 -0.6096)
					(mid 0 0.6096)
					(end 0 -0.6096)
				)
			)
			(stroke
				(width 0)
				(type default)
			)
			(fill no)
			(layer "F.Fab")
		)
		(pad "1" smd circle
			(at 0 0 270)
			(size 0.7112 0.7112)
			(layers "F.Cu" "F.Mask" "F.Paste")
			(net "IOC_GPIO_15")
		)
	)
	(footprint ""
		(layer "B.Cu")
		(at 179.796694 -34.01822)
		(property "Reference" "TP132"
			(at 0 0 0)
			(layer "B.SilkS")
			(hide yes)
			(effects
				(font
					(size 1.27 1.27)
				)
				(justify mirror)
			)
		)
		(property "Value" "TPAD28-2-GP"
			(at 0.0127 -1.6637 0)
			(unlocked yes)
			(layer "B.Fab")
			(hide yes)
			(effects
				(font
					(size 1.016 1.016)
					(thickness 0.1524)
				)
				(justify mirror)
			)
		)
		(property "Device Type" "TPAD28"
			(at 0.0127 -3.1877 0)
			(unlocked yes)
			(layer "B.Fab")
			(hide yes)
			(effects
				(font
					(size 1.016 1.016)
					(thickness 0.1524)
				)
				(justify mirror)
			)
		)
		(duplicate_pad_numbers_are_jumpers no)
		(fp_poly
			(pts
				(arc
					(start 0.3556 0)
					(mid -0.3556 0)
					(end 0.3556 0)
				)
			)
			(stroke
				(width 0)
				(type default)
			)
			(fill no)
			(layer "B.CrtYd")
		)
		(fp_poly
			(pts
				(arc
					(start 0.6096 0)
					(mid -0.6096 0)
					(end 0.6096 0)
				)
			)
			(stroke
				(width 0)
				(type default)
			)
			(fill no)
			(layer "B.Fab")
		)
		(pad "1" smd circle
			(at 0 0 180)
			(size 0.7112 0.7112)
			(layers "B.Cu" "B.Mask" "B.Paste")
			(net "SYS_DBMODE0")
		)
	)
	(footprint ""
		(layer "B.Cu")
		(at 129.397252 -55.233824 90)
		(property "Reference" "C297"
			(at 0 0 90)
			(layer "B.SilkS")
			(hide yes)
			(effects
				(font
					(size 1.27 1.27)
				)
				(justify mirror)
			)
		)
		(property "Value" "SCD1U6D3V1KX-GP"
			(at 2.8321 -1.7399 90)
			(unlocked yes)
			(layer "B.Fab")
			(hide yes)
			(effects
				(font
					(size 1.016 1.016)
					(thickness 0.1524)
				)
				(justify mirror)
			)
		)
		(property "Device Type" "C0201H13"
			(at 2.8321 -3.2639 90)
			(unlocked yes)
			(layer "B.Fab")
			(hide yes)
			(effects
				(font
					(size 1.016 1.016)
					(thickness 0.1524)
				)
				(justify mirror)
			)
		)
		(duplicate_pad_numbers_are_jumpers no)
		(fp_rect
			(start 0.2794 0.6477)
			(end -0.2794 -0.6477)
			(stroke
				(width 0)
				(type default)
			)
			(fill no)
			(layer "B.CrtYd")
		)
		(fp_rect
			(start 0.2794 0.6477)
			(end -0.2794 -0.6477)
			(stroke
				(width 0)
				(type default)
			)
			(fill no)
			(layer "B.Fab")
		)
		(pad "1" smd custom
			(at 0 -0.2794 270)
			(size 0.0762 0.0762)
			(layers "B.Cu" "B.Mask" "B.Paste")
			(net "GB_VDDA")
			(options
				(clearance outline)
				(anchor circle)
			)
			(primitives
				(gr_poly
					(pts
						(arc
							(start 0.1524 0.127)
							(mid 0.137521 0.162921)
							(end 0.1016 0.1778)
						)
						(arc
							(start -0.1016 0.1778)
							(mid -0.137521 0.162921)
							(end -0.1524 0.127)
						)
						(arc
							(start -0.1524 -0.127)
							(mid -0.137521 -0.162921)
							(end -0.1016 -0.1778)
						)
						(arc
							(start 0.1016 -0.1778)
							(mid 0.137521 -0.162921)
							(end 0.1524 -0.127)
						)
					)
					(width 0)
					(fill yes)
				)
			)
		)
		(pad "2" smd custom
			(at 0 0.2794 270)
			(size 0.0762 0.0762)
			(layers "B.Cu" "B.Mask" "B.Paste")
			(net "GND")
			(options
				(clearance outline)
				(anchor circle)
			)
			(primitives
				(gr_poly
					(pts
						(arc
							(start 0.1524 0.127)
							(mid 0.137521 0.162921)
							(end 0.1016 0.1778)
						)
						(arc
							(start -0.1016 0.1778)
							(mid -0.137521 0.162921)
							(end -0.1524 0.127)
						)
						(arc
							(start -0.1524 -0.127)
							(mid -0.137521 -0.162921)
							(end -0.1016 -0.1778)
						)
						(arc
							(start 0.1016 -0.1778)
							(mid 0.137521 -0.162921)
							(end 0.1524 -0.127)
						)
					)
					(width 0)
					(fill yes)
				)
			)
		)
	)
	(footprint ""
		(layer "B.Cu")
		(at 11.43 -52.1208)
		(property "Reference" "P1"
			(at 0 0 0)
			(layer "B.SilkS")
			(hide yes)
			(effects
				(font
					(size 1.27 1.27)
				)
				(justify mirror)
			)
		)
		(property "Value" "0R0603-PAD-2-GP-U"
			(at -2.1209 -0.1397 0)
			(unlocked yes)
			(layer "B.Fab")
			(hide yes)
			(effects
				(font
					(size 1.016 1.016)
					(thickness 0.1524)
				)
				(justify mirror)
			)
		)
		(property "Device Type" "0R0603-PAD-1-U"
			(at -2.1209 -1.6637 0)
			(unlocked yes)
			(layer "B.Fab")
			(hide yes)
			(effects
				(font
					(size 1.016 1.016)
					(thickness 0.1524)
				)
				(justify mirror)
			)
		)
		(duplicate_pad_numbers_are_jumpers no)
		(fp_rect
			(start 0.5842 1.3335)
			(end -0.5842 -1.3335)
			(stroke
				(width 0)
				(type default)
			)
			(fill no)
			(layer "B.CrtYd")
		)
		(fp_rect
			(start 0.5842 1.3335)
			(end -0.5842 -1.3335)
			(stroke
				(width 0)
				(type default)
			)
			(fill no)
			(layer "B.Fab")
		)
		(pad "1" smd custom
			(at 0 -0.762 180)
			(size 0.2159 0.2159)
			(layers "B.Cu" "B.Mask" "B.Paste")
			(net "AGND_CURRENT_MON")
			(options
				(clearance outline)
				(anchor circle)
			)
			(primitives
				(gr_poly
					(pts
						(arc
							(start -0.3302 0.5842)
							(mid -0.402042 0.554442)
							(end -0.4318 0.4826)
						)
						(arc
							(start -0.4318 -0.4826)
							(mid -0.402042 -0.554442)
							(end -0.3302 -0.5842)
						)
						(arc
							(start 0.3302 -0.5842)
							(mid 0.402042 -0.554442)
							(end 0.4318 -0.4826)
						)
						(arc
							(start 0.4318 0.4826)
							(mid 0.402042 0.554442)
							(end 0.3302 0.5842)
						)
					)
					(width 0)
					(fill yes)
				)
			)
		)
		(pad "2" smd custom
			(at 0 0.762 180)
			(size 0.2159 0.2159)
			(layers "B.Cu" "B.Mask" "B.Paste")
			(net "GND")
			(options
				(clearance outline)
				(anchor circle)
			)
			(primitives
				(gr_poly
					(pts
						(arc
							(start -0.4318 -0.4826)
							(mid -0.402042 -0.554442)
							(end -0.3302 -0.5842)
						)
						(arc
							(start 0.3302 -0.5842)
							(mid 0.402042 -0.554442)
							(end 0.4318 -0.4826)
						)
						(arc
							(start 0.4318 0.4826)
							(mid 0.402042 0.554442)
							(end 0.3302 0.5842)
						)
						(arc
							(start -0.3302 0.5842)
							(mid -0.402042 0.554442)
							(end -0.4318 0.4826)
						)
					)
					(width 0)
					(fill yes)
				)
			)
		)
	)
	(footprint ""
		(layer "B.Cu")
		(at 97.2058 -44.2214 180)
		(property "Reference" "C87"
			(at 0 0 0)
			(layer "B.SilkS")
			(hide yes)
			(effects
				(font
					(size 1.27 1.27)
				)
				(justify mirror)
			)
		)
		(property "Value" "SCD01U16V1KX-GP"
			(at 2.8321 -1.7399 180)
			(unlocked yes)
			(layer "B.Fab")
			(hide yes)
			(effects
				(font
					(size 1.016 1.016)
					(thickness 0.1524)
				)
				(justify mirror)
			)
		)
		(property "Device Type" "C0201H13"
			(at 2.8321 -3.2639 180)
			(unlocked yes)
			(layer "B.Fab")
			(hide yes)
			(effects
				(font
					(size 1.016 1.016)
					(thickness 0.1524)
				)
				(justify mirror)
			)
		)
		(duplicate_pad_numbers_are_jumpers no)
		(fp_rect
			(start 0.2794 0.6477)
			(end -0.2794 -0.6477)
			(stroke
				(width 0)
				(type default)
			)
			(fill no)
			(layer "B.CrtYd")
		)
		(fp_rect
			(start 0.2794 0.6477)
			(end -0.2794 -0.6477)
			(stroke
				(width 0)
				(type default)
			)
			(fill no)
			(layer "B.Fab")
		)
		(pad "1" smd custom
			(at 0 -0.2794)
			(size 0.0762 0.0762)
			(layers "B.Cu" "B.Mask" "B.Paste")
			(net "PHY_DPB_TO_SCC_16_DP")
			(options
				(clearance outline)
				(anchor circle)
			)
			(primitives
				(gr_poly
					(pts
						(arc
							(start 0.1524 0.127)
							(mid 0.137521 0.162921)
							(end 0.1016 0.1778)
						)
						(arc
							(start -0.1016 0.1778)
							(mid -0.137521 0.162921)
							(end -0.1524 0.127)
						)
						(arc
							(start -0.1524 -0.127)
							(mid -0.137521 -0.162921)
							(end -0.1016 -0.1778)
						)
						(arc
							(start 0.1016 -0.1778)
							(mid 0.137521 -0.162921)
							(end 0.1524 -0.127)
						)
					)
					(width 0)
					(fill yes)
				)
			)
		)
		(pad "2" smd custom
			(at 0 0.2794)
			(size 0.0762 0.0762)
			(layers "B.Cu" "B.Mask" "B.Paste")
			(net "PHY_DPB_TO_SCC_C_16_DP")
			(options
				(clearance outline)
				(anchor circle)
			)
			(primitives
				(gr_poly
					(pts
						(arc
							(start 0.1524 0.127)
							(mid 0.137521 0.162921)
							(end 0.1016 0.1778)
						)
						(arc
							(start -0.1016 0.1778)
							(mid -0.137521 0.162921)
							(end -0.1524 0.127)
						)
						(arc
							(start -0.1524 -0.127)
							(mid -0.137521 -0.162921)
							(end -0.1016 -0.1778)
						)
						(arc
							(start 0.1016 -0.1778)
							(mid 0.137521 -0.162921)
							(end 0.1524 -0.127)
						)
					)
					(width 0)
					(fill yes)
				)
			)
		)
	)
	(footprint ""
		(layer "B.Cu")
		(at 173.838108 -36.91001 -90)
		(property "Reference" "C446"
			(at 0 0 90)
			(layer "B.SilkS")
			(hide yes)
			(effects
				(font
					(size 1.27 1.27)
				)
				(justify mirror)
			)
		)
		(property "Value" "SC1KP50V2KX-1GP"
			(at -1.1811 -2.7051 270)
			(unlocked yes)
			(layer "B.Fab")
			(hide yes)
			(effects
				(font
					(size 1.016 1.016)
					(thickness 0.1524)
				)
				(justify mirror)
			)
		)
		(property "Device Type" "C402H22"
			(at -1.1811 -4.2291 270)
			(unlocked yes)
			(layer "B.Fab")
			(hide yes)
			(effects
				(font
					(size 1.016 1.016)
					(thickness 0.1524)
				)
				(justify mirror)
			)
		)
		(duplicate_pad_numbers_are_jumpers no)
		(fp_rect
			(start 0.4318 0.9525)
			(end -0.4318 -0.9525)
			(stroke
				(width 0)
				(type default)
			)
			(fill no)
			(layer "B.CrtYd")
		)
		(fp_rect
			(start 0.4318 0.9525)
			(end -0.4318 -0.9525)
			(stroke
				(width 0)
				(type default)
			)
			(fill no)
			(layer "B.Fab")
		)
		(pad "1" smd custom
			(at 0 -0.4445 90)
			(size 0.1524 0.1524)
			(layers "B.Cu" "B.Mask" "B.Paste")
			(net "P0V975")
			(options
				(clearance outline)
				(anchor circle)
			)
			(primitives
				(gr_poly
					(pts
						(arc
							(start 0.3048 0.2032)
							(mid 0.275042 0.275042)
							(end 0.2032 0.3048)
						)
						(arc
							(start -0.2032 0.3048)
							(mid -0.275042 0.275042)
							(end -0.3048 0.2032)
						)
						(arc
							(start -0.3048 -0.2032)
							(mid -0.275042 -0.275042)
							(end -0.2032 -0.3048)
						)
						(arc
							(start 0.2032 -0.3048)
							(mid 0.275042 -0.275042)
							(end 0.3048 -0.2032)
						)
					)
					(width 0)
					(fill yes)
				)
			)
		)
		(pad "2" smd custom
			(at 0 0.4445 90)
			(size 0.1524 0.1524)
			(layers "B.Cu" "B.Mask" "B.Paste")
			(net "GND")
			(options
				(clearance outline)
				(anchor circle)
			)
			(primitives
				(gr_poly
					(pts
						(arc
							(start 0.3048 0.2032)
							(mid 0.275042 0.275042)
							(end 0.2032 0.3048)
						)
						(arc
							(start -0.2032 0.3048)
							(mid -0.275042 0.275042)
							(end -0.3048 0.2032)
						)
						(arc
							(start -0.3048 -0.2032)
							(mid -0.275042 -0.275042)
							(end -0.2032 -0.3048)
						)
						(arc
							(start 0.2032 -0.3048)
							(mid 0.275042 -0.275042)
							(end 0.3048 -0.2032)
						)
					)
					(width 0)
					(fill yes)
				)
			)
		)
	)
	(footprint ""
		(layer "B.Cu")
		(at 132.715 -89.916 180)
		(property "Reference" "R54"
			(at 0 0 0)
			(layer "B.SilkS")
			(hide yes)
			(effects
				(font
					(size 1.27 1.27)
				)
				(justify mirror)
			)
		)
		(property "Value" "4K7R2F-GP"
			(at -0.064008 -3.993896 180)
			(unlocked yes)
			(layer "B.Fab")
			(hide yes)
			(effects
				(font
					(size 1.016 1.016)
					(thickness 0.1524)
				)
				(justify mirror)
			)
		)
		(property "Device Type" "R402H16"
			(at -0.064008 -5.517896 180)
			(unlocked yes)
			(layer "B.Fab")
			(hide yes)
			(effects
				(font
					(size 1.016 1.016)
					(thickness 0.1524)
				)
				(justify mirror)
			)
		)
		(duplicate_pad_numbers_are_jumpers no)
		(fp_line
			(start 0.508 -0.9398)
			(end 0.508 0.9398)
			(stroke
				(width 0.1524)
				(type default)
			)
			(layer "B.SilkS")
		)
		(fp_line
			(start -0.508 -0.9398)
			(end 0.508 -0.9398)
			(stroke
				(width 0.1524)
				(type default)
			)
			(layer "B.SilkS")
		)
		(fp_rect
			(start 0.508 0.9398)
			(end -0.508 -0.9398)
			(stroke
				(width 0)
				(type default)
			)
			(fill no)
			(layer "B.CrtYd")
		)
		(fp_rect
			(start 0.508 0.9398)
			(end -0.508 -0.9398)
			(stroke
				(width 0)
				(type default)
			)
			(fill no)
			(layer "B.Fab")
		)
		(pad "1" smd custom
			(at 0 -0.4445)
			(size 0.1397 0.1397)
			(layers "B.Cu" "B.Mask" "B.Paste")
			(net "P1V8_E")
			(options
				(clearance outline)
				(anchor circle)
			)
			(primitives
				(gr_poly
					(pts
						(arc
							(start -0.1778 0.2794)
							(mid -0.249642 0.249642)
							(end -0.2794 0.1778)
						)
						(arc
							(start -0.2794 -0.1778)
							(mid -0.249642 -0.249642)
							(end -0.1778 -0.2794)
						)
						(arc
							(start 0.1778 -0.2794)
							(mid 0.249642 -0.249642)
							(end 0.2794 -0.1778)
						)
						(arc
							(start 0.2794 0.1778)
							(mid 0.249642 0.249642)
							(end 0.1778 0.2794)
						)
					)
					(width 0)
					(fill yes)
				)
			)
		)
		(pad "2" smd custom
			(at 0 0.4445)
			(size 0.1397 0.1397)
			(layers "B.Cu" "B.Mask" "B.Paste")
			(net "I2C_DPB_SCL3_LS")
			(options
				(clearance outline)
				(anchor circle)
			)
			(primitives
				(gr_poly
					(pts
						(arc
							(start -0.1778 0.2794)
							(mid -0.249642 0.249642)
							(end -0.2794 0.1778)
						)
						(arc
							(start -0.2794 -0.1778)
							(mid -0.249642 -0.249642)
							(end -0.1778 -0.2794)
						)
						(arc
							(start 0.1778 -0.2794)
							(mid 0.249642 -0.249642)
							(end 0.2794 -0.1778)
						)
						(arc
							(start 0.2794 0.1778)
							(mid 0.249642 0.249642)
							(end 0.1778 0.2794)
						)
					)
					(width 0)
					(fill yes)
				)
			)
		)
	)
	(footprint ""
		(layer "B.Cu")
		(at 177.805842 -41.329356 90)
		(property "Reference" "C436"
			(at 0 0 90)
			(layer "B.SilkS")
			(hide yes)
			(effects
				(font
					(size 1.27 1.27)
				)
				(justify mirror)
			)
		)
		(property "Value" "SCD1U6D3V1KX-GP"
			(at 2.8321 -1.7399 90)
			(unlocked yes)
			(layer "B.Fab")
			(hide yes)
			(effects
				(font
					(size 1.016 1.016)
					(thickness 0.1524)
				)
				(justify mirror)
			)
		)
		(property "Device Type" "C0201H13"
			(at 2.8321 -3.2639 90)
			(unlocked yes)
			(layer "B.Fab")
			(hide yes)
			(effects
				(font
					(size 1.016 1.016)
					(thickness 0.1524)
				)
				(justify mirror)
			)
		)
		(duplicate_pad_numbers_are_jumpers no)
		(fp_rect
			(start 0.2794 0.6477)
			(end -0.2794 -0.6477)
			(stroke
				(width 0)
				(type default)
			)
			(fill no)
			(layer "B.CrtYd")
		)
		(fp_rect
			(start 0.2794 0.6477)
			(end -0.2794 -0.6477)
			(stroke
				(width 0)
				(type default)
			)
			(fill no)
			(layer "B.Fab")
		)
		(pad "1" smd custom
			(at 0 -0.2794 270)
			(size 0.0762 0.0762)
			(layers "B.Cu" "B.Mask" "B.Paste")
			(net "P0V975")
			(options
				(clearance outline)
				(anchor circle)
			)
			(primitives
				(gr_poly
					(pts
						(arc
							(start 0.1524 0.127)
							(mid 0.137521 0.162921)
							(end 0.1016 0.1778)
						)
						(arc
							(start -0.1016 0.1778)
							(mid -0.137521 0.162921)
							(end -0.1524 0.127)
						)
						(arc
							(start -0.1524 -0.127)
							(mid -0.137521 -0.162921)
							(end -0.1016 -0.1778)
						)
						(arc
							(start 0.1016 -0.1778)
							(mid 0.137521 -0.162921)
							(end 0.1524 -0.127)
						)
					)
					(width 0)
					(fill yes)
				)
			)
		)
		(pad "2" smd custom
			(at 0 0.2794 270)
			(size 0.0762 0.0762)
			(layers "B.Cu" "B.Mask" "B.Paste")
			(net "GND")
			(options
				(clearance outline)
				(anchor circle)
			)
			(primitives
				(gr_poly
					(pts
						(arc
							(start 0.1524 0.127)
							(mid 0.137521 0.162921)
							(end 0.1016 0.1778)
						)
						(arc
							(start -0.1016 0.1778)
							(mid -0.137521 0.162921)
							(end -0.1524 0.127)
						)
						(arc
							(start -0.1524 -0.127)
							(mid -0.137521 -0.162921)
							(end -0.1016 -0.1778)
						)
						(arc
							(start 0.1016 -0.1778)
							(mid 0.137521 -0.162921)
							(end 0.1524 -0.127)
						)
					)
					(width 0)
					(fill yes)
				)
			)
		)
	)
	(footprint ""
		(layer "B.Cu")
		(at 183.668416 -84.718652 -90)
		(property "Reference" "R488"
			(at 0 0 90)
			(layer "B.SilkS")
			(hide yes)
			(effects
				(font
					(size 1.27 1.27)
				)
				(justify mirror)
			)
		)
		(property "Value" "10KR2F-2-GP"
			(at -0.064008 -3.993896 270)
			(unlocked yes)
			(layer "B.Fab")
			(hide yes)
			(effects
				(font
					(size 1.016 1.016)
					(thickness 0.1524)
				)
				(justify mirror)
			)
		)
		(property "Device Type" "R402H16"
			(at -0.064008 -5.517896 270)
			(unlocked yes)
			(layer "B.Fab")
			(hide yes)
			(effects
				(font
					(size 1.016 1.016)
					(thickness 0.1524)
				)
				(justify mirror)
			)
		)
		(duplicate_pad_numbers_are_jumpers no)
		(fp_line
			(start -0.508 -0.9398)
			(end 0.508 -0.9398)
			(stroke
				(width 0.1524)
				(type default)
			)
			(layer "B.SilkS")
		)
		(fp_line
			(start 0.508 -0.9398)
			(end 0.508 0.9398)
			(stroke
				(width 0.1524)
				(type default)
			)
			(layer "B.SilkS")
		)
		(fp_rect
			(start 0.508 0.9398)
			(end -0.508 -0.9398)
			(stroke
				(width 0)
				(type default)
			)
			(fill no)
			(layer "B.CrtYd")
		)
		(fp_rect
			(start 0.508 0.9398)
			(end -0.508 -0.9398)
			(stroke
				(width 0)
				(type default)
			)
			(fill no)
			(layer "B.Fab")
		)
		(pad "1" smd custom
			(at 0 -0.4445 90)
			(size 0.1397 0.1397)
			(layers "B.Cu" "B.Mask" "B.Paste")
			(net "GND")
			(options
				(clearance outline)
				(anchor circle)
			)
			(primitives
				(gr_poly
					(pts
						(arc
							(start -0.1778 0.2794)
							(mid -0.249642 0.249642)
							(end -0.2794 0.1778)
						)
						(arc
							(start -0.2794 -0.1778)
							(mid -0.249642 -0.249642)
							(end -0.1778 -0.2794)
						)
						(arc
							(start 0.1778 -0.2794)
							(mid 0.249642 -0.249642)
							(end 0.2794 -0.1778)
						)
						(arc
							(start 0.2794 0.1778)
							(mid 0.249642 0.249642)
							(end 0.1778 0.2794)
						)
					)
					(width 0)
					(fill yes)
				)
			)
		)
		(pad "2" smd custom
			(at 0 0.4445 90)
			(size 0.1397 0.1397)
			(layers "B.Cu" "B.Mask" "B.Paste")
			(net "P0V975")
			(options
				(clearance outline)
				(anchor circle)
			)
			(primitives
				(gr_poly
					(pts
						(arc
							(start -0.1778 0.2794)
							(mid -0.249642 0.249642)
							(end -0.2794 0.1778)
						)
						(arc
							(start -0.2794 -0.1778)
							(mid -0.249642 -0.249642)
							(end -0.1778 -0.2794)
						)
						(arc
							(start 0.1778 -0.2794)
							(mid 0.249642 -0.249642)
							(end 0.2794 -0.1778)
						)
						(arc
							(start 0.2794 0.1778)
							(mid 0.249642 0.249642)
							(end 0.1778 0.2794)
						)
					)
					(width 0)
					(fill yes)
				)
			)
		)
	)
	(footprint ""
		(layer "B.Cu")
		(at 176.200308 -37.03701 90)
		(property "Reference" "C428"
			(at 0 0 90)
			(layer "B.SilkS")
			(hide yes)
			(effects
				(font
					(size 1.27 1.27)
				)
				(justify mirror)
			)
		)
		(property "Value" "SCD1U6D3V1KX-GP"
			(at 2.8321 -1.7399 90)
			(unlocked yes)
			(layer "B.Fab")
			(hide yes)
			(effects
				(font
					(size 1.016 1.016)
					(thickness 0.1524)
				)
				(justify mirror)
			)
		)
		(property "Device Type" "C0201H13"
			(at 2.8321 -3.2639 90)
			(unlocked yes)
			(layer "B.Fab")
			(hide yes)
			(effects
				(font
					(size 1.016 1.016)
					(thickness 0.1524)
				)
				(justify mirror)
			)
		)
		(duplicate_pad_numbers_are_jumpers no)
		(fp_rect
			(start 0.2794 0.6477)
			(end -0.2794 -0.6477)
			(stroke
				(width 0)
				(type default)
			)
			(fill no)
			(layer "B.CrtYd")
		)
		(fp_rect
			(start 0.2794 0.6477)
			(end -0.2794 -0.6477)
			(stroke
				(width 0)
				(type default)
			)
			(fill no)
			(layer "B.Fab")
		)
		(pad "1" smd custom
			(at 0 -0.2794 270)
			(size 0.0762 0.0762)
			(layers "B.Cu" "B.Mask" "B.Paste")
			(net "P0V975")
			(options
				(clearance outline)
				(anchor circle)
			)
			(primitives
				(gr_poly
					(pts
						(arc
							(start 0.1524 0.127)
							(mid 0.137521 0.162921)
							(end 0.1016 0.1778)
						)
						(arc
							(start -0.1016 0.1778)
							(mid -0.137521 0.162921)
							(end -0.1524 0.127)
						)
						(arc
							(start -0.1524 -0.127)
							(mid -0.137521 -0.162921)
							(end -0.1016 -0.1778)
						)
						(arc
							(start 0.1016 -0.1778)
							(mid 0.137521 -0.162921)
							(end 0.1524 -0.127)
						)
					)
					(width 0)
					(fill yes)
				)
			)
		)
		(pad "2" smd custom
			(at 0 0.2794 270)
			(size 0.0762 0.0762)
			(layers "B.Cu" "B.Mask" "B.Paste")
			(net "GND")
			(options
				(clearance outline)
				(anchor circle)
			)
			(primitives
				(gr_poly
					(pts
						(arc
							(start 0.1524 0.127)
							(mid 0.137521 0.162921)
							(end 0.1016 0.1778)
						)
						(arc
							(start -0.1016 0.1778)
							(mid -0.137521 0.162921)
							(end -0.1524 0.127)
						)
						(arc
							(start -0.1524 -0.127)
							(mid -0.137521 -0.162921)
							(end -0.1016 -0.1778)
						)
						(arc
							(start 0.1016 -0.1778)
							(mid 0.137521 -0.162921)
							(end 0.1524 -0.127)
						)
					)
					(width 0)
					(fill yes)
				)
			)
		)
	)
	(footprint ""
		(layer "B.Cu")
		(at 112.395 -70.3834 180)
		(property "Reference" "C182"
			(at 0 0 0)
			(layer "B.SilkS")
			(hide yes)
			(effects
				(font
					(size 1.27 1.27)
				)
				(justify mirror)
			)
		)
		(property "Value" "SCD1U6D3V1KX-GP"
			(at 2.8321 -1.7399 180)
			(unlocked yes)
			(layer "B.Fab")
			(hide yes)
			(effects
				(font
					(size 1.016 1.016)
					(thickness 0.1524)
				)
				(justify mirror)
			)
		)
		(property "Device Type" "C0201H13"
			(at 2.8321 -3.2639 180)
			(unlocked yes)
			(layer "B.Fab")
			(hide yes)
			(effects
				(font
					(size 1.016 1.016)
					(thickness 0.1524)
				)
				(justify mirror)
			)
		)
		(duplicate_pad_numbers_are_jumpers no)
		(fp_rect
			(start 0.2794 0.6477)
			(end -0.2794 -0.6477)
			(stroke
				(width 0)
				(type default)
			)
			(fill no)
			(layer "B.CrtYd")
		)
		(fp_rect
			(start 0.2794 0.6477)
			(end -0.2794 -0.6477)
			(stroke
				(width 0)
				(type default)
			)
			(fill no)
			(layer "B.Fab")
		)
		(pad "1" smd custom
			(at 0 -0.2794)
			(size 0.0762 0.0762)
			(layers "B.Cu" "B.Mask" "B.Paste")
			(net "P0V9")
			(options
				(clearance outline)
				(anchor circle)
			)
			(primitives
				(gr_poly
					(pts
						(arc
							(start 0.1524 0.127)
							(mid 0.137521 0.162921)
							(end 0.1016 0.1778)
						)
						(arc
							(start -0.1016 0.1778)
							(mid -0.137521 0.162921)
							(end -0.1524 0.127)
						)
						(arc
							(start -0.1524 -0.127)
							(mid -0.137521 -0.162921)
							(end -0.1016 -0.1778)
						)
						(arc
							(start 0.1016 -0.1778)
							(mid 0.137521 -0.162921)
							(end 0.1524 -0.127)
						)
					)
					(width 0)
					(fill yes)
				)
			)
		)
		(pad "2" smd custom
			(at 0 0.2794)
			(size 0.0762 0.0762)
			(layers "B.Cu" "B.Mask" "B.Paste")
			(net "GND")
			(options
				(clearance outline)
				(anchor circle)
			)
			(primitives
				(gr_poly
					(pts
						(arc
							(start 0.1524 0.127)
							(mid 0.137521 0.162921)
							(end 0.1016 0.1778)
						)
						(arc
							(start -0.1016 0.1778)
							(mid -0.137521 0.162921)
							(end -0.1524 0.127)
						)
						(arc
							(start -0.1524 -0.127)
							(mid -0.137521 -0.162921)
							(end -0.1016 -0.1778)
						)
						(arc
							(start 0.1016 -0.1778)
							(mid 0.137521 -0.162921)
							(end 0.1524 -0.127)
						)
					)
					(width 0)
					(fill yes)
				)
			)
		)
	)
	(footprint ""
		(layer "B.Cu")
		(at 112.499902 -77.499972)
		(property "Reference" "TP47"
			(at 0 0 0)
			(layer "B.SilkS")
			(hide yes)
			(effects
				(font
					(size 1.27 1.27)
				)
				(justify mirror)
			)
		)
		(property "Value" "TPAD28-2-GP"
			(at 0.0127 -1.6637 0)
			(unlocked yes)
			(layer "B.Fab")
			(hide yes)
			(effects
				(font
					(size 1.016 1.016)
					(thickness 0.1524)
				)
				(justify mirror)
			)
		)
		(property "Device Type" "TPAD28"
			(at 0.0127 -3.1877 0)
			(unlocked yes)
			(layer "B.Fab")
			(hide yes)
			(effects
				(font
					(size 1.016 1.016)
					(thickness 0.1524)
				)
				(justify mirror)
			)
		)
		(duplicate_pad_numbers_are_jumpers no)
		(fp_poly
			(pts
				(arc
					(start 0.3556 0)
					(mid -0.3556 0)
					(end 0.3556 0)
				)
			)
			(stroke
				(width 0)
				(type default)
			)
			(fill no)
			(layer "B.CrtYd")
		)
		(fp_poly
			(pts
				(arc
					(start 0.6096 0)
					(mid -0.6096 0)
					(end 0.6096 0)
				)
			)
			(stroke
				(width 0)
				(type default)
			)
			(fill no)
			(layer "B.Fab")
		)
		(pad "1" smd circle
			(at 0 0 180)
			(size 0.7112 0.7112)
			(layers "B.Cu" "B.Mask" "B.Paste")
			(net "XM_GP_CS_3#_TP")
		)
	)
	(footprint ""
		(layer "B.Cu")
		(at 89.46642 -63.899034)
		(property "Reference" "L1"
			(at 0 0 0)
			(layer "B.SilkS")
			(hide yes)
			(effects
				(font
					(size 1.27 1.27)
				)
				(justify mirror)
			)
		)
		(property "Value" "MPZ2012S601AT-GP"
			(at 0 -4.2418 0)
			(unlocked yes)
			(layer "B.Fab")
			(hide yes)
			(effects
				(font
					(size 1.016 1.016)
					(thickness 0.1524)
				)
				(justify mirror)
			)
		)
		(property "Device Type" "L805H42"
			(at 0 -5.7912 0)
			(unlocked yes)
			(layer "B.Fab")
			(hide yes)
			(effects
				(font
					(size 1.016 1.016)
					(thickness 0.1524)
				)
				(justify mirror)
			)
		)
		(duplicate_pad_numbers_are_jumpers no)
		(fp_line
			(start -0.889 -1.7018)
			(end -0.889 1.7018)
			(stroke
				(width 0.1524)
				(type default)
			)
			(layer "B.SilkS")
		)
		(fp_line
			(start -0.889 1.7018)
			(end 0.889 1.7018)
			(stroke
				(width 0.1524)
				(type default)
			)
			(layer "B.SilkS")
		)
		(fp_line
			(start 0.889 -1.7018)
			(end -0.889 -1.7018)
			(stroke
				(width 0.1524)
				(type default)
			)
			(layer "B.SilkS")
		)
		(fp_line
			(start 0.889 1.7018)
			(end 0.889 -1.7018)
			(stroke
				(width 0.1524)
				(type default)
			)
			(layer "B.SilkS")
		)
		(fp_rect
			(start 0.9652 1.778)
			(end -0.9652 -1.778)
			(stroke
				(width 0)
				(type default)
			)
			(fill no)
			(layer "B.CrtYd")
		)
		(fp_rect
			(start 0.9652 1.778)
			(end -0.9652 -1.778)
			(stroke
				(width 0)
				(type default)
			)
			(fill no)
			(layer "B.Fab")
		)
		(pad "1" smd rect
			(at 0 -0.9652 180)
			(size 1.397 1.143)
			(layers "B.Cu" "B.Mask" "B.Paste")
			(net "XTAL_VDDA18")
		)
		(pad "2" smd rect
			(at 0 0.9652 180)
			(size 1.397 1.143)
			(layers "B.Cu" "B.Mask" "B.Paste")
			(net "P1V8_E")
		)
	)
	(footprint ""
		(layer "B.Cu")
		(at 108.585 -84.4296 180)
		(property "Reference" "R111"
			(at 0 0 0)
			(layer "B.SilkS")
			(hide yes)
			(effects
				(font
					(size 1.27 1.27)
				)
				(justify mirror)
			)
		)
		(property "Value" "4K75R2F-1-GP"
			(at -0.064008 -3.993896 180)
			(unlocked yes)
			(layer "B.Fab")
			(hide yes)
			(effects
				(font
					(size 1.016 1.016)
					(thickness 0.1524)
				)
				(justify mirror)
			)
		)
		(property "Device Type" "R402H16"
			(at -0.064008 -5.517896 180)
			(unlocked yes)
			(layer "B.Fab")
			(hide yes)
			(effects
				(font
					(size 1.016 1.016)
					(thickness 0.1524)
				)
				(justify mirror)
			)
		)
		(duplicate_pad_numbers_are_jumpers no)
		(fp_line
			(start 0.508 -0.9398)
			(end 0.508 0.9398)
			(stroke
				(width 0.1524)
				(type default)
			)
			(layer "B.SilkS")
		)
		(fp_line
			(start -0.508 -0.9398)
			(end 0.508 -0.9398)
			(stroke
				(width 0.1524)
				(type default)
			)
			(layer "B.SilkS")
		)
		(fp_rect
			(start 0.508 0.9398)
			(end -0.508 -0.9398)
			(stroke
				(width 0)
				(type default)
			)
			(fill no)
			(layer "B.CrtYd")
		)
		(fp_rect
			(start 0.508 0.9398)
			(end -0.508 -0.9398)
			(stroke
				(width 0)
				(type default)
			)
			(fill no)
			(layer "B.Fab")
		)
		(pad "1" smd custom
			(at 0 -0.4445)
			(size 0.1397 0.1397)
			(layers "B.Cu" "B.Mask" "B.Paste")
			(net "EXP_CPU_MODE_1")
			(options
				(clearance outline)
				(anchor circle)
			)
			(primitives
				(gr_poly
					(pts
						(arc
							(start -0.1778 0.2794)
							(mid -0.249642 0.249642)
							(end -0.2794 0.1778)
						)
						(arc
							(start -0.2794 -0.1778)
							(mid -0.249642 -0.249642)
							(end -0.1778 -0.2794)
						)
						(arc
							(start 0.1778 -0.2794)
							(mid 0.249642 -0.249642)
							(end 0.2794 -0.1778)
						)
						(arc
							(start 0.2794 0.1778)
							(mid 0.249642 0.249642)
							(end 0.1778 0.2794)
						)
					)
					(width 0)
					(fill yes)
				)
			)
		)
		(pad "2" smd custom
			(at 0 0.4445)
			(size 0.1397 0.1397)
			(layers "B.Cu" "B.Mask" "B.Paste")
			(net "GND")
			(options
				(clearance outline)
				(anchor circle)
			)
			(primitives
				(gr_poly
					(pts
						(arc
							(start -0.1778 0.2794)
							(mid -0.249642 0.249642)
							(end -0.2794 0.1778)
						)
						(arc
							(start -0.2794 -0.1778)
							(mid -0.249642 -0.249642)
							(end -0.1778 -0.2794)
						)
						(arc
							(start 0.1778 -0.2794)
							(mid 0.249642 -0.249642)
							(end 0.2794 -0.1778)
						)
						(arc
							(start 0.2794 0.1778)
							(mid 0.249642 0.249642)
							(end 0.1778 0.2794)
						)
					)
					(width 0)
					(fill yes)
				)
			)
		)
	)
	(footprint ""
		(layer "B.Cu")
		(at 96.497394 -54.557168 90)
		(property "Reference" "C95"
			(at 0 0 90)
			(layer "B.SilkS")
			(hide yes)
			(effects
				(font
					(size 1.27 1.27)
				)
				(justify mirror)
			)
		)
		(property "Value" "SCD01U16V1KX-GP"
			(at 2.8321 -1.7399 90)
			(unlocked yes)
			(layer "B.Fab")
			(hide yes)
			(effects
				(font
					(size 1.016 1.016)
					(thickness 0.1524)
				)
				(justify mirror)
			)
		)
		(property "Device Type" "C0201H13"
			(at 2.8321 -3.2639 90)
			(unlocked yes)
			(layer "B.Fab")
			(hide yes)
			(effects
				(font
					(size 1.016 1.016)
					(thickness 0.1524)
				)
				(justify mirror)
			)
		)
		(duplicate_pad_numbers_are_jumpers no)
		(fp_rect
			(start 0.2794 0.6477)
			(end -0.2794 -0.6477)
			(stroke
				(width 0)
				(type default)
			)
			(fill no)
			(layer "B.CrtYd")
		)
		(fp_rect
			(start 0.2794 0.6477)
			(end -0.2794 -0.6477)
			(stroke
				(width 0)
				(type default)
			)
			(fill no)
			(layer "B.Fab")
		)
		(pad "1" smd custom
			(at 0 -0.2794 270)
			(size 0.0762 0.0762)
			(layers "B.Cu" "B.Mask" "B.Paste")
			(net "PHY_DPB_TO_SCC_12_DP")
			(options
				(clearance outline)
				(anchor circle)
			)
			(primitives
				(gr_poly
					(pts
						(arc
							(start 0.1524 0.127)
							(mid 0.137521 0.162921)
							(end 0.1016 0.1778)
						)
						(arc
							(start -0.1016 0.1778)
							(mid -0.137521 0.162921)
							(end -0.1524 0.127)
						)
						(arc
							(start -0.1524 -0.127)
							(mid -0.137521 -0.162921)
							(end -0.1016 -0.1778)
						)
						(arc
							(start 0.1016 -0.1778)
							(mid 0.137521 -0.162921)
							(end 0.1524 -0.127)
						)
					)
					(width 0)
					(fill yes)
				)
			)
		)
		(pad "2" smd custom
			(at 0 0.2794 270)
			(size 0.0762 0.0762)
			(layers "B.Cu" "B.Mask" "B.Paste")
			(net "PHY_DPB_TO_SCC_C_12_DP")
			(options
				(clearance outline)
				(anchor circle)
			)
			(primitives
				(gr_poly
					(pts
						(arc
							(start 0.1524 0.127)
							(mid 0.137521 0.162921)
							(end 0.1016 0.1778)
						)
						(arc
							(start -0.1016 0.1778)
							(mid -0.137521 0.162921)
							(end -0.1524 0.127)
						)
						(arc
							(start -0.1524 -0.127)
							(mid -0.137521 -0.162921)
							(end -0.1016 -0.1778)
						)
						(arc
							(start 0.1016 -0.1778)
							(mid 0.137521 -0.162921)
							(end 0.1524 -0.127)
						)
					)
					(width 0)
					(fill yes)
				)
			)
		)
	)
	(footprint ""
		(layer "B.Cu")
		(at 179.441348 -41.887902 90)
		(property "Reference" "C411"
			(at 0 0 90)
			(layer "B.SilkS")
			(hide yes)
			(effects
				(font
					(size 1.27 1.27)
				)
				(justify mirror)
			)
		)
		(property "Value" "SC1U6D3V1MX-GP"
			(at -1.9177 2.0193 90)
			(unlocked yes)
			(layer "B.Fab")
			(hide yes)
			(effects
				(font
					(size 1.016 1.016)
					(thickness 0.1524)
				)
				(justify mirror)
			)
		)
		(property "Device Type" "C0201H14"
			(at -1.9177 0.4953 90)
			(unlocked yes)
			(layer "B.Fab")
			(hide yes)
			(effects
				(font
					(size 1.016 1.016)
					(thickness 0.1524)
				)
				(justify mirror)
			)
		)
		(duplicate_pad_numbers_are_jumpers no)
		(fp_rect
			(start 0.1524 0.3048)
			(end -0.1524 -0.3048)
			(stroke
				(width 0)
				(type default)
			)
			(fill no)
			(layer "B.CrtYd")
		)
		(fp_poly
			(pts
				(xy 0.2794 0.6477) (xy 0.2794 -0.6477) (xy -0.2794 -0.6477) (xy -0.2794 -0.1905) (xy -0.1524 -0.1905)
				(xy -0.1524 -0.3048) (xy 0.1524 -0.3048) (xy 0.1524 0.3048) (xy -0.1524 0.3048) (xy -0.1524 -0.1778)
				(xy -0.2794 -0.1778) (xy -0.2794 0.6477)
			)
			(stroke
				(width 0)
				(type default)
			)
			(fill no)
			(layer "B.CrtYd")
		)
		(fp_rect
			(start 0.2794 0.6477)
			(end -0.2794 -0.6477)
			(stroke
				(width 0)
				(type default)
			)
			(fill no)
			(layer "B.Fab")
		)
		(pad "1" smd custom
			(at 0 -0.2794 270)
			(size 0.0762 0.0762)
			(layers "B.Cu" "B.Mask" "B.Paste")
			(net "P0V975")
			(options
				(clearance outline)
				(anchor circle)
			)
			(primitives
				(gr_poly
					(pts
						(arc
							(start 0.1524 0.127)
							(mid 0.137521 0.162921)
							(end 0.1016 0.1778)
						)
						(arc
							(start -0.1016 0.1778)
							(mid -0.137521 0.162921)
							(end -0.1524 0.127)
						)
						(arc
							(start -0.1524 -0.127)
							(mid -0.137521 -0.162921)
							(end -0.1016 -0.1778)
						)
						(arc
							(start 0.1016 -0.1778)
							(mid 0.137521 -0.162921)
							(end 0.1524 -0.127)
						)
					)
					(width 0)
					(fill yes)
				)
			)
		)
		(pad "2" smd custom
			(at 0 0.2794 270)
			(size 0.0762 0.0762)
			(layers "B.Cu" "B.Mask" "B.Paste")
			(net "GND")
			(options
				(clearance outline)
				(anchor circle)
			)
			(primitives
				(gr_poly
					(pts
						(arc
							(start 0.1524 0.127)
							(mid 0.137521 0.162921)
							(end 0.1016 0.1778)
						)
						(arc
							(start -0.1016 0.1778)
							(mid -0.137521 0.162921)
							(end -0.1524 0.127)
						)
						(arc
							(start -0.1524 -0.127)
							(mid -0.137521 -0.162921)
							(end -0.1016 -0.1778)
						)
						(arc
							(start 0.1016 -0.1778)
							(mid 0.137521 -0.162921)
							(end 0.1524 -0.127)
						)
					)
					(width 0)
					(fill yes)
				)
			)
		)
	)
	(footprint ""
		(layer "B.Cu")
		(at 81.733898 -70.40118)
		(property "Reference" "C516"
			(at 0 0 0)
			(layer "B.SilkS")
			(hide yes)
			(effects
				(font
					(size 1.27 1.27)
				)
				(justify mirror)
			)
		)
		(property "Value" "SCD1U16V2KX-3GP"
			(at -1.1811 -2.7051 0)
			(unlocked yes)
			(layer "B.Fab")
			(hide yes)
			(effects
				(font
					(size 1.016 1.016)
					(thickness 0.1524)
				)
				(justify mirror)
			)
		)
		(property "Device Type" "C402H22"
			(at -1.1811 -4.2291 0)
			(unlocked yes)
			(layer "B.Fab")
			(hide yes)
			(effects
				(font
					(size 1.016 1.016)
					(thickness 0.1524)
				)
				(justify mirror)
			)
		)
		(duplicate_pad_numbers_are_jumpers no)
		(fp_rect
			(start 0.4318 0.9525)
			(end -0.4318 -0.9525)
			(stroke
				(width 0)
				(type default)
			)
			(fill no)
			(layer "B.CrtYd")
		)
		(fp_rect
			(start 0.4318 0.9525)
			(end -0.4318 -0.9525)
			(stroke
				(width 0)
				(type default)
			)
			(fill no)
			(layer "B.Fab")
		)
		(pad "1" smd custom
			(at 0 -0.4445 180)
			(size 0.1524 0.1524)
			(layers "B.Cu" "B.Mask" "B.Paste")
			(net "P3V3")
			(options
				(clearance outline)
				(anchor circle)
			)
			(primitives
				(gr_poly
					(pts
						(arc
							(start 0.3048 0.2032)
							(mid 0.275042 0.275042)
							(end 0.2032 0.3048)
						)
						(arc
							(start -0.2032 0.3048)
							(mid -0.275042 0.275042)
							(end -0.3048 0.2032)
						)
						(arc
							(start -0.3048 -0.2032)
							(mid -0.275042 -0.275042)
							(end -0.2032 -0.3048)
						)
						(arc
							(start 0.2032 -0.3048)
							(mid 0.275042 -0.275042)
							(end 0.3048 -0.2032)
						)
					)
					(width 0)
					(fill yes)
				)
			)
		)
		(pad "2" smd custom
			(at 0 0.4445 180)
			(size 0.1524 0.1524)
			(layers "B.Cu" "B.Mask" "B.Paste")
			(net "GND")
			(options
				(clearance outline)
				(anchor circle)
			)
			(primitives
				(gr_poly
					(pts
						(arc
							(start 0.3048 0.2032)
							(mid 0.275042 0.275042)
							(end 0.2032 0.3048)
						)
						(arc
							(start -0.2032 0.3048)
							(mid -0.275042 0.275042)
							(end -0.3048 0.2032)
						)
						(arc
							(start -0.3048 -0.2032)
							(mid -0.275042 -0.275042)
							(end -0.2032 -0.3048)
						)
						(arc
							(start 0.2032 -0.3048)
							(mid 0.275042 -0.275042)
							(end 0.3048 -0.2032)
						)
					)
					(width 0)
					(fill yes)
				)
			)
		)
	)
	(footprint ""
		(layer "B.Cu")
		(at 109.499908 -74.499978)
		(property "Reference" "TP37"
			(at 0 0 0)
			(layer "B.SilkS")
			(hide yes)
			(effects
				(font
					(size 1.27 1.27)
				)
				(justify mirror)
			)
		)
		(property "Value" "TPAD28-2-GP"
			(at 0.0127 -1.6637 0)
			(unlocked yes)
			(layer "B.Fab")
			(hide yes)
			(effects
				(font
					(size 1.016 1.016)
					(thickness 0.1524)
				)
				(justify mirror)
			)
		)
		(property "Device Type" "TPAD28"
			(at 0.0127 -3.1877 0)
			(unlocked yes)
			(layer "B.Fab")
			(hide yes)
			(effects
				(font
					(size 1.016 1.016)
					(thickness 0.1524)
				)
				(justify mirror)
			)
		)
		(duplicate_pad_numbers_are_jumpers no)
		(fp_poly
			(pts
				(arc
					(start 0.3556 0)
					(mid -0.3556 0)
					(end 0.3556 0)
				)
			)
			(stroke
				(width 0)
				(type default)
			)
			(fill no)
			(layer "B.CrtYd")
		)
		(fp_poly
			(pts
				(arc
					(start 0.6096 0)
					(mid -0.6096 0)
					(end 0.6096 0)
				)
			)
			(stroke
				(width 0)
				(type default)
			)
			(fill no)
			(layer "B.Fab")
		)
		(pad "1" smd circle
			(at 0 0 180)
			(size 0.7112 0.7112)
			(layers "B.Cu" "B.Mask" "B.Paste")
			(net "JTAG_EXP_TCK")
		)
	)
	(footprint ""
		(layer "B.Cu")
		(at 119.888 -89.535 180)
		(property "Reference" "R375"
			(at 0 0 0)
			(layer "B.SilkS")
			(hide yes)
			(effects
				(font
					(size 1.27 1.27)
				)
				(justify mirror)
			)
		)
		(property "Value" "10KR2F-2-GP"
			(at -0.064008 -3.993896 180)
			(unlocked yes)
			(layer "B.Fab")
			(hide yes)
			(effects
				(font
					(size 1.016 1.016)
					(thickness 0.1524)
				)
				(justify mirror)
			)
		)
		(property "Device Type" "R402H16"
			(at -0.064008 -5.517896 180)
			(unlocked yes)
			(layer "B.Fab")
			(hide yes)
			(effects
				(font
					(size 1.016 1.016)
					(thickness 0.1524)
				)
				(justify mirror)
			)
		)
		(duplicate_pad_numbers_are_jumpers no)
		(fp_line
			(start 0.508 -0.9398)
			(end 0.508 0.9398)
			(stroke
				(width 0.1524)
				(type default)
			)
			(layer "B.SilkS")
		)
		(fp_line
			(start -0.508 -0.9398)
			(end 0.508 -0.9398)
			(stroke
				(width 0.1524)
				(type default)
			)
			(layer "B.SilkS")
		)
		(fp_rect
			(start 0.508 0.9398)
			(end -0.508 -0.9398)
			(stroke
				(width 0)
				(type default)
			)
			(fill no)
			(layer "B.CrtYd")
		)
		(fp_rect
			(start 0.508 0.9398)
			(end -0.508 -0.9398)
			(stroke
				(width 0)
				(type default)
			)
			(fill no)
			(layer "B.Fab")
		)
		(pad "1" smd custom
			(at 0 -0.4445)
			(size 0.1397 0.1397)
			(layers "B.Cu" "B.Mask" "B.Paste")
			(net "COMP_SPARE_0_LS")
			(options
				(clearance outline)
				(anchor circle)
			)
			(primitives
				(gr_poly
					(pts
						(arc
							(start -0.1778 0.2794)
							(mid -0.249642 0.249642)
							(end -0.2794 0.1778)
						)
						(arc
							(start -0.2794 -0.1778)
							(mid -0.249642 -0.249642)
							(end -0.1778 -0.2794)
						)
						(arc
							(start 0.1778 -0.2794)
							(mid 0.249642 -0.249642)
							(end 0.2794 -0.1778)
						)
						(arc
							(start 0.2794 0.1778)
							(mid 0.249642 0.249642)
							(end 0.1778 0.2794)
						)
					)
					(width 0)
					(fill yes)
				)
			)
		)
		(pad "2" smd custom
			(at 0 0.4445)
			(size 0.1397 0.1397)
			(layers "B.Cu" "B.Mask" "B.Paste")
			(net "GND")
			(options
				(clearance outline)
				(anchor circle)
			)
			(primitives
				(gr_poly
					(pts
						(arc
							(start -0.1778 0.2794)
							(mid -0.249642 0.249642)
							(end -0.2794 0.1778)
						)
						(arc
							(start -0.2794 -0.1778)
							(mid -0.249642 -0.249642)
							(end -0.1778 -0.2794)
						)
						(arc
							(start 0.1778 -0.2794)
							(mid 0.249642 -0.249642)
							(end 0.2794 -0.1778)
						)
						(arc
							(start 0.2794 0.1778)
							(mid 0.249642 0.249642)
							(end 0.1778 0.2794)
						)
					)
					(width 0)
					(fill yes)
				)
			)
		)
	)
	(footprint ""
		(layer "B.Cu")
		(at 104.4956 -64.77 180)
		(property "Reference" "C199"
			(at 0 0 0)
			(layer "B.SilkS")
			(hide yes)
			(effects
				(font
					(size 1.27 1.27)
				)
				(justify mirror)
			)
		)
		(property "Value" "SCD1U6D3V1KX-GP"
			(at 2.8321 -1.7399 180)
			(unlocked yes)
			(layer "B.Fab")
			(hide yes)
			(effects
				(font
					(size 1.016 1.016)
					(thickness 0.1524)
				)
				(justify mirror)
			)
		)
		(property "Device Type" "C0201H13"
			(at 2.8321 -3.2639 180)
			(unlocked yes)
			(layer "B.Fab")
			(hide yes)
			(effects
				(font
					(size 1.016 1.016)
					(thickness 0.1524)
				)
				(justify mirror)
			)
		)
		(duplicate_pad_numbers_are_jumpers no)
		(fp_rect
			(start 0.2794 0.6477)
			(end -0.2794 -0.6477)
			(stroke
				(width 0)
				(type default)
			)
			(fill no)
			(layer "B.CrtYd")
		)
		(fp_rect
			(start 0.2794 0.6477)
			(end -0.2794 -0.6477)
			(stroke
				(width 0)
				(type default)
			)
			(fill no)
			(layer "B.Fab")
		)
		(pad "1" smd custom
			(at 0 -0.2794)
			(size 0.0762 0.0762)
			(layers "B.Cu" "B.Mask" "B.Paste")
			(net "SYSPLL_VDDA18")
			(options
				(clearance outline)
				(anchor circle)
			)
			(primitives
				(gr_poly
					(pts
						(arc
							(start 0.1524 0.127)
							(mid 0.137521 0.162921)
							(end 0.1016 0.1778)
						)
						(arc
							(start -0.1016 0.1778)
							(mid -0.137521 0.162921)
							(end -0.1524 0.127)
						)
						(arc
							(start -0.1524 -0.127)
							(mid -0.137521 -0.162921)
							(end -0.1016 -0.1778)
						)
						(arc
							(start 0.1016 -0.1778)
							(mid 0.137521 -0.162921)
							(end 0.1524 -0.127)
						)
					)
					(width 0)
					(fill yes)
				)
			)
		)
		(pad "2" smd custom
			(at 0 0.2794)
			(size 0.0762 0.0762)
			(layers "B.Cu" "B.Mask" "B.Paste")
			(net "GND")
			(options
				(clearance outline)
				(anchor circle)
			)
			(primitives
				(gr_poly
					(pts
						(arc
							(start 0.1524 0.127)
							(mid 0.137521 0.162921)
							(end 0.1016 0.1778)
						)
						(arc
							(start -0.1016 0.1778)
							(mid -0.137521 0.162921)
							(end -0.1524 0.127)
						)
						(arc
							(start -0.1524 -0.127)
							(mid -0.137521 -0.162921)
							(end -0.1016 -0.1778)
						)
						(arc
							(start 0.1016 -0.1778)
							(mid 0.137521 -0.162921)
							(end 0.1524 -0.127)
						)
					)
					(width 0)
					(fill yes)
				)
			)
		)
	)
	(footprint ""
		(layer "B.Cu")
		(at 117.488462 -70.37578 180)
		(property "Reference" "C187"
			(at 0 0 0)
			(layer "B.SilkS")
			(hide yes)
			(effects
				(font
					(size 1.27 1.27)
				)
				(justify mirror)
			)
		)
		(property "Value" "SC1KP25V1KX-GP"
			(at 2.8321 -1.7399 180)
			(unlocked yes)
			(layer "B.Fab")
			(hide yes)
			(effects
				(font
					(size 1.016 1.016)
					(thickness 0.1524)
				)
				(justify mirror)
			)
		)
		(property "Device Type" "C0201H13"
			(at 2.8321 -3.2639 180)
			(unlocked yes)
			(layer "B.Fab")
			(hide yes)
			(effects
				(font
					(size 1.016 1.016)
					(thickness 0.1524)
				)
				(justify mirror)
			)
		)
		(duplicate_pad_numbers_are_jumpers no)
		(fp_rect
			(start 0.2794 0.6477)
			(end -0.2794 -0.6477)
			(stroke
				(width 0)
				(type default)
			)
			(fill no)
			(layer "B.CrtYd")
		)
		(fp_rect
			(start 0.2794 0.6477)
			(end -0.2794 -0.6477)
			(stroke
				(width 0)
				(type default)
			)
			(fill no)
			(layer "B.Fab")
		)
		(pad "1" smd custom
			(at 0 -0.2794)
			(size 0.0762 0.0762)
			(layers "B.Cu" "B.Mask" "B.Paste")
			(net "P0V9")
			(options
				(clearance outline)
				(anchor circle)
			)
			(primitives
				(gr_poly
					(pts
						(arc
							(start 0.1524 0.127)
							(mid 0.137521 0.162921)
							(end 0.1016 0.1778)
						)
						(arc
							(start -0.1016 0.1778)
							(mid -0.137521 0.162921)
							(end -0.1524 0.127)
						)
						(arc
							(start -0.1524 -0.127)
							(mid -0.137521 -0.162921)
							(end -0.1016 -0.1778)
						)
						(arc
							(start 0.1016 -0.1778)
							(mid 0.137521 -0.162921)
							(end 0.1524 -0.127)
						)
					)
					(width 0)
					(fill yes)
				)
			)
		)
		(pad "2" smd custom
			(at 0 0.2794)
			(size 0.0762 0.0762)
			(layers "B.Cu" "B.Mask" "B.Paste")
			(net "GND")
			(options
				(clearance outline)
				(anchor circle)
			)
			(primitives
				(gr_poly
					(pts
						(arc
							(start 0.1524 0.127)
							(mid 0.137521 0.162921)
							(end 0.1016 0.1778)
						)
						(arc
							(start -0.1016 0.1778)
							(mid -0.137521 0.162921)
							(end -0.1524 0.127)
						)
						(arc
							(start -0.1524 -0.127)
							(mid -0.137521 -0.162921)
							(end -0.1016 -0.1778)
						)
						(arc
							(start 0.1016 -0.1778)
							(mid 0.137521 -0.162921)
							(end 0.1524 -0.127)
						)
					)
					(width 0)
					(fill yes)
				)
			)
		)
	)
	(footprint ""
		(layer "B.Cu")
		(at 129.397252 -57.35066 90)
		(property "Reference" "C299"
			(at 0 0 90)
			(layer "B.SilkS")
			(hide yes)
			(effects
				(font
					(size 1.27 1.27)
				)
				(justify mirror)
			)
		)
		(property "Value" "SCD1U6D3V1KX-GP"
			(at 2.8321 -1.7399 90)
			(unlocked yes)
			(layer "B.Fab")
			(hide yes)
			(effects
				(font
					(size 1.016 1.016)
					(thickness 0.1524)
				)
				(justify mirror)
			)
		)
		(property "Device Type" "C0201H13"
			(at 2.8321 -3.2639 90)
			(unlocked yes)
			(layer "B.Fab")
			(hide yes)
			(effects
				(font
					(size 1.016 1.016)
					(thickness 0.1524)
				)
				(justify mirror)
			)
		)
		(duplicate_pad_numbers_are_jumpers no)
		(fp_rect
			(start 0.2794 0.6477)
			(end -0.2794 -0.6477)
			(stroke
				(width 0)
				(type default)
			)
			(fill no)
			(layer "B.CrtYd")
		)
		(fp_rect
			(start 0.2794 0.6477)
			(end -0.2794 -0.6477)
			(stroke
				(width 0)
				(type default)
			)
			(fill no)
			(layer "B.Fab")
		)
		(pad "1" smd custom
			(at 0 -0.2794 270)
			(size 0.0762 0.0762)
			(layers "B.Cu" "B.Mask" "B.Paste")
			(net "GB_VDDA")
			(options
				(clearance outline)
				(anchor circle)
			)
			(primitives
				(gr_poly
					(pts
						(arc
							(start 0.1524 0.127)
							(mid 0.137521 0.162921)
							(end 0.1016 0.1778)
						)
						(arc
							(start -0.1016 0.1778)
							(mid -0.137521 0.162921)
							(end -0.1524 0.127)
						)
						(arc
							(start -0.1524 -0.127)
							(mid -0.137521 -0.162921)
							(end -0.1016 -0.1778)
						)
						(arc
							(start 0.1016 -0.1778)
							(mid 0.137521 -0.162921)
							(end 0.1524 -0.127)
						)
					)
					(width 0)
					(fill yes)
				)
			)
		)
		(pad "2" smd custom
			(at 0 0.2794 270)
			(size 0.0762 0.0762)
			(layers "B.Cu" "B.Mask" "B.Paste")
			(net "GND")
			(options
				(clearance outline)
				(anchor circle)
			)
			(primitives
				(gr_poly
					(pts
						(arc
							(start 0.1524 0.127)
							(mid 0.137521 0.162921)
							(end 0.1016 0.1778)
						)
						(arc
							(start -0.1016 0.1778)
							(mid -0.137521 0.162921)
							(end -0.1524 0.127)
						)
						(arc
							(start -0.1524 -0.127)
							(mid -0.137521 -0.162921)
							(end -0.1016 -0.1778)
						)
						(arc
							(start 0.1016 -0.1778)
							(mid 0.137521 -0.162921)
							(end 0.1524 -0.127)
						)
					)
					(width 0)
					(fill yes)
				)
			)
		)
	)
	(footprint ""
		(layer "B.Cu")
		(at 126.290324 -87.256874 180)
		(property "Reference" "R40"
			(at 0 0 0)
			(layer "B.SilkS")
			(hide yes)
			(effects
				(font
					(size 1.27 1.27)
				)
				(justify mirror)
			)
		)
		(property "Value" "4K7R2F-GP"
			(at -0.064008 -3.993896 180)
			(unlocked yes)
			(layer "B.Fab")
			(hide yes)
			(effects
				(font
					(size 1.016 1.016)
					(thickness 0.1524)
				)
				(justify mirror)
			)
		)
		(property "Device Type" "R402H16"
			(at -0.064008 -5.517896 180)
			(unlocked yes)
			(layer "B.Fab")
			(hide yes)
			(effects
				(font
					(size 1.016 1.016)
					(thickness 0.1524)
				)
				(justify mirror)
			)
		)
		(duplicate_pad_numbers_are_jumpers no)
		(fp_line
			(start 0.508 -0.9398)
			(end 0.508 0.9398)
			(stroke
				(width 0.1524)
				(type default)
			)
			(layer "B.SilkS")
		)
		(fp_line
			(start -0.508 -0.9398)
			(end 0.508 -0.9398)
			(stroke
				(width 0.1524)
				(type default)
			)
			(layer "B.SilkS")
		)
		(fp_rect
			(start 0.508 0.9398)
			(end -0.508 -0.9398)
			(stroke
				(width 0)
				(type default)
			)
			(fill no)
			(layer "B.CrtYd")
		)
		(fp_rect
			(start 0.508 0.9398)
			(end -0.508 -0.9398)
			(stroke
				(width 0)
				(type default)
			)
			(fill no)
			(layer "B.Fab")
		)
		(pad "1" smd custom
			(at 0 -0.4445)
			(size 0.1397 0.1397)
			(layers "B.Cu" "B.Mask" "B.Paste")
			(net "EXP_SIO_CLK_IN")
			(options
				(clearance outline)
				(anchor circle)
			)
			(primitives
				(gr_poly
					(pts
						(arc
							(start -0.1778 0.2794)
							(mid -0.249642 0.249642)
							(end -0.2794 0.1778)
						)
						(arc
							(start -0.2794 -0.1778)
							(mid -0.249642 -0.249642)
							(end -0.1778 -0.2794)
						)
						(arc
							(start 0.1778 -0.2794)
							(mid 0.249642 -0.249642)
							(end 0.2794 -0.1778)
						)
						(arc
							(start 0.2794 0.1778)
							(mid 0.249642 0.249642)
							(end 0.1778 0.2794)
						)
					)
					(width 0)
					(fill yes)
				)
			)
		)
		(pad "2" smd custom
			(at 0 0.4445)
			(size 0.1397 0.1397)
			(layers "B.Cu" "B.Mask" "B.Paste")
			(net "P1V8_E")
			(options
				(clearance outline)
				(anchor circle)
			)
			(primitives
				(gr_poly
					(pts
						(arc
							(start -0.1778 0.2794)
							(mid -0.249642 0.249642)
							(end -0.2794 0.1778)
						)
						(arc
							(start -0.2794 -0.1778)
							(mid -0.249642 -0.249642)
							(end -0.1778 -0.2794)
						)
						(arc
							(start 0.1778 -0.2794)
							(mid 0.249642 -0.249642)
							(end 0.2794 -0.1778)
						)
						(arc
							(start 0.2794 0.1778)
							(mid 0.249642 0.249642)
							(end 0.1778 0.2794)
						)
					)
					(width 0)
					(fill yes)
				)
			)
		)
	)
	(footprint ""
		(layer "B.Cu")
		(at 192.024 -40.8432 -90)
		(property "Reference" "R182"
			(at 0 0 90)
			(layer "B.SilkS")
			(hide yes)
			(effects
				(font
					(size 1.27 1.27)
				)
				(justify mirror)
			)
		)
		(property "Value" "2K2R2F-GP"
			(at -0.064008 -3.993896 270)
			(unlocked yes)
			(layer "B.Fab")
			(hide yes)
			(effects
				(font
					(size 1.016 1.016)
					(thickness 0.1524)
				)
				(justify mirror)
			)
		)
		(property "Device Type" "R402H16"
			(at -0.064008 -5.517896 270)
			(unlocked yes)
			(layer "B.Fab")
			(hide yes)
			(effects
				(font
					(size 1.016 1.016)
					(thickness 0.1524)
				)
				(justify mirror)
			)
		)
		(duplicate_pad_numbers_are_jumpers no)
		(fp_line
			(start -0.508 -0.9398)
			(end 0.508 -0.9398)
			(stroke
				(width 0.1524)
				(type default)
			)
			(layer "B.SilkS")
		)
		(fp_line
			(start 0.508 -0.9398)
			(end 0.508 0.9398)
			(stroke
				(width 0.1524)
				(type default)
			)
			(layer "B.SilkS")
		)
		(fp_rect
			(start 0.508 0.9398)
			(end -0.508 -0.9398)
			(stroke
				(width 0)
				(type default)
			)
			(fill no)
			(layer "B.CrtYd")
		)
		(fp_rect
			(start 0.508 0.9398)
			(end -0.508 -0.9398)
			(stroke
				(width 0)
				(type default)
			)
			(fill no)
			(layer "B.Fab")
		)
		(pad "1" smd custom
			(at 0 -0.4445 90)
			(size 0.1397 0.1397)
			(layers "B.Cu" "B.Mask" "B.Paste")
			(net "P1V8_C")
			(options
				(clearance outline)
				(anchor circle)
			)
			(primitives
				(gr_poly
					(pts
						(arc
							(start -0.1778 0.2794)
							(mid -0.249642 0.249642)
							(end -0.2794 0.1778)
						)
						(arc
							(start -0.2794 -0.1778)
							(mid -0.249642 -0.249642)
							(end -0.1778 -0.2794)
						)
						(arc
							(start 0.1778 -0.2794)
							(mid 0.249642 -0.249642)
							(end 0.2794 -0.1778)
						)
						(arc
							(start 0.2794 0.1778)
							(mid 0.249642 0.249642)
							(end 0.1778 0.2794)
						)
					)
					(width 0)
					(fill yes)
				)
			)
		)
		(pad "2" smd custom
			(at 0 0.4445 90)
			(size 0.1397 0.1397)
			(layers "B.Cu" "B.Mask" "B.Paste")
			(net "I2C_IOC_0_SDA")
			(options
				(clearance outline)
				(anchor circle)
			)
			(primitives
				(gr_poly
					(pts
						(arc
							(start -0.1778 0.2794)
							(mid -0.249642 0.249642)
							(end -0.2794 0.1778)
						)
						(arc
							(start -0.2794 -0.1778)
							(mid -0.249642 -0.249642)
							(end -0.1778 -0.2794)
						)
						(arc
							(start 0.1778 -0.2794)
							(mid 0.249642 -0.249642)
							(end 0.2794 -0.1778)
						)
						(arc
							(start 0.2794 0.1778)
							(mid 0.249642 0.249642)
							(end 0.1778 0.2794)
						)
					)
					(width 0)
					(fill yes)
				)
			)
		)
	)
	(footprint ""
		(layer "B.Cu")
		(at 124.4981 -60.5028 90)
		(property "Reference" "C252"
			(at 0 0 90)
			(layer "B.SilkS")
			(hide yes)
			(effects
				(font
					(size 1.27 1.27)
				)
				(justify mirror)
			)
		)
		(property "Value" "SCD1U6D3V1KX-GP"
			(at 2.8321 -1.7399 90)
			(unlocked yes)
			(layer "B.Fab")
			(hide yes)
			(effects
				(font
					(size 1.016 1.016)
					(thickness 0.1524)
				)
				(justify mirror)
			)
		)
		(property "Device Type" "C0201H13"
			(at 2.8321 -3.2639 90)
			(unlocked yes)
			(layer "B.Fab")
			(hide yes)
			(effects
				(font
					(size 1.016 1.016)
					(thickness 0.1524)
				)
				(justify mirror)
			)
		)
		(duplicate_pad_numbers_are_jumpers no)
		(fp_rect
			(start 0.2794 0.6477)
			(end -0.2794 -0.6477)
			(stroke
				(width 0)
				(type default)
			)
			(fill no)
			(layer "B.CrtYd")
		)
		(fp_rect
			(start 0.2794 0.6477)
			(end -0.2794 -0.6477)
			(stroke
				(width 0)
				(type default)
			)
			(fill no)
			(layer "B.Fab")
		)
		(pad "1" smd custom
			(at 0 -0.2794 270)
			(size 0.0762 0.0762)
			(layers "B.Cu" "B.Mask" "B.Paste")
			(net "GB_VDDA")
			(options
				(clearance outline)
				(anchor circle)
			)
			(primitives
				(gr_poly
					(pts
						(arc
							(start 0.1524 0.127)
							(mid 0.137521 0.162921)
							(end 0.1016 0.1778)
						)
						(arc
							(start -0.1016 0.1778)
							(mid -0.137521 0.162921)
							(end -0.1524 0.127)
						)
						(arc
							(start -0.1524 -0.127)
							(mid -0.137521 -0.162921)
							(end -0.1016 -0.1778)
						)
						(arc
							(start 0.1016 -0.1778)
							(mid 0.137521 -0.162921)
							(end 0.1524 -0.127)
						)
					)
					(width 0)
					(fill yes)
				)
			)
		)
		(pad "2" smd custom
			(at 0 0.2794 270)
			(size 0.0762 0.0762)
			(layers "B.Cu" "B.Mask" "B.Paste")
			(net "GND")
			(options
				(clearance outline)
				(anchor circle)
			)
			(primitives
				(gr_poly
					(pts
						(arc
							(start 0.1524 0.127)
							(mid 0.137521 0.162921)
							(end 0.1016 0.1778)
						)
						(arc
							(start -0.1016 0.1778)
							(mid -0.137521 0.162921)
							(end -0.1524 0.127)
						)
						(arc
							(start -0.1524 -0.127)
							(mid -0.137521 -0.162921)
							(end -0.1016 -0.1778)
						)
						(arc
							(start 0.1016 -0.1778)
							(mid 0.137521 -0.162921)
							(end 0.1524 -0.127)
						)
					)
					(width 0)
					(fill yes)
				)
			)
		)
	)
	(footprint ""
		(layer "B.Cu")
		(at 186.276488 -33.07969 90)
		(property "Reference" "TP86"
			(at 0 0 90)
			(layer "B.SilkS")
			(hide yes)
			(effects
				(font
					(size 1.27 1.27)
				)
				(justify mirror)
			)
		)
		(property "Value" "TPAD28-2-GP"
			(at 0.0127 -1.6637 90)
			(unlocked yes)
			(layer "B.Fab")
			(hide yes)
			(effects
				(font
					(size 1.016 1.016)
					(thickness 0.1524)
				)
				(justify mirror)
			)
		)
		(property "Device Type" "TPAD28"
			(at 0.0127 -3.1877 90)
			(unlocked yes)
			(layer "B.Fab")
			(hide yes)
			(effects
				(font
					(size 1.016 1.016)
					(thickness 0.1524)
				)
				(justify mirror)
			)
		)
		(duplicate_pad_numbers_are_jumpers no)
		(fp_poly
			(pts
				(arc
					(start 0 0.3556)
					(mid 0 -0.3556)
					(end 0 0.3556)
				)
			)
			(stroke
				(width 0)
				(type default)
			)
			(fill no)
			(layer "B.CrtYd")
		)
		(fp_poly
			(pts
				(arc
					(start 0 0.6096)
					(mid 0 -0.6096)
					(end 0 0.6096)
				)
			)
			(stroke
				(width 0)
				(type default)
			)
			(fill no)
			(layer "B.Fab")
		)
		(pad "1" smd circle
			(at 0 0 270)
			(size 0.7112 0.7112)
			(layers "B.Cu" "B.Mask" "B.Paste")
			(net "IOC_GPIO_29")
		)
	)
	(footprint ""
		(layer "B.Cu")
		(at 90.974926 -67.835272)
		(property "Reference" "R153"
			(at 0 0 0)
			(layer "B.SilkS")
			(hide yes)
			(effects
				(font
					(size 1.27 1.27)
				)
				(justify mirror)
			)
		)
		(property "Value" "10R2F-L-GP"
			(at -0.064008 -3.993896 0)
			(unlocked yes)
			(layer "B.Fab")
			(hide yes)
			(effects
				(font
					(size 1.016 1.016)
					(thickness 0.1524)
				)
				(justify mirror)
			)
		)
		(property "Device Type" "R402H14"
			(at -0.064008 -5.517896 0)
			(unlocked yes)
			(layer "B.Fab")
			(hide yes)
			(effects
				(font
					(size 1.016 1.016)
					(thickness 0.1524)
				)
				(justify mirror)
			)
		)
		(duplicate_pad_numbers_are_jumpers no)
		(fp_line
			(start -0.508 -0.9398)
			(end 0.508 -0.9398)
			(stroke
				(width 0.1524)
				(type default)
			)
			(layer "B.SilkS")
		)
		(fp_line
			(start 0.508 -0.9398)
			(end 0.508 0.9398)
			(stroke
				(width 0.1524)
				(type default)
			)
			(layer "B.SilkS")
		)
		(fp_rect
			(start 0.508 0.9398)
			(end -0.508 -0.9398)
			(stroke
				(width 0)
				(type default)
			)
			(fill no)
			(layer "B.CrtYd")
		)
		(fp_rect
			(start 0.508 0.9398)
			(end -0.508 -0.9398)
			(stroke
				(width 0)
				(type default)
			)
			(fill no)
			(layer "B.Fab")
		)
		(pad "1" smd custom
			(at 0 -0.4445 180)
			(size 0.1397 0.1397)
			(layers "B.Cu" "B.Mask" "B.Paste")
			(net "P1V8_E")
			(options
				(clearance outline)
				(anchor circle)
			)
			(primitives
				(gr_poly
					(pts
						(arc
							(start -0.1778 0.2794)
							(mid -0.249642 0.249642)
							(end -0.2794 0.1778)
						)
						(arc
							(start -0.2794 -0.1778)
							(mid -0.249642 -0.249642)
							(end -0.1778 -0.2794)
						)
						(arc
							(start 0.1778 -0.2794)
							(mid 0.249642 -0.249642)
							(end 0.2794 -0.1778)
						)
						(arc
							(start 0.2794 0.1778)
							(mid 0.249642 0.249642)
							(end 0.1778 0.2794)
						)
					)
					(width 0)
					(fill yes)
				)
			)
		)
		(pad "2" smd custom
			(at 0 0.4445 180)
			(size 0.1397 0.1397)
			(layers "B.Cu" "B.Mask" "B.Paste")
			(net "PLLDDR_VDDA18")
			(options
				(clearance outline)
				(anchor circle)
			)
			(primitives
				(gr_poly
					(pts
						(arc
							(start -0.1778 0.2794)
							(mid -0.249642 0.249642)
							(end -0.2794 0.1778)
						)
						(arc
							(start -0.2794 -0.1778)
							(mid -0.249642 -0.249642)
							(end -0.1778 -0.2794)
						)
						(arc
							(start 0.1778 -0.2794)
							(mid 0.249642 -0.249642)
							(end 0.2794 -0.1778)
						)
						(arc
							(start 0.2794 0.1778)
							(mid 0.249642 0.249642)
							(end 0.1778 0.2794)
						)
					)
					(width 0)
					(fill yes)
				)
			)
		)
	)
	(footprint ""
		(layer "B.Cu")
		(at 107.061 -87.0712 180)
		(property "Reference" "R47"
			(at 0 0 0)
			(layer "B.SilkS")
			(hide yes)
			(effects
				(font
					(size 1.27 1.27)
				)
				(justify mirror)
			)
		)
		(property "Value" "4K75R2F-1-GP"
			(at -0.064008 -3.993896 180)
			(unlocked yes)
			(layer "B.Fab")
			(hide yes)
			(effects
				(font
					(size 1.016 1.016)
					(thickness 0.1524)
				)
				(justify mirror)
			)
		)
		(property "Device Type" "R402H16"
			(at -0.064008 -5.517896 180)
			(unlocked yes)
			(layer "B.Fab")
			(hide yes)
			(effects
				(font
					(size 1.016 1.016)
					(thickness 0.1524)
				)
				(justify mirror)
			)
		)
		(duplicate_pad_numbers_are_jumpers no)
		(fp_line
			(start 0.508 -0.9398)
			(end 0.508 0.9398)
			(stroke
				(width 0.1524)
				(type default)
			)
			(layer "B.SilkS")
		)
		(fp_line
			(start -0.508 -0.9398)
			(end 0.508 -0.9398)
			(stroke
				(width 0.1524)
				(type default)
			)
			(layer "B.SilkS")
		)
		(fp_rect
			(start 0.508 0.9398)
			(end -0.508 -0.9398)
			(stroke
				(width 0)
				(type default)
			)
			(fill no)
			(layer "B.CrtYd")
		)
		(fp_rect
			(start 0.508 0.9398)
			(end -0.508 -0.9398)
			(stroke
				(width 0)
				(type default)
			)
			(fill no)
			(layer "B.Fab")
		)
		(pad "1" smd custom
			(at 0 -0.4445)
			(size 0.1397 0.1397)
			(layers "B.Cu" "B.Mask" "B.Paste")
			(net "GND")
			(options
				(clearance outline)
				(anchor circle)
			)
			(primitives
				(gr_poly
					(pts
						(arc
							(start -0.1778 0.2794)
							(mid -0.249642 0.249642)
							(end -0.2794 0.1778)
						)
						(arc
							(start -0.2794 -0.1778)
							(mid -0.249642 -0.249642)
							(end -0.1778 -0.2794)
						)
						(arc
							(start 0.1778 -0.2794)
							(mid 0.249642 -0.249642)
							(end 0.2794 -0.1778)
						)
						(arc
							(start 0.2794 0.1778)
							(mid 0.249642 0.249642)
							(end 0.1778 0.2794)
						)
					)
					(width 0)
					(fill yes)
				)
			)
		)
		(pad "2" smd custom
			(at 0 0.4445)
			(size 0.1397 0.1397)
			(layers "B.Cu" "B.Mask" "B.Paste")
			(net "EXP_BLINK_IN")
			(options
				(clearance outline)
				(anchor circle)
			)
			(primitives
				(gr_poly
					(pts
						(arc
							(start -0.1778 0.2794)
							(mid -0.249642 0.249642)
							(end -0.2794 0.1778)
						)
						(arc
							(start -0.2794 -0.1778)
							(mid -0.249642 -0.249642)
							(end -0.1778 -0.2794)
						)
						(arc
							(start 0.1778 -0.2794)
							(mid 0.249642 -0.249642)
							(end 0.2794 -0.1778)
						)
						(arc
							(start 0.2794 0.1778)
							(mid 0.249642 0.249642)
							(end 0.1778 0.2794)
						)
					)
					(width 0)
					(fill yes)
				)
			)
		)
	)
	(footprint ""
		(layer "B.Cu")
		(at 189.427612 -45.263816 -90)
		(property "Reference" "TP105"
			(at 0 0 90)
			(layer "B.SilkS")
			(hide yes)
			(effects
				(font
					(size 1.27 1.27)
				)
				(justify mirror)
			)
		)
		(property "Value" "TPAD28-2-GP"
			(at 0.0127 -1.6637 270)
			(unlocked yes)
			(layer "B.Fab")
			(hide yes)
			(effects
				(font
					(size 1.016 1.016)
					(thickness 0.1524)
				)
				(justify mirror)
			)
		)
		(property "Device Type" "TPAD28"
			(at 0.0127 -3.1877 270)
			(unlocked yes)
			(layer "B.Fab")
			(hide yes)
			(effects
				(font
					(size 1.016 1.016)
					(thickness 0.1524)
				)
				(justify mirror)
			)
		)
		(duplicate_pad_numbers_are_jumpers no)
		(fp_poly
			(pts
				(arc
					(start 0 -0.3556)
					(mid 0 0.3556)
					(end 0 -0.3556)
				)
			)
			(stroke
				(width 0)
				(type default)
			)
			(fill no)
			(layer "B.CrtYd")
		)
		(fp_poly
			(pts
				(arc
					(start 0 -0.6096)
					(mid 0 0.6096)
					(end 0 -0.6096)
				)
			)
			(stroke
				(width 0)
				(type default)
			)
			(fill no)
			(layer "B.Fab")
		)
		(pad "1" smd circle
			(at 0 0 90)
			(size 0.7112 0.7112)
			(layers "B.Cu" "B.Mask" "B.Paste")
			(net "XM_ADDR_18")
		)
	)
	(footprint ""
		(layer "B.Cu")
		(at 177.429414 -51.025806 180)
		(property "Reference" "R220"
			(at 0 0 0)
			(layer "B.SilkS")
			(hide yes)
			(effects
				(font
					(size 1.27 1.27)
				)
				(justify mirror)
			)
		)
		(property "Value" "10KR2F-2-GP"
			(at -0.064008 -3.993896 180)
			(unlocked yes)
			(layer "B.Fab")
			(hide yes)
			(effects
				(font
					(size 1.016 1.016)
					(thickness 0.1524)
				)
				(justify mirror)
			)
		)
		(property "Device Type" "R402H16"
			(at -0.064008 -5.517896 180)
			(unlocked yes)
			(layer "B.Fab")
			(hide yes)
			(effects
				(font
					(size 1.016 1.016)
					(thickness 0.1524)
				)
				(justify mirror)
			)
		)
		(duplicate_pad_numbers_are_jumpers no)
		(fp_line
			(start 0.508 -0.9398)
			(end 0.508 0.9398)
			(stroke
				(width 0.1524)
				(type default)
			)
			(layer "B.SilkS")
		)
		(fp_line
			(start -0.508 -0.9398)
			(end 0.508 -0.9398)
			(stroke
				(width 0.1524)
				(type default)
			)
			(layer "B.SilkS")
		)
		(fp_rect
			(start 0.508 0.9398)
			(end -0.508 -0.9398)
			(stroke
				(width 0)
				(type default)
			)
			(fill no)
			(layer "B.CrtYd")
		)
		(fp_rect
			(start 0.508 0.9398)
			(end -0.508 -0.9398)
			(stroke
				(width 0)
				(type default)
			)
			(fill no)
			(layer "B.Fab")
		)
		(pad "1" smd custom
			(at 0 -0.4445)
			(size 0.1397 0.1397)
			(layers "B.Cu" "B.Mask" "B.Paste")
			(net "P1V8_C")
			(options
				(clearance outline)
				(anchor circle)
			)
			(primitives
				(gr_poly
					(pts
						(arc
							(start -0.1778 0.2794)
							(mid -0.249642 0.249642)
							(end -0.2794 0.1778)
						)
						(arc
							(start -0.2794 -0.1778)
							(mid -0.249642 -0.249642)
							(end -0.1778 -0.2794)
						)
						(arc
							(start 0.1778 -0.2794)
							(mid 0.249642 -0.249642)
							(end 0.2794 -0.1778)
						)
						(arc
							(start 0.2794 0.1778)
							(mid 0.249642 0.249642)
							(end 0.1778 0.2794)
						)
					)
					(width 0)
					(fill yes)
				)
			)
		)
		(pad "2" smd custom
			(at 0 0.4445)
			(size 0.1397 0.1397)
			(layers "B.Cu" "B.Mask" "B.Paste")
			(net "XM_NAND_CS_N")
			(options
				(clearance outline)
				(anchor circle)
			)
			(primitives
				(gr_poly
					(pts
						(arc
							(start -0.1778 0.2794)
							(mid -0.249642 0.249642)
							(end -0.2794 0.1778)
						)
						(arc
							(start -0.2794 -0.1778)
							(mid -0.249642 -0.249642)
							(end -0.1778 -0.2794)
						)
						(arc
							(start 0.1778 -0.2794)
							(mid 0.249642 -0.249642)
							(end 0.2794 -0.1778)
						)
						(arc
							(start 0.2794 0.1778)
							(mid 0.249642 0.249642)
							(end 0.1778 0.2794)
						)
					)
					(width 0)
					(fill yes)
				)
			)
		)
	)
	(footprint ""
		(layer "B.Cu")
		(at 177.254408 -49.50333 -90)
		(property "Reference" "C497"
			(at 0 0 90)
			(layer "B.SilkS")
			(hide yes)
			(effects
				(font
					(size 1.27 1.27)
				)
				(justify mirror)
			)
		)
		(property "Value" "SC1KP50V2KX-1GP"
			(at -1.1811 -2.7051 270)
			(unlocked yes)
			(layer "B.Fab")
			(hide yes)
			(effects
				(font
					(size 1.016 1.016)
					(thickness 0.1524)
				)
				(justify mirror)
			)
		)
		(property "Device Type" "C402H22"
			(at -1.1811 -4.2291 270)
			(unlocked yes)
			(layer "B.Fab")
			(hide yes)
			(effects
				(font
					(size 1.016 1.016)
					(thickness 0.1524)
				)
				(justify mirror)
			)
		)
		(duplicate_pad_numbers_are_jumpers no)
		(fp_rect
			(start 0.4318 0.9525)
			(end -0.4318 -0.9525)
			(stroke
				(width 0)
				(type default)
			)
			(fill no)
			(layer "B.CrtYd")
		)
		(fp_rect
			(start 0.4318 0.9525)
			(end -0.4318 -0.9525)
			(stroke
				(width 0)
				(type default)
			)
			(fill no)
			(layer "B.Fab")
		)
		(pad "1" smd custom
			(at 0 -0.4445 90)
			(size 0.1524 0.1524)
			(layers "B.Cu" "B.Mask" "B.Paste")
			(net "P1V8_C")
			(options
				(clearance outline)
				(anchor circle)
			)
			(primitives
				(gr_poly
					(pts
						(arc
							(start 0.3048 0.2032)
							(mid 0.275042 0.275042)
							(end 0.2032 0.3048)
						)
						(arc
							(start -0.2032 0.3048)
							(mid -0.275042 0.275042)
							(end -0.3048 0.2032)
						)
						(arc
							(start -0.3048 -0.2032)
							(mid -0.275042 -0.275042)
							(end -0.2032 -0.3048)
						)
						(arc
							(start 0.2032 -0.3048)
							(mid 0.275042 -0.275042)
							(end 0.3048 -0.2032)
						)
					)
					(width 0)
					(fill yes)
				)
			)
		)
		(pad "2" smd custom
			(at 0 0.4445 90)
			(size 0.1524 0.1524)
			(layers "B.Cu" "B.Mask" "B.Paste")
			(net "GND")
			(options
				(clearance outline)
				(anchor circle)
			)
			(primitives
				(gr_poly
					(pts
						(arc
							(start 0.3048 0.2032)
							(mid 0.275042 0.275042)
							(end 0.2032 0.3048)
						)
						(arc
							(start -0.2032 0.3048)
							(mid -0.275042 0.275042)
							(end -0.3048 0.2032)
						)
						(arc
							(start -0.3048 -0.2032)
							(mid -0.275042 -0.275042)
							(end -0.2032 -0.3048)
						)
						(arc
							(start 0.2032 -0.3048)
							(mid 0.275042 -0.275042)
							(end 0.3048 -0.2032)
						)
					)
					(width 0)
					(fill yes)
				)
			)
		)
	)
	(footprint ""
		(layer "B.Cu")
		(at 158.8262 -27.178)
		(property "Reference" "L24"
			(at 0 0 0)
			(layer "B.SilkS")
			(hide yes)
			(effects
				(font
					(size 1.27 1.27)
				)
				(justify mirror)
			)
		)
		(property "Value" "MPZ2012S601AT-GP"
			(at 0 -4.2418 0)
			(unlocked yes)
			(layer "B.Fab")
			(hide yes)
			(effects
				(font
					(size 1.016 1.016)
					(thickness 0.1524)
				)
				(justify mirror)
			)
		)
		(property "Device Type" "L805H42"
			(at 0 -5.7912 0)
			(unlocked yes)
			(layer "B.Fab")
			(hide yes)
			(effects
				(font
					(size 1.016 1.016)
					(thickness 0.1524)
				)
				(justify mirror)
			)
		)
		(duplicate_pad_numbers_are_jumpers no)
		(fp_line
			(start -0.889 -1.7018)
			(end -0.889 1.7018)
			(stroke
				(width 0.1524)
				(type default)
			)
			(layer "B.SilkS")
		)
		(fp_line
			(start -0.889 1.7018)
			(end 0.889 1.7018)
			(stroke
				(width 0.1524)
				(type default)
			)
			(layer "B.SilkS")
		)
		(fp_line
			(start 0.889 -1.7018)
			(end -0.889 -1.7018)
			(stroke
				(width 0.1524)
				(type default)
			)
			(layer "B.SilkS")
		)
		(fp_line
			(start 0.889 1.7018)
			(end 0.889 -1.7018)
			(stroke
				(width 0.1524)
				(type default)
			)
			(layer "B.SilkS")
		)
		(fp_rect
			(start 0.9652 1.778)
			(end -0.9652 -1.778)
			(stroke
				(width 0)
				(type default)
			)
			(fill no)
			(layer "B.CrtYd")
		)
		(fp_rect
			(start 0.9652 1.778)
			(end -0.9652 -1.778)
			(stroke
				(width 0)
				(type default)
			)
			(fill no)
			(layer "B.Fab")
		)
		(pad "1" smd rect
			(at 0 -0.9652 180)
			(size 1.397 1.143)
			(layers "B.Cu" "B.Mask" "B.Paste")
			(net "SAS0_VDDH")
		)
		(pad "2" smd rect
			(at 0 0.9652 180)
			(size 1.397 1.143)
			(layers "B.Cu" "B.Mask" "B.Paste")
			(net "P1V8_C")
		)
	)
	(footprint ""
		(layer "B.Cu")
		(at 154.184604 -64.122808 -90)
		(property "Reference" "C355"
			(at 0 0 90)
			(layer "B.SilkS")
			(hide yes)
			(effects
				(font
					(size 1.27 1.27)
				)
				(justify mirror)
			)
		)
		(property "Value" "SC22U6D3V3MX-9-GP-U"
			(at 0 -2.8194 270)
			(unlocked yes)
			(layer "B.Fab")
			(hide yes)
			(effects
				(font
					(size 1.016 1.016)
					(thickness 0.1524)
				)
				(justify mirror)
			)
		)
		(property "Device Type" "C603H40"
			(at 0 -4.3434 270)
			(unlocked yes)
			(layer "B.Fab")
			(hide yes)
			(effects
				(font
					(size 1.016 1.016)
					(thickness 0.1524)
				)
				(justify mirror)
			)
		)
		(duplicate_pad_numbers_are_jumpers no)
		(fp_line
			(start -0.508 0)
			(end 0.508 0)
			(stroke
				(width 0.2032)
				(type default)
			)
			(layer "B.SilkS")
		)
		(fp_rect
			(start 0.5842 1.3335)
			(end -0.5842 -1.3335)
			(stroke
				(width 0)
				(type default)
			)
			(fill no)
			(layer "B.CrtYd")
		)
		(fp_rect
			(start 0.5842 1.3335)
			(end -0.5842 -1.3335)
			(stroke
				(width 0)
				(type default)
			)
			(fill no)
			(layer "B.Fab")
		)
		(pad "1" smd custom
			(at 0 -0.762 90)
			(size 0.2159 0.2159)
			(layers "B.Cu" "B.Mask" "B.Paste")
			(net "SYS_PLL_VDD")
			(options
				(clearance outline)
				(anchor circle)
			)
			(primitives
				(gr_poly
					(pts
						(arc
							(start -0.3302 0.4318)
							(mid -0.402042 0.402042)
							(end -0.4318 0.3302)
						)
						(arc
							(start -0.4318 -0.3302)
							(mid -0.402042 -0.402042)
							(end -0.3302 -0.4318)
						)
						(arc
							(start 0.3302 -0.4318)
							(mid 0.402042 -0.402042)
							(end 0.4318 -0.3302)
						)
						(arc
							(start 0.4318 0.3302)
							(mid 0.402042 0.402042)
							(end 0.3302 0.4318)
						)
					)
					(width 0)
					(fill yes)
				)
			)
		)
		(pad "2" smd custom
			(at 0 0.762 90)
			(size 0.2159 0.2159)
			(layers "B.Cu" "B.Mask" "B.Paste")
			(net "GND")
			(options
				(clearance outline)
				(anchor circle)
			)
			(primitives
				(gr_poly
					(pts
						(arc
							(start -0.3302 0.4318)
							(mid -0.402042 0.402042)
							(end -0.4318 0.3302)
						)
						(arc
							(start -0.4318 -0.3302)
							(mid -0.402042 -0.402042)
							(end -0.3302 -0.4318)
						)
						(arc
							(start 0.3302 -0.4318)
							(mid 0.402042 -0.402042)
							(end 0.4318 -0.3302)
						)
						(arc
							(start 0.4318 0.3302)
							(mid 0.402042 0.402042)
							(end 0.3302 0.4318)
						)
					)
					(width 0)
					(fill yes)
				)
			)
		)
	)
	(footprint ""
		(layer "B.Cu")
		(at 163.576 -52.07)
		(property "Reference" "R195"
			(at 0 0 0)
			(layer "B.SilkS")
			(hide yes)
			(effects
				(font
					(size 1.27 1.27)
				)
				(justify mirror)
			)
		)
		(property "Value" "2K2R2F-GP"
			(at -0.064008 -3.993896 0)
			(unlocked yes)
			(layer "B.Fab")
			(hide yes)
			(effects
				(font
					(size 1.016 1.016)
					(thickness 0.1524)
				)
				(justify mirror)
			)
		)
		(property "Device Type" "R402H16"
			(at -0.064008 -5.517896 0)
			(unlocked yes)
			(layer "B.Fab")
			(hide yes)
			(effects
				(font
					(size 1.016 1.016)
					(thickness 0.1524)
				)
				(justify mirror)
			)
		)
		(duplicate_pad_numbers_are_jumpers no)
		(fp_line
			(start -0.508 -0.9398)
			(end 0.508 -0.9398)
			(stroke
				(width 0.1524)
				(type default)
			)
			(layer "B.SilkS")
		)
		(fp_line
			(start 0.508 -0.9398)
			(end 0.508 0.9398)
			(stroke
				(width 0.1524)
				(type default)
			)
			(layer "B.SilkS")
		)
		(fp_rect
			(start 0.508 0.9398)
			(end -0.508 -0.9398)
			(stroke
				(width 0)
				(type default)
			)
			(fill no)
			(layer "B.CrtYd")
		)
		(fp_rect
			(start 0.508 0.9398)
			(end -0.508 -0.9398)
			(stroke
				(width 0)
				(type default)
			)
			(fill no)
			(layer "B.Fab")
		)
		(pad "1" smd custom
			(at 0 -0.4445 180)
			(size 0.1397 0.1397)
			(layers "B.Cu" "B.Mask" "B.Paste")
			(net "P1V8_C")
			(options
				(clearance outline)
				(anchor circle)
			)
			(primitives
				(gr_poly
					(pts
						(arc
							(start -0.1778 0.2794)
							(mid -0.249642 0.249642)
							(end -0.2794 0.1778)
						)
						(arc
							(start -0.2794 -0.1778)
							(mid -0.249642 -0.249642)
							(end -0.1778 -0.2794)
						)
						(arc
							(start 0.1778 -0.2794)
							(mid 0.249642 -0.249642)
							(end 0.2794 -0.1778)
						)
						(arc
							(start 0.2794 0.1778)
							(mid 0.249642 0.249642)
							(end 0.1778 0.2794)
						)
					)
					(width 0)
					(fill yes)
				)
			)
		)
		(pad "2" smd custom
			(at 0 0.4445 180)
			(size 0.1397 0.1397)
			(layers "B.Cu" "B.Mask" "B.Paste")
			(net "SIO_DOUT_0")
			(options
				(clearance outline)
				(anchor circle)
			)
			(primitives
				(gr_poly
					(pts
						(arc
							(start -0.1778 0.2794)
							(mid -0.249642 0.249642)
							(end -0.2794 0.1778)
						)
						(arc
							(start -0.2794 -0.1778)
							(mid -0.249642 -0.249642)
							(end -0.1778 -0.2794)
						)
						(arc
							(start 0.1778 -0.2794)
							(mid 0.249642 -0.249642)
							(end 0.2794 -0.1778)
						)
						(arc
							(start 0.2794 0.1778)
							(mid 0.249642 0.249642)
							(end 0.1778 0.2794)
						)
					)
					(width 0)
					(fill yes)
				)
			)
		)
	)
	(footprint ""
		(layer "B.Cu")
		(at 164.781992 -11.70813)
		(property "Reference" "C502"
			(at 0 0 0)
			(layer "B.SilkS")
			(hide yes)
			(effects
				(font
					(size 1.27 1.27)
				)
				(justify mirror)
			)
		)
		(property "Value" "SCD1U16V2KX-3GP"
			(at -1.1811 -2.7051 0)
			(unlocked yes)
			(layer "B.Fab")
			(hide yes)
			(effects
				(font
					(size 1.016 1.016)
					(thickness 0.1524)
				)
				(justify mirror)
			)
		)
		(property "Device Type" "C402H22"
			(at -1.1811 -4.2291 0)
			(unlocked yes)
			(layer "B.Fab")
			(hide yes)
			(effects
				(font
					(size 1.016 1.016)
					(thickness 0.1524)
				)
				(justify mirror)
			)
		)
		(duplicate_pad_numbers_are_jumpers no)
		(fp_rect
			(start 0.4318 0.9525)
			(end -0.4318 -0.9525)
			(stroke
				(width 0)
				(type default)
			)
			(fill no)
			(layer "B.CrtYd")
		)
		(fp_rect
			(start 0.4318 0.9525)
			(end -0.4318 -0.9525)
			(stroke
				(width 0)
				(type default)
			)
			(fill no)
			(layer "B.Fab")
		)
		(pad "1" smd custom
			(at 0 -0.4445 180)
			(size 0.1524 0.1524)
			(layers "B.Cu" "B.Mask" "B.Paste")
			(net "P3V3")
			(options
				(clearance outline)
				(anchor circle)
			)
			(primitives
				(gr_poly
					(pts
						(arc
							(start 0.3048 0.2032)
							(mid 0.275042 0.275042)
							(end 0.2032 0.3048)
						)
						(arc
							(start -0.2032 0.3048)
							(mid -0.275042 0.275042)
							(end -0.3048 0.2032)
						)
						(arc
							(start -0.3048 -0.2032)
							(mid -0.275042 -0.275042)
							(end -0.2032 -0.3048)
						)
						(arc
							(start 0.2032 -0.3048)
							(mid 0.275042 -0.275042)
							(end 0.3048 -0.2032)
						)
					)
					(width 0)
					(fill yes)
				)
			)
		)
		(pad "2" smd custom
			(at 0 0.4445 180)
			(size 0.1524 0.1524)
			(layers "B.Cu" "B.Mask" "B.Paste")
			(net "GND")
			(options
				(clearance outline)
				(anchor circle)
			)
			(primitives
				(gr_poly
					(pts
						(arc
							(start 0.3048 0.2032)
							(mid 0.275042 0.275042)
							(end 0.2032 0.3048)
						)
						(arc
							(start -0.2032 0.3048)
							(mid -0.275042 0.275042)
							(end -0.3048 0.2032)
						)
						(arc
							(start -0.3048 -0.2032)
							(mid -0.275042 -0.275042)
							(end -0.2032 -0.3048)
						)
						(arc
							(start 0.2032 -0.3048)
							(mid 0.275042 -0.275042)
							(end 0.3048 -0.2032)
						)
					)
					(width 0)
					(fill yes)
				)
			)
		)
	)
	(footprint ""
		(layer "B.Cu")
		(at 113.1316 -84.455)
		(property "Reference" "R139"
			(at 0 0 0)
			(layer "B.SilkS")
			(hide yes)
			(effects
				(font
					(size 1.27 1.27)
				)
				(justify mirror)
			)
		)
		(property "Value" "10KR2F-2-GP"
			(at -0.064008 -3.993896 0)
			(unlocked yes)
			(layer "B.Fab")
			(hide yes)
			(effects
				(font
					(size 1.016 1.016)
					(thickness 0.1524)
				)
				(justify mirror)
			)
		)
		(property "Device Type" "R402H16"
			(at -0.064008 -5.517896 0)
			(unlocked yes)
			(layer "B.Fab")
			(hide yes)
			(effects
				(font
					(size 1.016 1.016)
					(thickness 0.1524)
				)
				(justify mirror)
			)
		)
		(duplicate_pad_numbers_are_jumpers no)
		(fp_line
			(start -0.508 -0.9398)
			(end 0.508 -0.9398)
			(stroke
				(width 0.1524)
				(type default)
			)
			(layer "B.SilkS")
		)
		(fp_line
			(start 0.508 -0.9398)
			(end 0.508 0.9398)
			(stroke
				(width 0.1524)
				(type default)
			)
			(layer "B.SilkS")
		)
		(fp_rect
			(start 0.508 0.9398)
			(end -0.508 -0.9398)
			(stroke
				(width 0)
				(type default)
			)
			(fill no)
			(layer "B.CrtYd")
		)
		(fp_rect
			(start 0.508 0.9398)
			(end -0.508 -0.9398)
			(stroke
				(width 0)
				(type default)
			)
			(fill no)
			(layer "B.Fab")
		)
		(pad "1" smd custom
			(at 0 -0.4445 180)
			(size 0.1397 0.1397)
			(layers "B.Cu" "B.Mask" "B.Paste")
			(net "P1V8_E")
			(options
				(clearance outline)
				(anchor circle)
			)
			(primitives
				(gr_poly
					(pts
						(arc
							(start -0.1778 0.2794)
							(mid -0.249642 0.249642)
							(end -0.2794 0.1778)
						)
						(arc
							(start -0.2794 -0.1778)
							(mid -0.249642 -0.249642)
							(end -0.1778 -0.2794)
						)
						(arc
							(start 0.1778 -0.2794)
							(mid 0.249642 -0.249642)
							(end 0.2794 -0.1778)
						)
						(arc
							(start 0.2794 0.1778)
							(mid 0.249642 0.249642)
							(end 0.1778 0.2794)
						)
					)
					(width 0)
					(fill yes)
				)
			)
		)
		(pad "2" smd custom
			(at 0 0.4445 180)
			(size 0.1397 0.1397)
			(layers "B.Cu" "B.Mask" "B.Paste")
			(net "EXP_XM_CS_N_0")
			(options
				(clearance outline)
				(anchor circle)
			)
			(primitives
				(gr_poly
					(pts
						(arc
							(start -0.1778 0.2794)
							(mid -0.249642 0.249642)
							(end -0.2794 0.1778)
						)
						(arc
							(start -0.2794 -0.1778)
							(mid -0.249642 -0.249642)
							(end -0.1778 -0.2794)
						)
						(arc
							(start 0.1778 -0.2794)
							(mid 0.249642 -0.249642)
							(end 0.2794 -0.1778)
						)
						(arc
							(start 0.2794 0.1778)
							(mid 0.249642 0.249642)
							(end 0.1778 0.2794)
						)
					)
					(width 0)
					(fill yes)
				)
			)
		)
	)
	(footprint ""
		(layer "B.Cu")
		(at 184.87517 -49.663858 90)
		(property "Reference" "C499"
			(at 0 0 90)
			(layer "B.SilkS")
			(hide yes)
			(effects
				(font
					(size 1.27 1.27)
				)
				(justify mirror)
			)
		)
		(property "Value" "SC1KP50V2KX-1GP"
			(at -1.1811 -2.7051 90)
			(unlocked yes)
			(layer "B.Fab")
			(hide yes)
			(effects
				(font
					(size 1.016 1.016)
					(thickness 0.1524)
				)
				(justify mirror)
			)
		)
		(property "Device Type" "C402H22"
			(at -1.1811 -4.2291 90)
			(unlocked yes)
			(layer "B.Fab")
			(hide yes)
			(effects
				(font
					(size 1.016 1.016)
					(thickness 0.1524)
				)
				(justify mirror)
			)
		)
		(duplicate_pad_numbers_are_jumpers no)
		(fp_rect
			(start 0.4318 0.9525)
			(end -0.4318 -0.9525)
			(stroke
				(width 0)
				(type default)
			)
			(fill no)
			(layer "B.CrtYd")
		)
		(fp_rect
			(start 0.4318 0.9525)
			(end -0.4318 -0.9525)
			(stroke
				(width 0)
				(type default)
			)
			(fill no)
			(layer "B.Fab")
		)
		(pad "1" smd custom
			(at 0 -0.4445 270)
			(size 0.1524 0.1524)
			(layers "B.Cu" "B.Mask" "B.Paste")
			(net "P1V8_C")
			(options
				(clearance outline)
				(anchor circle)
			)
			(primitives
				(gr_poly
					(pts
						(arc
							(start 0.3048 0.2032)
							(mid 0.275042 0.275042)
							(end 0.2032 0.3048)
						)
						(arc
							(start -0.2032 0.3048)
							(mid -0.275042 0.275042)
							(end -0.3048 0.2032)
						)
						(arc
							(start -0.3048 -0.2032)
							(mid -0.275042 -0.275042)
							(end -0.2032 -0.3048)
						)
						(arc
							(start 0.2032 -0.3048)
							(mid 0.275042 -0.275042)
							(end 0.3048 -0.2032)
						)
					)
					(width 0)
					(fill yes)
				)
			)
		)
		(pad "2" smd custom
			(at 0 0.4445 270)
			(size 0.1524 0.1524)
			(layers "B.Cu" "B.Mask" "B.Paste")
			(net "GND")
			(options
				(clearance outline)
				(anchor circle)
			)
			(primitives
				(gr_poly
					(pts
						(arc
							(start 0.3048 0.2032)
							(mid 0.275042 0.275042)
							(end 0.2032 0.3048)
						)
						(arc
							(start -0.2032 0.3048)
							(mid -0.275042 0.275042)
							(end -0.3048 0.2032)
						)
						(arc
							(start -0.3048 -0.2032)
							(mid -0.275042 -0.275042)
							(end -0.2032 -0.3048)
						)
						(arc
							(start 0.2032 -0.3048)
							(mid 0.275042 -0.275042)
							(end 0.3048 -0.2032)
						)
					)
					(width 0)
					(fill yes)
				)
			)
		)
	)
	(footprint ""
		(layer "B.Cu")
		(at 96.497394 -53.160168 90)
		(property "Reference" "C94"
			(at 0 0 90)
			(layer "B.SilkS")
			(hide yes)
			(effects
				(font
					(size 1.27 1.27)
				)
				(justify mirror)
			)
		)
		(property "Value" "SCD01U16V1KX-GP"
			(at 2.8321 -1.7399 90)
			(unlocked yes)
			(layer "B.Fab")
			(hide yes)
			(effects
				(font
					(size 1.016 1.016)
					(thickness 0.1524)
				)
				(justify mirror)
			)
		)
		(property "Device Type" "C0201H13"
			(at 2.8321 -3.2639 90)
			(unlocked yes)
			(layer "B.Fab")
			(hide yes)
			(effects
				(font
					(size 1.016 1.016)
					(thickness 0.1524)
				)
				(justify mirror)
			)
		)
		(duplicate_pad_numbers_are_jumpers no)
		(fp_rect
			(start 0.2794 0.6477)
			(end -0.2794 -0.6477)
			(stroke
				(width 0)
				(type default)
			)
			(fill no)
			(layer "B.CrtYd")
		)
		(fp_rect
			(start 0.2794 0.6477)
			(end -0.2794 -0.6477)
			(stroke
				(width 0)
				(type default)
			)
			(fill no)
			(layer "B.Fab")
		)
		(pad "1" smd custom
			(at 0 -0.2794 270)
			(size 0.0762 0.0762)
			(layers "B.Cu" "B.Mask" "B.Paste")
			(net "PHY_DPB_TO_SCC_13_DP")
			(options
				(clearance outline)
				(anchor circle)
			)
			(primitives
				(gr_poly
					(pts
						(arc
							(start 0.1524 0.127)
							(mid 0.137521 0.162921)
							(end 0.1016 0.1778)
						)
						(arc
							(start -0.1016 0.1778)
							(mid -0.137521 0.162921)
							(end -0.1524 0.127)
						)
						(arc
							(start -0.1524 -0.127)
							(mid -0.137521 -0.162921)
							(end -0.1016 -0.1778)
						)
						(arc
							(start 0.1016 -0.1778)
							(mid 0.137521 -0.162921)
							(end 0.1524 -0.127)
						)
					)
					(width 0)
					(fill yes)
				)
			)
		)
		(pad "2" smd custom
			(at 0 0.2794 270)
			(size 0.0762 0.0762)
			(layers "B.Cu" "B.Mask" "B.Paste")
			(net "PHY_DPB_TO_SCC_C_13_DP")
			(options
				(clearance outline)
				(anchor circle)
			)
			(primitives
				(gr_poly
					(pts
						(arc
							(start 0.1524 0.127)
							(mid 0.137521 0.162921)
							(end 0.1016 0.1778)
						)
						(arc
							(start -0.1016 0.1778)
							(mid -0.137521 0.162921)
							(end -0.1524 0.127)
						)
						(arc
							(start -0.1524 -0.127)
							(mid -0.137521 -0.162921)
							(end -0.1016 -0.1778)
						)
						(arc
							(start 0.1016 -0.1778)
							(mid 0.137521 -0.162921)
							(end 0.1524 -0.127)
						)
					)
					(width 0)
					(fill yes)
				)
			)
		)
	)
	(footprint ""
		(layer "B.Cu")
		(at 170.914568 -49.71161 90)
		(property "Reference" "C495"
			(at 0 0 90)
			(layer "B.SilkS")
			(hide yes)
			(effects
				(font
					(size 1.27 1.27)
				)
				(justify mirror)
			)
		)
		(property "Value" "SC1KP50V2KX-1GP"
			(at -1.1811 -2.7051 90)
			(unlocked yes)
			(layer "B.Fab")
			(hide yes)
			(effects
				(font
					(size 1.016 1.016)
					(thickness 0.1524)
				)
				(justify mirror)
			)
		)
		(property "Device Type" "C402H22"
			(at -1.1811 -4.2291 90)
			(unlocked yes)
			(layer "B.Fab")
			(hide yes)
			(effects
				(font
					(size 1.016 1.016)
					(thickness 0.1524)
				)
				(justify mirror)
			)
		)
		(duplicate_pad_numbers_are_jumpers no)
		(fp_rect
			(start 0.4318 0.9525)
			(end -0.4318 -0.9525)
			(stroke
				(width 0)
				(type default)
			)
			(fill no)
			(layer "B.CrtYd")
		)
		(fp_rect
			(start 0.4318 0.9525)
			(end -0.4318 -0.9525)
			(stroke
				(width 0)
				(type default)
			)
			(fill no)
			(layer "B.Fab")
		)
		(pad "1" smd custom
			(at 0 -0.4445 270)
			(size 0.1524 0.1524)
			(layers "B.Cu" "B.Mask" "B.Paste")
			(net "P1V8_C")
			(options
				(clearance outline)
				(anchor circle)
			)
			(primitives
				(gr_poly
					(pts
						(arc
							(start 0.3048 0.2032)
							(mid 0.275042 0.275042)
							(end 0.2032 0.3048)
						)
						(arc
							(start -0.2032 0.3048)
							(mid -0.275042 0.275042)
							(end -0.3048 0.2032)
						)
						(arc
							(start -0.3048 -0.2032)
							(mid -0.275042 -0.275042)
							(end -0.2032 -0.3048)
						)
						(arc
							(start 0.2032 -0.3048)
							(mid 0.275042 -0.275042)
							(end 0.3048 -0.2032)
						)
					)
					(width 0)
					(fill yes)
				)
			)
		)
		(pad "2" smd custom
			(at 0 0.4445 270)
			(size 0.1524 0.1524)
			(layers "B.Cu" "B.Mask" "B.Paste")
			(net "GND")
			(options
				(clearance outline)
				(anchor circle)
			)
			(primitives
				(gr_poly
					(pts
						(arc
							(start 0.3048 0.2032)
							(mid 0.275042 0.275042)
							(end 0.2032 0.3048)
						)
						(arc
							(start -0.2032 0.3048)
							(mid -0.275042 0.275042)
							(end -0.3048 0.2032)
						)
						(arc
							(start -0.3048 -0.2032)
							(mid -0.275042 -0.275042)
							(end -0.2032 -0.3048)
						)
						(arc
							(start 0.2032 -0.3048)
							(mid 0.275042 -0.275042)
							(end 0.3048 -0.2032)
						)
					)
					(width 0)
					(fill yes)
				)
			)
		)
	)
	(footprint ""
		(layer "B.Cu")
		(at 116.7003 -64.4779)
		(property "Reference" "C174"
			(at 0 0 0)
			(layer "B.SilkS")
			(hide yes)
			(effects
				(font
					(size 1.27 1.27)
				)
				(justify mirror)
			)
		)
		(property "Value" "SCD1U6D3V1KX-GP"
			(at 2.8321 -1.7399 0)
			(unlocked yes)
			(layer "B.Fab")
			(hide yes)
			(effects
				(font
					(size 1.016 1.016)
					(thickness 0.1524)
				)
				(justify mirror)
			)
		)
		(property "Device Type" "C0201H13"
			(at 2.8321 -3.2639 0)
			(unlocked yes)
			(layer "B.Fab")
			(hide yes)
			(effects
				(font
					(size 1.016 1.016)
					(thickness 0.1524)
				)
				(justify mirror)
			)
		)
		(duplicate_pad_numbers_are_jumpers no)
		(fp_rect
			(start 0.2794 0.6477)
			(end -0.2794 -0.6477)
			(stroke
				(width 0)
				(type default)
			)
			(fill no)
			(layer "B.CrtYd")
		)
		(fp_rect
			(start 0.2794 0.6477)
			(end -0.2794 -0.6477)
			(stroke
				(width 0)
				(type default)
			)
			(fill no)
			(layer "B.Fab")
		)
		(pad "1" smd custom
			(at 0 -0.2794 180)
			(size 0.0762 0.0762)
			(layers "B.Cu" "B.Mask" "B.Paste")
			(net "P0V9")
			(options
				(clearance outline)
				(anchor circle)
			)
			(primitives
				(gr_poly
					(pts
						(arc
							(start 0.1524 0.127)
							(mid 0.137521 0.162921)
							(end 0.1016 0.1778)
						)
						(arc
							(start -0.1016 0.1778)
							(mid -0.137521 0.162921)
							(end -0.1524 0.127)
						)
						(arc
							(start -0.1524 -0.127)
							(mid -0.137521 -0.162921)
							(end -0.1016 -0.1778)
						)
						(arc
							(start 0.1016 -0.1778)
							(mid 0.137521 -0.162921)
							(end 0.1524 -0.127)
						)
					)
					(width 0)
					(fill yes)
				)
			)
		)
		(pad "2" smd custom
			(at 0 0.2794 180)
			(size 0.0762 0.0762)
			(layers "B.Cu" "B.Mask" "B.Paste")
			(net "GND")
			(options
				(clearance outline)
				(anchor circle)
			)
			(primitives
				(gr_poly
					(pts
						(arc
							(start 0.1524 0.127)
							(mid 0.137521 0.162921)
							(end 0.1016 0.1778)
						)
						(arc
							(start -0.1016 0.1778)
							(mid -0.137521 0.162921)
							(end -0.1524 0.127)
						)
						(arc
							(start -0.1524 -0.127)
							(mid -0.137521 -0.162921)
							(end -0.1016 -0.1778)
						)
						(arc
							(start 0.1016 -0.1778)
							(mid 0.137521 -0.162921)
							(end 0.1524 -0.127)
						)
					)
					(width 0)
					(fill yes)
				)
			)
		)
	)
	(footprint ""
		(layer "B.Cu")
		(at 133.223 -85.217)
		(property "Reference" "TP16"
			(at 0 0 0)
			(layer "B.SilkS")
			(hide yes)
			(effects
				(font
					(size 1.27 1.27)
				)
				(justify mirror)
			)
		)
		(property "Value" "TPAD28-2-GP"
			(at 0.0127 -1.6637 0)
			(unlocked yes)
			(layer "B.Fab")
			(hide yes)
			(effects
				(font
					(size 1.016 1.016)
					(thickness 0.1524)
				)
				(justify mirror)
			)
		)
		(property "Device Type" "TPAD28"
			(at 0.0127 -3.1877 0)
			(unlocked yes)
			(layer "B.Fab")
			(hide yes)
			(effects
				(font
					(size 1.016 1.016)
					(thickness 0.1524)
				)
				(justify mirror)
			)
		)
		(duplicate_pad_numbers_are_jumpers no)
		(fp_poly
			(pts
				(arc
					(start 0.3556 0)
					(mid -0.3556 0)
					(end 0.3556 0)
				)
			)
			(stroke
				(width 0)
				(type default)
			)
			(fill no)
			(layer "B.CrtYd")
		)
		(fp_poly
			(pts
				(arc
					(start 0.6096 0)
					(mid -0.6096 0)
					(end 0.6096 0)
				)
			)
			(stroke
				(width 0)
				(type default)
			)
			(fill no)
			(layer "B.Fab")
		)
		(pad "1" smd circle
			(at 0 0 180)
			(size 0.7112 0.7112)
			(layers "B.Cu" "B.Mask" "B.Paste")
			(net "EXP_I2C_SCL11")
		)
	)
	(footprint ""
		(layer "B.Cu")
		(at 183.477408 -33.53435 -90)
		(property "Reference" "C472"
			(at 0 0 90)
			(layer "B.SilkS")
			(hide yes)
			(effects
				(font
					(size 1.27 1.27)
				)
				(justify mirror)
			)
		)
		(property "Value" "SCD1U6D3V1KX-GP"
			(at 2.8321 -1.7399 270)
			(unlocked yes)
			(layer "B.Fab")
			(hide yes)
			(effects
				(font
					(size 1.016 1.016)
					(thickness 0.1524)
				)
				(justify mirror)
			)
		)
		(property "Device Type" "C0201H13"
			(at 2.8321 -3.2639 270)
			(unlocked yes)
			(layer "B.Fab")
			(hide yes)
			(effects
				(font
					(size 1.016 1.016)
					(thickness 0.1524)
				)
				(justify mirror)
			)
		)
		(duplicate_pad_numbers_are_jumpers no)
		(fp_rect
			(start 0.2794 0.6477)
			(end -0.2794 -0.6477)
			(stroke
				(width 0)
				(type default)
			)
			(fill no)
			(layer "B.CrtYd")
		)
		(fp_rect
			(start 0.2794 0.6477)
			(end -0.2794 -0.6477)
			(stroke
				(width 0)
				(type default)
			)
			(fill no)
			(layer "B.Fab")
		)
		(pad "1" smd custom
			(at 0 -0.2794 90)
			(size 0.0762 0.0762)
			(layers "B.Cu" "B.Mask" "B.Paste")
			(net "P1V8_C")
			(options
				(clearance outline)
				(anchor circle)
			)
			(primitives
				(gr_poly
					(pts
						(arc
							(start 0.1524 0.127)
							(mid 0.137521 0.162921)
							(end 0.1016 0.1778)
						)
						(arc
							(start -0.1016 0.1778)
							(mid -0.137521 0.162921)
							(end -0.1524 0.127)
						)
						(arc
							(start -0.1524 -0.127)
							(mid -0.137521 -0.162921)
							(end -0.1016 -0.1778)
						)
						(arc
							(start 0.1016 -0.1778)
							(mid 0.137521 -0.162921)
							(end 0.1524 -0.127)
						)
					)
					(width 0)
					(fill yes)
				)
			)
		)
		(pad "2" smd custom
			(at 0 0.2794 90)
			(size 0.0762 0.0762)
			(layers "B.Cu" "B.Mask" "B.Paste")
			(net "GND")
			(options
				(clearance outline)
				(anchor circle)
			)
			(primitives
				(gr_poly
					(pts
						(arc
							(start 0.1524 0.127)
							(mid 0.137521 0.162921)
							(end 0.1016 0.1778)
						)
						(arc
							(start -0.1016 0.1778)
							(mid -0.137521 0.162921)
							(end -0.1524 0.127)
						)
						(arc
							(start -0.1524 -0.127)
							(mid -0.137521 -0.162921)
							(end -0.1016 -0.1778)
						)
						(arc
							(start 0.1016 -0.1778)
							(mid 0.137521 -0.162921)
							(end 0.1524 -0.127)
						)
					)
					(width 0)
					(fill yes)
				)
			)
		)
	)
	(footprint ""
		(layer "B.Cu")
		(at 106.3498 -44.2214 180)
		(property "Reference" "C75"
			(at 0 0 0)
			(layer "B.SilkS")
			(hide yes)
			(effects
				(font
					(size 1.27 1.27)
				)
				(justify mirror)
			)
		)
		(property "Value" "SCD01U16V1KX-GP"
			(at 2.8321 -1.7399 180)
			(unlocked yes)
			(layer "B.Fab")
			(hide yes)
			(effects
				(font
					(size 1.016 1.016)
					(thickness 0.1524)
				)
				(justify mirror)
			)
		)
		(property "Device Type" "C0201H13"
			(at 2.8321 -3.2639 180)
			(unlocked yes)
			(layer "B.Fab")
			(hide yes)
			(effects
				(font
					(size 1.016 1.016)
					(thickness 0.1524)
				)
				(justify mirror)
			)
		)
		(duplicate_pad_numbers_are_jumpers no)
		(fp_rect
			(start 0.2794 0.6477)
			(end -0.2794 -0.6477)
			(stroke
				(width 0)
				(type default)
			)
			(fill no)
			(layer "B.CrtYd")
		)
		(fp_rect
			(start 0.2794 0.6477)
			(end -0.2794 -0.6477)
			(stroke
				(width 0)
				(type default)
			)
			(fill no)
			(layer "B.Fab")
		)
		(pad "1" smd custom
			(at 0 -0.2794)
			(size 0.0762 0.0762)
			(layers "B.Cu" "B.Mask" "B.Paste")
			(net "PHY_DPB_TO_SCC_22_DP")
			(options
				(clearance outline)
				(anchor circle)
			)
			(primitives
				(gr_poly
					(pts
						(arc
							(start 0.1524 0.127)
							(mid 0.137521 0.162921)
							(end 0.1016 0.1778)
						)
						(arc
							(start -0.1016 0.1778)
							(mid -0.137521 0.162921)
							(end -0.1524 0.127)
						)
						(arc
							(start -0.1524 -0.127)
							(mid -0.137521 -0.162921)
							(end -0.1016 -0.1778)
						)
						(arc
							(start 0.1016 -0.1778)
							(mid 0.137521 -0.162921)
							(end 0.1524 -0.127)
						)
					)
					(width 0)
					(fill yes)
				)
			)
		)
		(pad "2" smd custom
			(at 0 0.2794)
			(size 0.0762 0.0762)
			(layers "B.Cu" "B.Mask" "B.Paste")
			(net "PHY_DPB_TO_SCC_C_22_DP")
			(options
				(clearance outline)
				(anchor circle)
			)
			(primitives
				(gr_poly
					(pts
						(arc
							(start 0.1524 0.127)
							(mid 0.137521 0.162921)
							(end 0.1016 0.1778)
						)
						(arc
							(start -0.1016 0.1778)
							(mid -0.137521 0.162921)
							(end -0.1524 0.127)
						)
						(arc
							(start -0.1524 -0.127)
							(mid -0.137521 -0.162921)
							(end -0.1016 -0.1778)
						)
						(arc
							(start 0.1016 -0.1778)
							(mid 0.137521 -0.162921)
							(end 0.1524 -0.127)
						)
					)
					(width 0)
					(fill yes)
				)
			)
		)
	)
	(footprint ""
		(layer "B.Cu")
		(at 175.7045 -60.063126 -90)
		(property "Reference" "R402"
			(at 0 0 90)
			(layer "B.SilkS")
			(hide yes)
			(effects
				(font
					(size 1.27 1.27)
				)
				(justify mirror)
			)
		)
		(property "Value" "0R2J-2-GP"
			(at -0.064008 -3.993896 270)
			(unlocked yes)
			(layer "B.Fab")
			(hide yes)
			(effects
				(font
					(size 1.016 1.016)
					(thickness 0.1524)
				)
				(justify mirror)
			)
		)
		(property "Device Type" "R402H16"
			(at -0.064008 -5.517896 270)
			(unlocked yes)
			(layer "B.Fab")
			(hide yes)
			(effects
				(font
					(size 1.016 1.016)
					(thickness 0.1524)
				)
				(justify mirror)
			)
		)
		(duplicate_pad_numbers_are_jumpers no)
		(fp_line
			(start -0.508 -0.9398)
			(end 0.508 -0.9398)
			(stroke
				(width 0.1524)
				(type default)
			)
			(layer "B.SilkS")
		)
		(fp_line
			(start 0.508 -0.9398)
			(end 0.508 0.9398)
			(stroke
				(width 0.1524)
				(type default)
			)
			(layer "B.SilkS")
		)
		(fp_rect
			(start 0.508 0.9398)
			(end -0.508 -0.9398)
			(stroke
				(width 0)
				(type default)
			)
			(fill no)
			(layer "B.CrtYd")
		)
		(fp_rect
			(start 0.508 0.9398)
			(end -0.508 -0.9398)
			(stroke
				(width 0)
				(type default)
			)
			(fill no)
			(layer "B.Fab")
		)
		(pad "1" smd custom
			(at 0 -0.4445 90)
			(size 0.1397 0.1397)
			(layers "B.Cu" "B.Mask" "B.Paste")
			(net "SCC_FULL_PGOOD")
			(options
				(clearance outline)
				(anchor circle)
			)
			(primitives
				(gr_poly
					(pts
						(arc
							(start -0.1778 0.2794)
							(mid -0.249642 0.249642)
							(end -0.2794 0.1778)
						)
						(arc
							(start -0.2794 -0.1778)
							(mid -0.249642 -0.249642)
							(end -0.1778 -0.2794)
						)
						(arc
							(start 0.1778 -0.2794)
							(mid 0.249642 -0.249642)
							(end 0.2794 -0.1778)
						)
						(arc
							(start 0.2794 0.1778)
							(mid 0.249642 0.249642)
							(end 0.1778 0.2794)
						)
					)
					(width 0)
					(fill yes)
				)
			)
		)
		(pad "2" smd custom
			(at 0 0.4445 90)
			(size 0.1397 0.1397)
			(layers "B.Cu" "B.Mask" "B.Paste")
			(net "SCC_FULL_PGOOD_SENSE")
			(options
				(clearance outline)
				(anchor circle)
			)
			(primitives
				(gr_poly
					(pts
						(arc
							(start -0.1778 0.2794)
							(mid -0.249642 0.249642)
							(end -0.2794 0.1778)
						)
						(arc
							(start -0.2794 -0.1778)
							(mid -0.249642 -0.249642)
							(end -0.1778 -0.2794)
						)
						(arc
							(start 0.1778 -0.2794)
							(mid 0.249642 -0.249642)
							(end 0.2794 -0.1778)
						)
						(arc
							(start 0.2794 0.1778)
							(mid 0.249642 0.249642)
							(end 0.1778 0.2794)
						)
					)
					(width 0)
					(fill yes)
				)
			)
		)
	)
	(footprint ""
		(layer "B.Cu")
		(at 109.50067 -78.48854)
		(property "Reference" "TP42"
			(at 0 0 0)
			(layer "B.SilkS")
			(hide yes)
			(effects
				(font
					(size 1.27 1.27)
				)
				(justify mirror)
			)
		)
		(property "Value" "TPAD28-2-GP"
			(at 0.0127 -1.6637 0)
			(unlocked yes)
			(layer "B.Fab")
			(hide yes)
			(effects
				(font
					(size 1.016 1.016)
					(thickness 0.1524)
				)
				(justify mirror)
			)
		)
		(property "Device Type" "TPAD28"
			(at 0.0127 -3.1877 0)
			(unlocked yes)
			(layer "B.Fab")
			(hide yes)
			(effects
				(font
					(size 1.016 1.016)
					(thickness 0.1524)
				)
				(justify mirror)
			)
		)
		(duplicate_pad_numbers_are_jumpers no)
		(fp_poly
			(pts
				(arc
					(start 0.3556 0)
					(mid -0.3556 0)
					(end 0.3556 0)
				)
			)
			(stroke
				(width 0)
				(type default)
			)
			(fill no)
			(layer "B.CrtYd")
		)
		(fp_poly
			(pts
				(arc
					(start 0.6096 0)
					(mid -0.6096 0)
					(end 0.6096 0)
				)
			)
			(stroke
				(width 0)
				(type default)
			)
			(fill no)
			(layer "B.Fab")
		)
		(pad "1" smd circle
			(at 0 0 180)
			(size 0.7112 0.7112)
			(layers "B.Cu" "B.Mask" "B.Paste")
			(net "LSI_PROCMON")
		)
	)
	(footprint ""
		(layer "B.Cu")
		(at 109.499908 -76.499974)
		(property "Reference" "TP38"
			(at 0 0 0)
			(layer "B.SilkS")
			(hide yes)
			(effects
				(font
					(size 1.27 1.27)
				)
				(justify mirror)
			)
		)
		(property "Value" "TPAD28-2-GP"
			(at 0.0127 -1.6637 0)
			(unlocked yes)
			(layer "B.Fab")
			(hide yes)
			(effects
				(font
					(size 1.016 1.016)
					(thickness 0.1524)
				)
				(justify mirror)
			)
		)
		(property "Device Type" "TPAD28"
			(at 0.0127 -3.1877 0)
			(unlocked yes)
			(layer "B.Fab")
			(hide yes)
			(effects
				(font
					(size 1.016 1.016)
					(thickness 0.1524)
				)
				(justify mirror)
			)
		)
		(duplicate_pad_numbers_are_jumpers no)
		(fp_poly
			(pts
				(arc
					(start 0.3556 0)
					(mid -0.3556 0)
					(end 0.3556 0)
				)
			)
			(stroke
				(width 0)
				(type default)
			)
			(fill no)
			(layer "B.CrtYd")
		)
		(fp_poly
			(pts
				(arc
					(start 0.6096 0)
					(mid -0.6096 0)
					(end 0.6096 0)
				)
			)
			(stroke
				(width 0)
				(type default)
			)
			(fill no)
			(layer "B.Fab")
		)
		(pad "1" smd circle
			(at 0 0 180)
			(size 0.7112 0.7112)
			(layers "B.Cu" "B.Mask" "B.Paste")
			(net "JTAG_EXP_TDI")
		)
	)
	(footprint ""
		(layer "B.Cu")
		(at 122.4788 -61.4934 -90)
		(property "Reference" "C269"
			(at 0 0 90)
			(layer "B.SilkS")
			(hide yes)
			(effects
				(font
					(size 1.27 1.27)
				)
				(justify mirror)
			)
		)
		(property "Value" "SCD1U6D3V1KX-GP"
			(at 2.8321 -1.7399 270)
			(unlocked yes)
			(layer "B.Fab")
			(hide yes)
			(effects
				(font
					(size 1.016 1.016)
					(thickness 0.1524)
				)
				(justify mirror)
			)
		)
		(property "Device Type" "C0201H13"
			(at 2.8321 -3.2639 270)
			(unlocked yes)
			(layer "B.Fab")
			(hide yes)
			(effects
				(font
					(size 1.016 1.016)
					(thickness 0.1524)
				)
				(justify mirror)
			)
		)
		(duplicate_pad_numbers_are_jumpers no)
		(fp_rect
			(start 0.2794 0.6477)
			(end -0.2794 -0.6477)
			(stroke
				(width 0)
				(type default)
			)
			(fill no)
			(layer "B.CrtYd")
		)
		(fp_rect
			(start 0.2794 0.6477)
			(end -0.2794 -0.6477)
			(stroke
				(width 0)
				(type default)
			)
			(fill no)
			(layer "B.Fab")
		)
		(pad "1" smd custom
			(at 0 -0.2794 90)
			(size 0.0762 0.0762)
			(layers "B.Cu" "B.Mask" "B.Paste")
			(net "GB_VDDA")
			(options
				(clearance outline)
				(anchor circle)
			)
			(primitives
				(gr_poly
					(pts
						(arc
							(start 0.1524 0.127)
							(mid 0.137521 0.162921)
							(end 0.1016 0.1778)
						)
						(arc
							(start -0.1016 0.1778)
							(mid -0.137521 0.162921)
							(end -0.1524 0.127)
						)
						(arc
							(start -0.1524 -0.127)
							(mid -0.137521 -0.162921)
							(end -0.1016 -0.1778)
						)
						(arc
							(start 0.1016 -0.1778)
							(mid 0.137521 -0.162921)
							(end 0.1524 -0.127)
						)
					)
					(width 0)
					(fill yes)
				)
			)
		)
		(pad "2" smd custom
			(at 0 0.2794 90)
			(size 0.0762 0.0762)
			(layers "B.Cu" "B.Mask" "B.Paste")
			(net "GND")
			(options
				(clearance outline)
				(anchor circle)
			)
			(primitives
				(gr_poly
					(pts
						(arc
							(start 0.1524 0.127)
							(mid 0.137521 0.162921)
							(end 0.1016 0.1778)
						)
						(arc
							(start -0.1016 0.1778)
							(mid -0.137521 0.162921)
							(end -0.1524 0.127)
						)
						(arc
							(start -0.1524 -0.127)
							(mid -0.137521 -0.162921)
							(end -0.1016 -0.1778)
						)
						(arc
							(start 0.1016 -0.1778)
							(mid 0.137521 -0.162921)
							(end 0.1524 -0.127)
						)
					)
					(width 0)
					(fill yes)
				)
			)
		)
	)
	(footprint ""
		(layer "B.Cu")
		(at 167.7543 -34.0614)
		(property "Reference" "C404"
			(at 0 0 0)
			(layer "B.SilkS")
			(hide yes)
			(effects
				(font
					(size 1.27 1.27)
				)
				(justify mirror)
			)
		)
		(property "Value" "SCD1U16V2KX-3GP"
			(at -1.1811 -2.7051 0)
			(unlocked yes)
			(layer "B.Fab")
			(hide yes)
			(effects
				(font
					(size 1.016 1.016)
					(thickness 0.1524)
				)
				(justify mirror)
			)
		)
		(property "Device Type" "C402H22"
			(at -1.1811 -4.2291 0)
			(unlocked yes)
			(layer "B.Fab")
			(hide yes)
			(effects
				(font
					(size 1.016 1.016)
					(thickness 0.1524)
				)
				(justify mirror)
			)
		)
		(duplicate_pad_numbers_are_jumpers no)
		(fp_rect
			(start 0.4318 0.9525)
			(end -0.4318 -0.9525)
			(stroke
				(width 0)
				(type default)
			)
			(fill no)
			(layer "B.CrtYd")
		)
		(fp_rect
			(start 0.4318 0.9525)
			(end -0.4318 -0.9525)
			(stroke
				(width 0)
				(type default)
			)
			(fill no)
			(layer "B.Fab")
		)
		(pad "1" smd custom
			(at 0 -0.4445 180)
			(size 0.1524 0.1524)
			(layers "B.Cu" "B.Mask" "B.Paste")
			(net "SAS0_AVDD")
			(options
				(clearance outline)
				(anchor circle)
			)
			(primitives
				(gr_poly
					(pts
						(arc
							(start 0.3048 0.2032)
							(mid 0.275042 0.275042)
							(end 0.2032 0.3048)
						)
						(arc
							(start -0.2032 0.3048)
							(mid -0.275042 0.275042)
							(end -0.3048 0.2032)
						)
						(arc
							(start -0.3048 -0.2032)
							(mid -0.275042 -0.275042)
							(end -0.2032 -0.3048)
						)
						(arc
							(start 0.2032 -0.3048)
							(mid 0.275042 -0.275042)
							(end 0.3048 -0.2032)
						)
					)
					(width 0)
					(fill yes)
				)
			)
		)
		(pad "2" smd custom
			(at 0 0.4445 180)
			(size 0.1524 0.1524)
			(layers "B.Cu" "B.Mask" "B.Paste")
			(net "GND")
			(options
				(clearance outline)
				(anchor circle)
			)
			(primitives
				(gr_poly
					(pts
						(arc
							(start 0.3048 0.2032)
							(mid 0.275042 0.275042)
							(end 0.2032 0.3048)
						)
						(arc
							(start -0.2032 0.3048)
							(mid -0.275042 0.275042)
							(end -0.3048 0.2032)
						)
						(arc
							(start -0.3048 -0.2032)
							(mid -0.275042 -0.275042)
							(end -0.2032 -0.3048)
						)
						(arc
							(start 0.2032 -0.3048)
							(mid 0.275042 -0.275042)
							(end 0.3048 -0.2032)
						)
					)
					(width 0)
					(fill yes)
				)
			)
		)
	)
	(footprint ""
		(layer "B.Cu")
		(at 124.7267 -72.5043 90)
		(property "Reference" "C582"
			(at 0 0 90)
			(layer "B.SilkS")
			(hide yes)
			(effects
				(font
					(size 1.27 1.27)
				)
				(justify mirror)
			)
		)
		(property "Value" "SCD1U6D3V1KX-GP"
			(at 2.8321 -1.7399 90)
			(unlocked yes)
			(layer "B.Fab")
			(hide yes)
			(effects
				(font
					(size 1.016 1.016)
					(thickness 0.1524)
				)
				(justify mirror)
			)
		)
		(property "Device Type" "C0201H13"
			(at 2.8321 -3.2639 90)
			(unlocked yes)
			(layer "B.Fab")
			(hide yes)
			(effects
				(font
					(size 1.016 1.016)
					(thickness 0.1524)
				)
				(justify mirror)
			)
		)
		(duplicate_pad_numbers_are_jumpers no)
		(fp_rect
			(start 0.2794 0.6477)
			(end -0.2794 -0.6477)
			(stroke
				(width 0)
				(type default)
			)
			(fill no)
			(layer "B.CrtYd")
		)
		(fp_rect
			(start 0.2794 0.6477)
			(end -0.2794 -0.6477)
			(stroke
				(width 0)
				(type default)
			)
			(fill no)
			(layer "B.Fab")
		)
		(pad "1" smd custom
			(at 0 -0.2794 270)
			(size 0.0762 0.0762)
			(layers "B.Cu" "B.Mask" "B.Paste")
			(net "GB_VDDA")
			(options
				(clearance outline)
				(anchor circle)
			)
			(primitives
				(gr_poly
					(pts
						(arc
							(start 0.1524 0.127)
							(mid 0.137521 0.162921)
							(end 0.1016 0.1778)
						)
						(arc
							(start -0.1016 0.1778)
							(mid -0.137521 0.162921)
							(end -0.1524 0.127)
						)
						(arc
							(start -0.1524 -0.127)
							(mid -0.137521 -0.162921)
							(end -0.1016 -0.1778)
						)
						(arc
							(start 0.1016 -0.1778)
							(mid 0.137521 -0.162921)
							(end 0.1524 -0.127)
						)
					)
					(width 0)
					(fill yes)
				)
			)
		)
		(pad "2" smd custom
			(at 0 0.2794 270)
			(size 0.0762 0.0762)
			(layers "B.Cu" "B.Mask" "B.Paste")
			(net "GND")
			(options
				(clearance outline)
				(anchor circle)
			)
			(primitives
				(gr_poly
					(pts
						(arc
							(start 0.1524 0.127)
							(mid 0.137521 0.162921)
							(end 0.1016 0.1778)
						)
						(arc
							(start -0.1016 0.1778)
							(mid -0.137521 0.162921)
							(end -0.1524 0.127)
						)
						(arc
							(start -0.1524 -0.127)
							(mid -0.137521 -0.162921)
							(end -0.1016 -0.1778)
						)
						(arc
							(start 0.1016 -0.1778)
							(mid 0.137521 -0.162921)
							(end 0.1524 -0.127)
						)
					)
					(width 0)
					(fill yes)
				)
			)
		)
	)
	(footprint ""
		(layer "B.Cu")
		(at 114.5794 -80.4672 180)
		(property "Reference" "C145"
			(at 0 0 0)
			(layer "B.SilkS")
			(hide yes)
			(effects
				(font
					(size 1.27 1.27)
				)
				(justify mirror)
			)
		)
		(property "Value" "SCD1U6D3V1KX-GP"
			(at 2.8321 -1.7399 180)
			(unlocked yes)
			(layer "B.Fab")
			(hide yes)
			(effects
				(font
					(size 1.016 1.016)
					(thickness 0.1524)
				)
				(justify mirror)
			)
		)
		(property "Device Type" "C0201H13"
			(at 2.8321 -3.2639 180)
			(unlocked yes)
			(layer "B.Fab")
			(hide yes)
			(effects
				(font
					(size 1.016 1.016)
					(thickness 0.1524)
				)
				(justify mirror)
			)
		)
		(duplicate_pad_numbers_are_jumpers no)
		(fp_rect
			(start 0.2794 0.6477)
			(end -0.2794 -0.6477)
			(stroke
				(width 0)
				(type default)
			)
			(fill no)
			(layer "B.CrtYd")
		)
		(fp_rect
			(start 0.2794 0.6477)
			(end -0.2794 -0.6477)
			(stroke
				(width 0)
				(type default)
			)
			(fill no)
			(layer "B.Fab")
		)
		(pad "1" smd custom
			(at 0 -0.2794)
			(size 0.0762 0.0762)
			(layers "B.Cu" "B.Mask" "B.Paste")
			(net "P1V8_E")
			(options
				(clearance outline)
				(anchor circle)
			)
			(primitives
				(gr_poly
					(pts
						(arc
							(start 0.1524 0.127)
							(mid 0.137521 0.162921)
							(end 0.1016 0.1778)
						)
						(arc
							(start -0.1016 0.1778)
							(mid -0.137521 0.162921)
							(end -0.1524 0.127)
						)
						(arc
							(start -0.1524 -0.127)
							(mid -0.137521 -0.162921)
							(end -0.1016 -0.1778)
						)
						(arc
							(start 0.1016 -0.1778)
							(mid 0.137521 -0.162921)
							(end 0.1524 -0.127)
						)
					)
					(width 0)
					(fill yes)
				)
			)
		)
		(pad "2" smd custom
			(at 0 0.2794)
			(size 0.0762 0.0762)
			(layers "B.Cu" "B.Mask" "B.Paste")
			(net "GND")
			(options
				(clearance outline)
				(anchor circle)
			)
			(primitives
				(gr_poly
					(pts
						(arc
							(start 0.1524 0.127)
							(mid 0.137521 0.162921)
							(end 0.1016 0.1778)
						)
						(arc
							(start -0.1016 0.1778)
							(mid -0.137521 0.162921)
							(end -0.1524 0.127)
						)
						(arc
							(start -0.1524 -0.127)
							(mid -0.137521 -0.162921)
							(end -0.1016 -0.1778)
						)
						(arc
							(start 0.1016 -0.1778)
							(mid 0.137521 -0.162921)
							(end 0.1524 -0.127)
						)
					)
					(width 0)
					(fill yes)
				)
			)
		)
	)
	(footprint ""
		(layer "B.Cu")
		(at 121.9454 -93.345 90)
		(property "Reference" "R559"
			(at 0 0 90)
			(layer "B.SilkS")
			(hide yes)
			(effects
				(font
					(size 1.27 1.27)
				)
				(justify mirror)
			)
		)
		(property "Value" "10KR2F-2-GP"
			(at -0.064008 -3.993896 90)
			(unlocked yes)
			(layer "B.Fab")
			(hide yes)
			(effects
				(font
					(size 1.016 1.016)
					(thickness 0.1524)
				)
				(justify mirror)
			)
		)
		(property "Device Type" "R402H16"
			(at -0.064008 -5.517896 90)
			(unlocked yes)
			(layer "B.Fab")
			(hide yes)
			(effects
				(font
					(size 1.016 1.016)
					(thickness 0.1524)
				)
				(justify mirror)
			)
		)
		(duplicate_pad_numbers_are_jumpers no)
		(fp_line
			(start 0.508 -0.9398)
			(end 0.508 0.9398)
			(stroke
				(width 0.1524)
				(type default)
			)
			(layer "B.SilkS")
		)
		(fp_line
			(start -0.508 -0.9398)
			(end 0.508 -0.9398)
			(stroke
				(width 0.1524)
				(type default)
			)
			(layer "B.SilkS")
		)
		(fp_rect
			(start 0.508 0.9398)
			(end -0.508 -0.9398)
			(stroke
				(width 0)
				(type default)
			)
			(fill no)
			(layer "B.CrtYd")
		)
		(fp_rect
			(start 0.508 0.9398)
			(end -0.508 -0.9398)
			(stroke
				(width 0)
				(type default)
			)
			(fill no)
			(layer "B.Fab")
		)
		(pad "1" smd custom
			(at 0 -0.4445 270)
			(size 0.1397 0.1397)
			(layers "B.Cu" "B.Mask" "B.Paste")
			(net "SCC_RMT_HEARTBEAT_LS")
			(options
				(clearance outline)
				(anchor circle)
			)
			(primitives
				(gr_poly
					(pts
						(arc
							(start -0.1778 0.2794)
							(mid -0.249642 0.249642)
							(end -0.2794 0.1778)
						)
						(arc
							(start -0.2794 -0.1778)
							(mid -0.249642 -0.249642)
							(end -0.1778 -0.2794)
						)
						(arc
							(start 0.1778 -0.2794)
							(mid 0.249642 -0.249642)
							(end 0.2794 -0.1778)
						)
						(arc
							(start 0.2794 0.1778)
							(mid 0.249642 0.249642)
							(end 0.1778 0.2794)
						)
					)
					(width 0)
					(fill yes)
				)
			)
		)
		(pad "2" smd custom
			(at 0 0.4445 270)
			(size 0.1397 0.1397)
			(layers "B.Cu" "B.Mask" "B.Paste")
			(net "GND")
			(options
				(clearance outline)
				(anchor circle)
			)
			(primitives
				(gr_poly
					(pts
						(arc
							(start -0.1778 0.2794)
							(mid -0.249642 0.249642)
							(end -0.2794 0.1778)
						)
						(arc
							(start -0.2794 -0.1778)
							(mid -0.249642 -0.249642)
							(end -0.1778 -0.2794)
						)
						(arc
							(start 0.1778 -0.2794)
							(mid 0.249642 -0.249642)
							(end 0.2794 -0.1778)
						)
						(arc
							(start 0.2794 0.1778)
							(mid 0.249642 0.249642)
							(end 0.1778 0.2794)
						)
					)
					(width 0)
					(fill yes)
				)
			)
		)
	)
	(footprint ""
		(layer "B.Cu")
		(at 120.523 -76.454 180)
		(property "Reference" "C144"
			(at 0 0 0)
			(layer "B.SilkS")
			(hide yes)
			(effects
				(font
					(size 1.27 1.27)
				)
				(justify mirror)
			)
		)
		(property "Value" "SCD1U6D3V1KX-GP"
			(at 2.8321 -1.7399 180)
			(unlocked yes)
			(layer "B.Fab")
			(hide yes)
			(effects
				(font
					(size 1.016 1.016)
					(thickness 0.1524)
				)
				(justify mirror)
			)
		)
		(property "Device Type" "C0201H13"
			(at 2.8321 -3.2639 180)
			(unlocked yes)
			(layer "B.Fab")
			(hide yes)
			(effects
				(font
					(size 1.016 1.016)
					(thickness 0.1524)
				)
				(justify mirror)
			)
		)
		(duplicate_pad_numbers_are_jumpers no)
		(fp_rect
			(start 0.2794 0.6477)
			(end -0.2794 -0.6477)
			(stroke
				(width 0)
				(type default)
			)
			(fill no)
			(layer "B.CrtYd")
		)
		(fp_rect
			(start 0.2794 0.6477)
			(end -0.2794 -0.6477)
			(stroke
				(width 0)
				(type default)
			)
			(fill no)
			(layer "B.Fab")
		)
		(pad "1" smd custom
			(at 0 -0.2794)
			(size 0.0762 0.0762)
			(layers "B.Cu" "B.Mask" "B.Paste")
			(net "P1V8_E")
			(options
				(clearance outline)
				(anchor circle)
			)
			(primitives
				(gr_poly
					(pts
						(arc
							(start 0.1524 0.127)
							(mid 0.137521 0.162921)
							(end 0.1016 0.1778)
						)
						(arc
							(start -0.1016 0.1778)
							(mid -0.137521 0.162921)
							(end -0.1524 0.127)
						)
						(arc
							(start -0.1524 -0.127)
							(mid -0.137521 -0.162921)
							(end -0.1016 -0.1778)
						)
						(arc
							(start 0.1016 -0.1778)
							(mid 0.137521 -0.162921)
							(end 0.1524 -0.127)
						)
					)
					(width 0)
					(fill yes)
				)
			)
		)
		(pad "2" smd custom
			(at 0 0.2794)
			(size 0.0762 0.0762)
			(layers "B.Cu" "B.Mask" "B.Paste")
			(net "GND")
			(options
				(clearance outline)
				(anchor circle)
			)
			(primitives
				(gr_poly
					(pts
						(arc
							(start 0.1524 0.127)
							(mid 0.137521 0.162921)
							(end 0.1016 0.1778)
						)
						(arc
							(start -0.1016 0.1778)
							(mid -0.137521 0.162921)
							(end -0.1524 0.127)
						)
						(arc
							(start -0.1524 -0.127)
							(mid -0.137521 -0.162921)
							(end -0.1016 -0.1778)
						)
						(arc
							(start 0.1016 -0.1778)
							(mid 0.137521 -0.162921)
							(end 0.1524 -0.127)
						)
					)
					(width 0)
					(fill yes)
				)
			)
		)
	)
	(footprint ""
		(layer "B.Cu")
		(at 179.524152 -36.913058 90)
		(property "Reference" "C451"
			(at 0 0 90)
			(layer "B.SilkS")
			(hide yes)
			(effects
				(font
					(size 1.27 1.27)
				)
				(justify mirror)
			)
		)
		(property "Value" "SC1KP50V2KX-1GP"
			(at -1.1811 -2.7051 90)
			(unlocked yes)
			(layer "B.Fab")
			(hide yes)
			(effects
				(font
					(size 1.016 1.016)
					(thickness 0.1524)
				)
				(justify mirror)
			)
		)
		(property "Device Type" "C402H22"
			(at -1.1811 -4.2291 90)
			(unlocked yes)
			(layer "B.Fab")
			(hide yes)
			(effects
				(font
					(size 1.016 1.016)
					(thickness 0.1524)
				)
				(justify mirror)
			)
		)
		(duplicate_pad_numbers_are_jumpers no)
		(fp_rect
			(start 0.4318 0.9525)
			(end -0.4318 -0.9525)
			(stroke
				(width 0)
				(type default)
			)
			(fill no)
			(layer "B.CrtYd")
		)
		(fp_rect
			(start 0.4318 0.9525)
			(end -0.4318 -0.9525)
			(stroke
				(width 0)
				(type default)
			)
			(fill no)
			(layer "B.Fab")
		)
		(pad "1" smd custom
			(at 0 -0.4445 270)
			(size 0.1524 0.1524)
			(layers "B.Cu" "B.Mask" "B.Paste")
			(net "P0V975")
			(options
				(clearance outline)
				(anchor circle)
			)
			(primitives
				(gr_poly
					(pts
						(arc
							(start 0.3048 0.2032)
							(mid 0.275042 0.275042)
							(end 0.2032 0.3048)
						)
						(arc
							(start -0.2032 0.3048)
							(mid -0.275042 0.275042)
							(end -0.3048 0.2032)
						)
						(arc
							(start -0.3048 -0.2032)
							(mid -0.275042 -0.275042)
							(end -0.2032 -0.3048)
						)
						(arc
							(start 0.2032 -0.3048)
							(mid 0.275042 -0.275042)
							(end 0.3048 -0.2032)
						)
					)
					(width 0)
					(fill yes)
				)
			)
		)
		(pad "2" smd custom
			(at 0 0.4445 270)
			(size 0.1524 0.1524)
			(layers "B.Cu" "B.Mask" "B.Paste")
			(net "GND")
			(options
				(clearance outline)
				(anchor circle)
			)
			(primitives
				(gr_poly
					(pts
						(arc
							(start 0.3048 0.2032)
							(mid 0.275042 0.275042)
							(end 0.2032 0.3048)
						)
						(arc
							(start -0.2032 0.3048)
							(mid -0.275042 0.275042)
							(end -0.3048 0.2032)
						)
						(arc
							(start -0.3048 -0.2032)
							(mid -0.275042 -0.275042)
							(end -0.2032 -0.3048)
						)
						(arc
							(start 0.2032 -0.3048)
							(mid 0.275042 -0.275042)
							(end 0.3048 -0.2032)
						)
					)
					(width 0)
					(fill yes)
				)
			)
		)
	)
	(footprint ""
		(layer "B.Cu")
		(at 129.397252 -54.602634 90)
		(property "Reference" "C236"
			(at 0 0 90)
			(layer "B.SilkS")
			(hide yes)
			(effects
				(font
					(size 1.27 1.27)
				)
				(justify mirror)
			)
		)
		(property "Value" "SC1U6D3V1MX-GP"
			(at -1.9177 2.0193 90)
			(unlocked yes)
			(layer "B.Fab")
			(hide yes)
			(effects
				(font
					(size 1.016 1.016)
					(thickness 0.1524)
				)
				(justify mirror)
			)
		)
		(property "Device Type" "C0201H14"
			(at -1.9177 0.4953 90)
			(unlocked yes)
			(layer "B.Fab")
			(hide yes)
			(effects
				(font
					(size 1.016 1.016)
					(thickness 0.1524)
				)
				(justify mirror)
			)
		)
		(duplicate_pad_numbers_are_jumpers no)
		(fp_rect
			(start 0.1524 0.3048)
			(end -0.1524 -0.3048)
			(stroke
				(width 0)
				(type default)
			)
			(fill no)
			(layer "B.CrtYd")
		)
		(fp_poly
			(pts
				(xy 0.2794 0.6477) (xy 0.2794 -0.6477) (xy -0.2794 -0.6477) (xy -0.2794 -0.1905) (xy -0.1524 -0.1905)
				(xy -0.1524 -0.3048) (xy 0.1524 -0.3048) (xy 0.1524 0.3048) (xy -0.1524 0.3048) (xy -0.1524 -0.1778)
				(xy -0.2794 -0.1778) (xy -0.2794 0.6477)
			)
			(stroke
				(width 0)
				(type default)
			)
			(fill no)
			(layer "B.CrtYd")
		)
		(fp_rect
			(start 0.2794 0.6477)
			(end -0.2794 -0.6477)
			(stroke
				(width 0)
				(type default)
			)
			(fill no)
			(layer "B.Fab")
		)
		(pad "1" smd custom
			(at 0 -0.2794 270)
			(size 0.0762 0.0762)
			(layers "B.Cu" "B.Mask" "B.Paste")
			(net "GB_VDDA")
			(options
				(clearance outline)
				(anchor circle)
			)
			(primitives
				(gr_poly
					(pts
						(arc
							(start 0.1524 0.127)
							(mid 0.137521 0.162921)
							(end 0.1016 0.1778)
						)
						(arc
							(start -0.1016 0.1778)
							(mid -0.137521 0.162921)
							(end -0.1524 0.127)
						)
						(arc
							(start -0.1524 -0.127)
							(mid -0.137521 -0.162921)
							(end -0.1016 -0.1778)
						)
						(arc
							(start 0.1016 -0.1778)
							(mid 0.137521 -0.162921)
							(end 0.1524 -0.127)
						)
					)
					(width 0)
					(fill yes)
				)
			)
		)
		(pad "2" smd custom
			(at 0 0.2794 270)
			(size 0.0762 0.0762)
			(layers "B.Cu" "B.Mask" "B.Paste")
			(net "GND")
			(options
				(clearance outline)
				(anchor circle)
			)
			(primitives
				(gr_poly
					(pts
						(arc
							(start 0.1524 0.127)
							(mid 0.137521 0.162921)
							(end 0.1016 0.1778)
						)
						(arc
							(start -0.1016 0.1778)
							(mid -0.137521 0.162921)
							(end -0.1524 0.127)
						)
						(arc
							(start -0.1524 -0.127)
							(mid -0.137521 -0.162921)
							(end -0.1016 -0.1778)
						)
						(arc
							(start 0.1016 -0.1778)
							(mid 0.137521 -0.162921)
							(end 0.1524 -0.127)
						)
					)
					(width 0)
					(fill yes)
				)
			)
		)
	)
	(footprint ""
		(layer "B.Cu")
		(at 108.500164 -75.50023)
		(property "Reference" "TP19"
			(at 0 0 0)
			(layer "B.SilkS")
			(hide yes)
			(effects
				(font
					(size 1.27 1.27)
				)
				(justify mirror)
			)
		)
		(property "Value" "TPAD28-2-GP"
			(at 0.0127 -1.6637 0)
			(unlocked yes)
			(layer "B.Fab")
			(hide yes)
			(effects
				(font
					(size 1.016 1.016)
					(thickness 0.1524)
				)
				(justify mirror)
			)
		)
		(property "Device Type" "TPAD28"
			(at 0.0127 -3.1877 0)
			(unlocked yes)
			(layer "B.Fab")
			(hide yes)
			(effects
				(font
					(size 1.016 1.016)
					(thickness 0.1524)
				)
				(justify mirror)
			)
		)
		(duplicate_pad_numbers_are_jumpers no)
		(fp_poly
			(pts
				(arc
					(start 0.3556 0)
					(mid -0.3556 0)
					(end 0.3556 0)
				)
			)
			(stroke
				(width 0)
				(type default)
			)
			(fill no)
			(layer "B.CrtYd")
		)
		(fp_poly
			(pts
				(arc
					(start 0.6096 0)
					(mid -0.6096 0)
					(end 0.6096 0)
				)
			)
			(stroke
				(width 0)
				(type default)
			)
			(fill no)
			(layer "B.Fab")
		)
		(pad "1" smd circle
			(at 0 0 180)
			(size 0.7112 0.7112)
			(layers "B.Cu" "B.Mask" "B.Paste")
			(net "SXP_ACTIVE_1")
		)
	)
	(footprint ""
		(layer "B.Cu")
		(at 179.430934 -39.730426 90)
		(property "Reference" "C424"
			(at 0 0 90)
			(layer "B.SilkS")
			(hide yes)
			(effects
				(font
					(size 1.27 1.27)
				)
				(justify mirror)
			)
		)
		(property "Value" "SCD1U6D3V1KX-GP"
			(at 2.8321 -1.7399 90)
			(unlocked yes)
			(layer "B.Fab")
			(hide yes)
			(effects
				(font
					(size 1.016 1.016)
					(thickness 0.1524)
				)
				(justify mirror)
			)
		)
		(property "Device Type" "C0201H13"
			(at 2.8321 -3.2639 90)
			(unlocked yes)
			(layer "B.Fab")
			(hide yes)
			(effects
				(font
					(size 1.016 1.016)
					(thickness 0.1524)
				)
				(justify mirror)
			)
		)
		(duplicate_pad_numbers_are_jumpers no)
		(fp_rect
			(start 0.2794 0.6477)
			(end -0.2794 -0.6477)
			(stroke
				(width 0)
				(type default)
			)
			(fill no)
			(layer "B.CrtYd")
		)
		(fp_rect
			(start 0.2794 0.6477)
			(end -0.2794 -0.6477)
			(stroke
				(width 0)
				(type default)
			)
			(fill no)
			(layer "B.Fab")
		)
		(pad "1" smd custom
			(at 0 -0.2794 270)
			(size 0.0762 0.0762)
			(layers "B.Cu" "B.Mask" "B.Paste")
			(net "P0V975")
			(options
				(clearance outline)
				(anchor circle)
			)
			(primitives
				(gr_poly
					(pts
						(arc
							(start 0.1524 0.127)
							(mid 0.137521 0.162921)
							(end 0.1016 0.1778)
						)
						(arc
							(start -0.1016 0.1778)
							(mid -0.137521 0.162921)
							(end -0.1524 0.127)
						)
						(arc
							(start -0.1524 -0.127)
							(mid -0.137521 -0.162921)
							(end -0.1016 -0.1778)
						)
						(arc
							(start 0.1016 -0.1778)
							(mid 0.137521 -0.162921)
							(end 0.1524 -0.127)
						)
					)
					(width 0)
					(fill yes)
				)
			)
		)
		(pad "2" smd custom
			(at 0 0.2794 270)
			(size 0.0762 0.0762)
			(layers "B.Cu" "B.Mask" "B.Paste")
			(net "GND")
			(options
				(clearance outline)
				(anchor circle)
			)
			(primitives
				(gr_poly
					(pts
						(arc
							(start 0.1524 0.127)
							(mid 0.137521 0.162921)
							(end 0.1016 0.1778)
						)
						(arc
							(start -0.1016 0.1778)
							(mid -0.137521 0.162921)
							(end -0.1524 0.127)
						)
						(arc
							(start -0.1524 -0.127)
							(mid -0.137521 -0.162921)
							(end -0.1016 -0.1778)
						)
						(arc
							(start 0.1016 -0.1778)
							(mid 0.137521 -0.162921)
							(end 0.1524 -0.127)
						)
					)
					(width 0)
					(fill yes)
				)
			)
		)
	)
	(footprint ""
		(layer "B.Cu")
		(at 107.270042 -72.605392)
		(property "Reference" "C119"
			(at 0 0 0)
			(layer "B.SilkS")
			(hide yes)
			(effects
				(font
					(size 1.27 1.27)
				)
				(justify mirror)
			)
		)
		(property "Value" "SC10U6D3V2MX-GP-U"
			(at 1.524 -1.905 0)
			(unlocked yes)
			(layer "B.Fab")
			(hide yes)
			(effects
				(font
					(size 1.016 1.016)
					(thickness 0.1524)
				)
				(justify mirror)
			)
		)
		(property "Device Type" "C402-TO0D2H28"
			(at 1.524 -3.429 0)
			(unlocked yes)
			(layer "B.Fab")
			(hide yes)
			(effects
				(font
					(size 1.016 1.016)
					(thickness 0.1524)
				)
				(justify mirror)
			)
		)
		(duplicate_pad_numbers_are_jumpers no)
		(fp_rect
			(start 0.4826 0.889)
			(end -0.4826 -0.889)
			(stroke
				(width 0)
				(type default)
			)
			(fill no)
			(layer "B.CrtYd")
		)
		(fp_rect
			(start 0.4826 0.889)
			(end -0.4826 -0.889)
			(stroke
				(width 0)
				(type default)
			)
			(fill no)
			(layer "B.Fab")
		)
		(pad "1" smd custom
			(at 0 -0.4572 180)
			(size 0.1524 0.1524)
			(layers "B.Cu" "B.Mask" "B.Paste")
			(net "P1V8_E")
			(options
				(clearance outline)
				(anchor circle)
			)
			(primitives
				(gr_poly
					(pts
						(arc
							(start -0.254 -0.3048)
							(mid -0.325842 -0.275042)
							(end -0.3556 -0.2032)
						)
						(arc
							(start -0.3556 0.2032)
							(mid -0.325842 0.275042)
							(end -0.254 0.3048)
						)
						(arc
							(start 0.254 0.3048)
							(mid 0.325842 0.275042)
							(end 0.3556 0.2032)
						)
						(arc
							(start 0.3556 -0.2032)
							(mid 0.325842 -0.275042)
							(end 0.254 -0.3048)
						)
					)
					(width 0)
					(fill yes)
				)
			)
		)
		(pad "2" smd custom
			(at 0 0.4572 180)
			(size 0.1524 0.1524)
			(layers "B.Cu" "B.Mask" "B.Paste")
			(net "GND")
			(options
				(clearance outline)
				(anchor circle)
			)
			(primitives
				(gr_poly
					(pts
						(arc
							(start -0.254 -0.3048)
							(mid -0.325842 -0.275042)
							(end -0.3556 -0.2032)
						)
						(arc
							(start -0.3556 0.2032)
							(mid -0.325842 0.275042)
							(end -0.254 0.3048)
						)
						(arc
							(start 0.254 0.3048)
							(mid 0.325842 0.275042)
							(end 0.3556 0.2032)
						)
						(arc
							(start 0.3556 -0.2032)
							(mid 0.325842 -0.275042)
							(end 0.254 -0.3048)
						)
					)
					(width 0)
					(fill yes)
				)
			)
		)
	)
	(footprint ""
		(layer "B.Cu")
		(at 128.366266 -87.251794)
		(property "Reference" "R301"
			(at 0 0 0)
			(layer "B.SilkS")
			(hide yes)
			(effects
				(font
					(size 1.27 1.27)
				)
				(justify mirror)
			)
		)
		(property "Value" "4K75R2F-1-GP"
			(at -0.064008 -3.993896 0)
			(unlocked yes)
			(layer "B.Fab")
			(hide yes)
			(effects
				(font
					(size 1.016 1.016)
					(thickness 0.1524)
				)
				(justify mirror)
			)
		)
		(property "Device Type" "R402H16"
			(at -0.064008 -5.517896 0)
			(unlocked yes)
			(layer "B.Fab")
			(hide yes)
			(effects
				(font
					(size 1.016 1.016)
					(thickness 0.1524)
				)
				(justify mirror)
			)
		)
		(duplicate_pad_numbers_are_jumpers no)
		(fp_line
			(start -0.508 -0.9398)
			(end 0.508 -0.9398)
			(stroke
				(width 0.1524)
				(type default)
			)
			(layer "B.SilkS")
		)
		(fp_line
			(start 0.508 -0.9398)
			(end 0.508 0.9398)
			(stroke
				(width 0.1524)
				(type default)
			)
			(layer "B.SilkS")
		)
		(fp_rect
			(start 0.508 0.9398)
			(end -0.508 -0.9398)
			(stroke
				(width 0)
				(type default)
			)
			(fill no)
			(layer "B.CrtYd")
		)
		(fp_rect
			(start 0.508 0.9398)
			(end -0.508 -0.9398)
			(stroke
				(width 0)
				(type default)
			)
			(fill no)
			(layer "B.Fab")
		)
		(pad "1" smd custom
			(at 0 -0.4445 180)
			(size 0.1397 0.1397)
			(layers "B.Cu" "B.Mask" "B.Paste")
			(net "P1V8_E")
			(options
				(clearance outline)
				(anchor circle)
			)
			(primitives
				(gr_poly
					(pts
						(arc
							(start -0.1778 0.2794)
							(mid -0.249642 0.249642)
							(end -0.2794 0.1778)
						)
						(arc
							(start -0.2794 -0.1778)
							(mid -0.249642 -0.249642)
							(end -0.1778 -0.2794)
						)
						(arc
							(start 0.1778 -0.2794)
							(mid 0.249642 -0.249642)
							(end 0.2794 -0.1778)
						)
						(arc
							(start 0.2794 0.1778)
							(mid 0.249642 0.249642)
							(end 0.1778 0.2794)
						)
					)
					(width 0)
					(fill yes)
				)
			)
		)
		(pad "2" smd custom
			(at 0 0.4445 180)
			(size 0.1397 0.1397)
			(layers "B.Cu" "B.Mask" "B.Paste")
			(net "ICE_TDI")
			(options
				(clearance outline)
				(anchor circle)
			)
			(primitives
				(gr_poly
					(pts
						(arc
							(start -0.1778 0.2794)
							(mid -0.249642 0.249642)
							(end -0.2794 0.1778)
						)
						(arc
							(start -0.2794 -0.1778)
							(mid -0.249642 -0.249642)
							(end -0.1778 -0.2794)
						)
						(arc
							(start 0.1778 -0.2794)
							(mid 0.249642 -0.249642)
							(end 0.2794 -0.1778)
						)
						(arc
							(start 0.2794 0.1778)
							(mid 0.249642 0.249642)
							(end 0.1778 0.2794)
						)
					)
					(width 0)
					(fill yes)
				)
			)
		)
	)
	(footprint ""
		(layer "B.Cu")
		(at 174.405544 -34.123884 180)
		(property "Reference" "C388"
			(at 0 0 0)
			(layer "B.SilkS")
			(hide yes)
			(effects
				(font
					(size 1.27 1.27)
				)
				(justify mirror)
			)
		)
		(property "Value" "SCD1U6D3V1KX-GP"
			(at 2.8321 -1.7399 180)
			(unlocked yes)
			(layer "B.Fab")
			(hide yes)
			(effects
				(font
					(size 1.016 1.016)
					(thickness 0.1524)
				)
				(justify mirror)
			)
		)
		(property "Device Type" "C0201H13"
			(at 2.8321 -3.2639 180)
			(unlocked yes)
			(layer "B.Fab")
			(hide yes)
			(effects
				(font
					(size 1.016 1.016)
					(thickness 0.1524)
				)
				(justify mirror)
			)
		)
		(duplicate_pad_numbers_are_jumpers no)
		(fp_rect
			(start 0.2794 0.6477)
			(end -0.2794 -0.6477)
			(stroke
				(width 0)
				(type default)
			)
			(fill no)
			(layer "B.CrtYd")
		)
		(fp_rect
			(start 0.2794 0.6477)
			(end -0.2794 -0.6477)
			(stroke
				(width 0)
				(type default)
			)
			(fill no)
			(layer "B.Fab")
		)
		(pad "1" smd custom
			(at 0 -0.2794)
			(size 0.0762 0.0762)
			(layers "B.Cu" "B.Mask" "B.Paste")
			(net "PCE_AVDD")
			(options
				(clearance outline)
				(anchor circle)
			)
			(primitives
				(gr_poly
					(pts
						(arc
							(start 0.1524 0.127)
							(mid 0.137521 0.162921)
							(end 0.1016 0.1778)
						)
						(arc
							(start -0.1016 0.1778)
							(mid -0.137521 0.162921)
							(end -0.1524 0.127)
						)
						(arc
							(start -0.1524 -0.127)
							(mid -0.137521 -0.162921)
							(end -0.1016 -0.1778)
						)
						(arc
							(start 0.1016 -0.1778)
							(mid 0.137521 -0.162921)
							(end 0.1524 -0.127)
						)
					)
					(width 0)
					(fill yes)
				)
			)
		)
		(pad "2" smd custom
			(at 0 0.2794)
			(size 0.0762 0.0762)
			(layers "B.Cu" "B.Mask" "B.Paste")
			(net "GND")
			(options
				(clearance outline)
				(anchor circle)
			)
			(primitives
				(gr_poly
					(pts
						(arc
							(start 0.1524 0.127)
							(mid 0.137521 0.162921)
							(end 0.1016 0.1778)
						)
						(arc
							(start -0.1016 0.1778)
							(mid -0.137521 0.162921)
							(end -0.1524 0.127)
						)
						(arc
							(start -0.1524 -0.127)
							(mid -0.137521 -0.162921)
							(end -0.1016 -0.1778)
						)
						(arc
							(start 0.1016 -0.1778)
							(mid 0.137521 -0.162921)
							(end 0.1524 -0.127)
						)
					)
					(width 0)
					(fill yes)
				)
			)
		)
	)
	(footprint ""
		(layer "B.Cu")
		(at 179.40909 -48.203358 -90)
		(property "Reference" "C492"
			(at 0 0 90)
			(layer "B.SilkS")
			(hide yes)
			(effects
				(font
					(size 1.27 1.27)
				)
				(justify mirror)
			)
		)
		(property "Value" "SCD1U6D3V1KX-GP"
			(at 2.8321 -1.7399 270)
			(unlocked yes)
			(layer "B.Fab")
			(hide yes)
			(effects
				(font
					(size 1.016 1.016)
					(thickness 0.1524)
				)
				(justify mirror)
			)
		)
		(property "Device Type" "C0201H13"
			(at 2.8321 -3.2639 270)
			(unlocked yes)
			(layer "B.Fab")
			(hide yes)
			(effects
				(font
					(size 1.016 1.016)
					(thickness 0.1524)
				)
				(justify mirror)
			)
		)
		(duplicate_pad_numbers_are_jumpers no)
		(fp_rect
			(start 0.2794 0.6477)
			(end -0.2794 -0.6477)
			(stroke
				(width 0)
				(type default)
			)
			(fill no)
			(layer "B.CrtYd")
		)
		(fp_rect
			(start 0.2794 0.6477)
			(end -0.2794 -0.6477)
			(stroke
				(width 0)
				(type default)
			)
			(fill no)
			(layer "B.Fab")
		)
		(pad "1" smd custom
			(at 0 -0.2794 90)
			(size 0.0762 0.0762)
			(layers "B.Cu" "B.Mask" "B.Paste")
			(net "P1V8_C")
			(options
				(clearance outline)
				(anchor circle)
			)
			(primitives
				(gr_poly
					(pts
						(arc
							(start 0.1524 0.127)
							(mid 0.137521 0.162921)
							(end 0.1016 0.1778)
						)
						(arc
							(start -0.1016 0.1778)
							(mid -0.137521 0.162921)
							(end -0.1524 0.127)
						)
						(arc
							(start -0.1524 -0.127)
							(mid -0.137521 -0.162921)
							(end -0.1016 -0.1778)
						)
						(arc
							(start 0.1016 -0.1778)
							(mid 0.137521 -0.162921)
							(end 0.1524 -0.127)
						)
					)
					(width 0)
					(fill yes)
				)
			)
		)
		(pad "2" smd custom
			(at 0 0.2794 90)
			(size 0.0762 0.0762)
			(layers "B.Cu" "B.Mask" "B.Paste")
			(net "GND")
			(options
				(clearance outline)
				(anchor circle)
			)
			(primitives
				(gr_poly
					(pts
						(arc
							(start 0.1524 0.127)
							(mid 0.137521 0.162921)
							(end 0.1016 0.1778)
						)
						(arc
							(start -0.1016 0.1778)
							(mid -0.137521 0.162921)
							(end -0.1524 0.127)
						)
						(arc
							(start -0.1524 -0.127)
							(mid -0.137521 -0.162921)
							(end -0.1016 -0.1778)
						)
						(arc
							(start 0.1016 -0.1778)
							(mid 0.137521 -0.162921)
							(end 0.1524 -0.127)
						)
					)
					(width 0)
					(fill yes)
				)
			)
		)
	)
	(footprint ""
		(layer "B.Cu")
		(at 191.897 -43.053 -90)
		(property "Reference" "R188"
			(at 0 0 90)
			(layer "B.SilkS")
			(hide yes)
			(effects
				(font
					(size 1.27 1.27)
				)
				(justify mirror)
			)
		)
		(property "Value" "2K2R2F-GP"
			(at -0.064008 -3.993896 270)
			(unlocked yes)
			(layer "B.Fab")
			(hide yes)
			(effects
				(font
					(size 1.016 1.016)
					(thickness 0.1524)
				)
				(justify mirror)
			)
		)
		(property "Device Type" "R402H16"
			(at -0.064008 -5.517896 270)
			(unlocked yes)
			(layer "B.Fab")
			(hide yes)
			(effects
				(font
					(size 1.016 1.016)
					(thickness 0.1524)
				)
				(justify mirror)
			)
		)
		(duplicate_pad_numbers_are_jumpers no)
		(fp_line
			(start -0.508 -0.9398)
			(end 0.508 -0.9398)
			(stroke
				(width 0.1524)
				(type default)
			)
			(layer "B.SilkS")
		)
		(fp_line
			(start 0.508 -0.9398)
			(end 0.508 0.9398)
			(stroke
				(width 0.1524)
				(type default)
			)
			(layer "B.SilkS")
		)
		(fp_rect
			(start 0.508 0.9398)
			(end -0.508 -0.9398)
			(stroke
				(width 0)
				(type default)
			)
			(fill no)
			(layer "B.CrtYd")
		)
		(fp_rect
			(start 0.508 0.9398)
			(end -0.508 -0.9398)
			(stroke
				(width 0)
				(type default)
			)
			(fill no)
			(layer "B.Fab")
		)
		(pad "1" smd custom
			(at 0 -0.4445 90)
			(size 0.1397 0.1397)
			(layers "B.Cu" "B.Mask" "B.Paste")
			(net "P1V8_C")
			(options
				(clearance outline)
				(anchor circle)
			)
			(primitives
				(gr_poly
					(pts
						(arc
							(start -0.1778 0.2794)
							(mid -0.249642 0.249642)
							(end -0.2794 0.1778)
						)
						(arc
							(start -0.2794 -0.1778)
							(mid -0.249642 -0.249642)
							(end -0.1778 -0.2794)
						)
						(arc
							(start 0.1778 -0.2794)
							(mid 0.249642 -0.249642)
							(end 0.2794 -0.1778)
						)
						(arc
							(start 0.2794 0.1778)
							(mid 0.249642 0.249642)
							(end 0.1778 0.2794)
						)
					)
					(width 0)
					(fill yes)
				)
			)
		)
		(pad "2" smd custom
			(at 0 0.4445 90)
			(size 0.1397 0.1397)
			(layers "B.Cu" "B.Mask" "B.Paste")
			(net "I2C_IOC_3_SCL")
			(options
				(clearance outline)
				(anchor circle)
			)
			(primitives
				(gr_poly
					(pts
						(arc
							(start -0.1778 0.2794)
							(mid -0.249642 0.249642)
							(end -0.2794 0.1778)
						)
						(arc
							(start -0.2794 -0.1778)
							(mid -0.249642 -0.249642)
							(end -0.1778 -0.2794)
						)
						(arc
							(start 0.1778 -0.2794)
							(mid 0.249642 -0.249642)
							(end 0.2794 -0.1778)
						)
						(arc
							(start 0.2794 0.1778)
							(mid 0.249642 0.249642)
							(end 0.1778 0.2794)
						)
					)
					(width 0)
					(fill yes)
				)
			)
		)
	)
	(footprint ""
		(layer "B.Cu")
		(at 160.6042 -39.7256 180)
		(property "Reference" "R240"
			(at 0 0 0)
			(layer "B.SilkS")
			(hide yes)
			(effects
				(font
					(size 1.27 1.27)
				)
				(justify mirror)
			)
		)
		(property "Value" "3KR2J-2-GP"
			(at -0.064008 -3.993896 180)
			(unlocked yes)
			(layer "B.Fab")
			(hide yes)
			(effects
				(font
					(size 1.016 1.016)
					(thickness 0.1524)
				)
				(justify mirror)
			)
		)
		(property "Device Type" "R402H16"
			(at -0.064008 -5.517896 180)
			(unlocked yes)
			(layer "B.Fab")
			(hide yes)
			(effects
				(font
					(size 1.016 1.016)
					(thickness 0.1524)
				)
				(justify mirror)
			)
		)
		(duplicate_pad_numbers_are_jumpers no)
		(fp_line
			(start 0.508 -0.9398)
			(end 0.508 0.9398)
			(stroke
				(width 0.1524)
				(type default)
			)
			(layer "B.SilkS")
		)
		(fp_line
			(start -0.508 -0.9398)
			(end 0.508 -0.9398)
			(stroke
				(width 0.1524)
				(type default)
			)
			(layer "B.SilkS")
		)
		(fp_rect
			(start 0.508 0.9398)
			(end -0.508 -0.9398)
			(stroke
				(width 0)
				(type default)
			)
			(fill no)
			(layer "B.CrtYd")
		)
		(fp_rect
			(start 0.508 0.9398)
			(end -0.508 -0.9398)
			(stroke
				(width 0)
				(type default)
			)
			(fill no)
			(layer "B.Fab")
		)
		(pad "1" smd custom
			(at 0 -0.4445)
			(size 0.1397 0.1397)
			(layers "B.Cu" "B.Mask" "B.Paste")
			(net "RTRIM")
			(options
				(clearance outline)
				(anchor circle)
			)
			(primitives
				(gr_poly
					(pts
						(arc
							(start -0.1778 0.2794)
							(mid -0.249642 0.249642)
							(end -0.2794 0.1778)
						)
						(arc
							(start -0.2794 -0.1778)
							(mid -0.249642 -0.249642)
							(end -0.1778 -0.2794)
						)
						(arc
							(start 0.1778 -0.2794)
							(mid 0.249642 -0.249642)
							(end 0.2794 -0.1778)
						)
						(arc
							(start 0.2794 0.1778)
							(mid 0.249642 0.249642)
							(end 0.1778 0.2794)
						)
					)
					(width 0)
					(fill yes)
				)
			)
		)
		(pad "2" smd custom
			(at 0 0.4445)
			(size 0.1397 0.1397)
			(layers "B.Cu" "B.Mask" "B.Paste")
			(net "RTRIM#")
			(options
				(clearance outline)
				(anchor circle)
			)
			(primitives
				(gr_poly
					(pts
						(arc
							(start -0.1778 0.2794)
							(mid -0.249642 0.249642)
							(end -0.2794 0.1778)
						)
						(arc
							(start -0.2794 -0.1778)
							(mid -0.249642 -0.249642)
							(end -0.1778 -0.2794)
						)
						(arc
							(start 0.1778 -0.2794)
							(mid 0.249642 -0.249642)
							(end 0.2794 -0.1778)
						)
						(arc
							(start 0.2794 0.1778)
							(mid 0.249642 0.249642)
							(end 0.1778 0.2794)
						)
					)
					(width 0)
					(fill yes)
				)
			)
		)
	)
	(footprint ""
		(layer "B.Cu")
		(at 193.60642 -67.277234 -90)
		(property "Reference" "U18"
			(at 0 0 90)
			(layer "B.SilkS")
			(hide yes)
			(effects
				(font
					(size 1.27 1.27)
				)
				(justify mirror)
			)
		)
		(property "Value" "S29GL128S10TFIV20-GP"
			(at 0.1778 -20.32 270)
			(unlocked yes)
			(layer "B.Fab")
			(hide yes)
			(effects
				(font
					(size 1.016 1.016)
					(thickness 0.1524)
				)
				(justify mirror)
			)
		)
		(property "Device Type" "TSOP56-1H48"
			(at 0.1778 -22.225 270)
			(unlocked yes)
			(layer "B.Fab")
			(hide yes)
			(effects
				(font
					(size 1.016 1.016)
					(thickness 0.1524)
				)
				(justify mirror)
			)
		)
		(duplicate_pad_numbers_are_jumpers no)
		(fp_line
			(start -6.8326 8.5598)
			(end -6.8326 -8.5598)
			(stroke
				(width 0.1524)
				(type default)
			)
			(layer "B.SilkS")
		)
		(fp_line
			(start 7.366 8.5598)
			(end 7.366 10.795)
			(stroke
				(width 0.508)
				(type default)
			)
			(layer "B.SilkS")
		)
		(fp_line
			(start 7.5438 8.5598)
			(end -6.8326 8.5598)
			(stroke
				(width 0.1524)
				(type default)
			)
			(layer "B.SilkS")
		)
		(fp_line
			(start 7.112 0)
			(end 7.5438 0.4318)
			(stroke
				(width 0.1524)
				(type default)
			)
			(layer "B.SilkS")
		)
		(fp_line
			(start 7.5438 -0.4318)
			(end 7.112 0)
			(stroke
				(width 0.1524)
				(type default)
			)
			(layer "B.SilkS")
		)
		(fp_line
			(start -6.8326 -8.5598)
			(end 7.5438 -8.5598)
			(stroke
				(width 0.1524)
				(type default)
			)
			(layer "B.SilkS")
		)
		(fp_line
			(start 7.5438 -8.5598)
			(end 7.5438 8.5598)
			(stroke
				(width 0.1524)
				(type default)
			)
			(layer "B.SilkS")
		)
		(fp_poly
			(pts
				(xy 7.62 11.049) (xy -7.62 11.049) (xy -7.62 -11.049) (xy 7.62 -11.049)
			)
			(stroke
				(width 0)
				(type default)
			)
			(fill no)
			(layer "B.CrtYd")
		)
		(fp_poly
			(pts
				(xy 7.62 -11.049) (xy -7.62 -11.049) (xy -7.62 11.049) (xy 7.62 11.049)
			)
			(stroke
				(width 0)
				(type default)
			)
			(fill no)
			(layer "B.Fab")
		)
		(pad "1" smd rect
			(at 6.75005 9.6139 90)
			(size 0.3048 1.524)
			(layers "B.Cu" "B.Mask" "B.Paste")
			(net "Net_766")
		)
		(pad "2" smd rect
			(at 6.24967 9.6139 90)
			(size 0.3048 1.524)
			(layers "B.Cu" "B.Mask" "B.Paste")
			(net "XM_ADDR_23")
		)
		(pad "3" smd rect
			(at 5.75056 9.6139 90)
			(size 0.3048 1.524)
			(layers "B.Cu" "B.Mask" "B.Paste")
			(net "XM_ADDR_16")
		)
		(pad "4" smd rect
			(at 5.25018 9.6139 90)
			(size 0.3048 1.524)
			(layers "B.Cu" "B.Mask" "B.Paste")
			(net "XM_ADDR_15")
		)
		(pad "5" smd rect
			(at 4.7498 9.6139 90)
			(size 0.3048 1.524)
			(layers "B.Cu" "B.Mask" "B.Paste")
			(net "XM_ADDR_14")
		)
		(pad "6" smd rect
			(at 4.24942 9.6139 90)
			(size 0.3048 1.524)
			(layers "B.Cu" "B.Mask" "B.Paste")
			(net "XM_ADDR_13")
		)
		(pad "7" smd rect
			(at 3.75031 9.6139 90)
			(size 0.3048 1.524)
			(layers "B.Cu" "B.Mask" "B.Paste")
			(net "XM_ADDR_12")
		)
		(pad "8" smd rect
			(at 3.24993 9.6139 90)
			(size 0.3048 1.524)
			(layers "B.Cu" "B.Mask" "B.Paste")
			(net "XM_ADDR_11")
		)
		(pad "9" smd rect
			(at 2.74955 9.6139 90)
			(size 0.3048 1.524)
			(layers "B.Cu" "B.Mask" "B.Paste")
			(net "XM_ADDR_10")
		)
		(pad "10" smd rect
			(at 2.25044 9.6139 90)
			(size 0.3048 1.524)
			(layers "B.Cu" "B.Mask" "B.Paste")
			(net "XM_ADDR_9")
		)
		(pad "11" smd rect
			(at 1.75006 9.6139 90)
			(size 0.3048 1.524)
			(layers "B.Cu" "B.Mask" "B.Paste")
			(net "XM_ADDR_20")
		)
		(pad "12" smd rect
			(at 1.24968 9.6139 90)
			(size 0.3048 1.524)
			(layers "B.Cu" "B.Mask" "B.Paste")
			(net "XM_ADDR_21")
		)
		(pad "13" smd rect
			(at 0.75057 9.6139 90)
			(size 0.3048 1.524)
			(layers "B.Cu" "B.Mask" "B.Paste")
			(net "XM_WE_N")
		)
		(pad "14" smd rect
			(at 0.25019 9.6139 90)
			(size 0.3048 1.524)
			(layers "B.Cu" "B.Mask" "B.Paste")
			(net "XM_F_RST_N")
		)
		(pad "15" smd rect
			(at -0.25019 9.6139 90)
			(size 0.3048 1.524)
			(layers "B.Cu" "B.Mask" "B.Paste")
			(net "XM_ADDR_22")
		)
		(pad "16" smd rect
			(at -0.75057 9.6139 90)
			(size 0.3048 1.524)
			(layers "B.Cu" "B.Mask" "B.Paste")
			(net "IOC_WP_N")
		)
		(pad "17" smd rect
			(at -1.24968 9.6139 90)
			(size 0.3048 1.524)
			(layers "B.Cu" "B.Mask" "B.Paste")
			(net "Net_761")
		)
		(pad "18" smd rect
			(at -1.75006 9.6139 90)
			(size 0.3048 1.524)
			(layers "B.Cu" "B.Mask" "B.Paste")
			(net "XM_ADDR_19")
		)
		(pad "19" smd rect
			(at -2.25044 9.6139 90)
			(size 0.3048 1.524)
			(layers "B.Cu" "B.Mask" "B.Paste")
			(net "XM_ADDR_18")
		)
		(pad "20" smd rect
			(at -2.74955 9.6139 90)
			(size 0.3048 1.524)
			(layers "B.Cu" "B.Mask" "B.Paste")
			(net "XM_ADDR_8")
		)
		(pad "21" smd rect
			(at -3.24993 9.6139 90)
			(size 0.3048 1.524)
			(layers "B.Cu" "B.Mask" "B.Paste")
			(net "XM_ADDR_7")
		)
		(pad "22" smd rect
			(at -3.75031 9.6139 90)
			(size 0.3048 1.524)
			(layers "B.Cu" "B.Mask" "B.Paste")
			(net "XM_ADDR_6")
		)
		(pad "23" smd rect
			(at -4.24942 9.6139 90)
			(size 0.3048 1.524)
			(layers "B.Cu" "B.Mask" "B.Paste")
			(net "XM_ADDR_5")
		)
		(pad "24" smd rect
			(at -4.7498 9.6139 90)
			(size 0.3048 1.524)
			(layers "B.Cu" "B.Mask" "B.Paste")
			(net "XM_ADDR_4")
		)
		(pad "25" smd rect
			(at -5.25018 9.6139 90)
			(size 0.3048 1.524)
			(layers "B.Cu" "B.Mask" "B.Paste")
			(net "XM_ADDR_3")
		)
		(pad "26" smd rect
			(at -5.75056 9.6139 90)
			(size 0.3048 1.524)
			(layers "B.Cu" "B.Mask" "B.Paste")
			(net "XM_ADDR_2")
		)
		(pad "27" smd rect
			(at -6.24967 9.6139 90)
			(size 0.3048 1.524)
			(layers "B.Cu" "B.Mask" "B.Paste")
			(net "Net_762")
		)
		(pad "28" smd rect
			(at -6.75005 9.6139 90)
			(size 0.3048 1.524)
			(layers "B.Cu" "B.Mask" "B.Paste")
			(net "Net_763")
		)
		(pad "29" smd rect
			(at -6.75005 -9.6139 90)
			(size 0.3048 1.524)
			(layers "B.Cu" "B.Mask" "B.Paste")
			(net "P1V8_C")
		)
		(pad "30" smd rect
			(at -6.24967 -9.6139 90)
			(size 0.3048 1.524)
			(layers "B.Cu" "B.Mask" "B.Paste")
			(net "Net_760")
		)
		(pad "31" smd rect
			(at -5.75056 -9.6139 90)
			(size 0.3048 1.524)
			(layers "B.Cu" "B.Mask" "B.Paste")
			(net "XM_ADDR_1")
		)
		(pad "32" smd rect
			(at -5.25018 -9.6139 90)
			(size 0.3048 1.524)
			(layers "B.Cu" "B.Mask" "B.Paste")
			(net "XM_NOR_CS_N")
		)
		(pad "33" smd rect
			(at -4.7498 -9.6139 90)
			(size 0.3048 1.524)
			(layers "B.Cu" "B.Mask" "B.Paste")
			(net "GND")
		)
		(pad "34" smd rect
			(at -4.24942 -9.6139 90)
			(size 0.3048 1.524)
			(layers "B.Cu" "B.Mask" "B.Paste")
			(net "XM_OE_N")
		)
		(pad "35" smd rect
			(at -3.75031 -9.6139 90)
			(size 0.3048 1.524)
			(layers "B.Cu" "B.Mask" "B.Paste")
			(net "XM_DATA_0")
		)
		(pad "36" smd rect
			(at -3.24993 -9.6139 90)
			(size 0.3048 1.524)
			(layers "B.Cu" "B.Mask" "B.Paste")
			(net "XM_DATA_8")
		)
		(pad "37" smd rect
			(at -2.74955 -9.6139 90)
			(size 0.3048 1.524)
			(layers "B.Cu" "B.Mask" "B.Paste")
			(net "XM_DATA_1")
		)
		(pad "38" smd rect
			(at -2.25044 -9.6139 90)
			(size 0.3048 1.524)
			(layers "B.Cu" "B.Mask" "B.Paste")
			(net "XM_DATA_9")
		)
		(pad "39" smd rect
			(at -1.75006 -9.6139 90)
			(size 0.3048 1.524)
			(layers "B.Cu" "B.Mask" "B.Paste")
			(net "XM_DATA_2")
		)
		(pad "40" smd rect
			(at -1.24968 -9.6139 90)
			(size 0.3048 1.524)
			(layers "B.Cu" "B.Mask" "B.Paste")
			(net "XM_DATA_10")
		)
		(pad "41" smd rect
			(at -0.75057 -9.6139 90)
			(size 0.3048 1.524)
			(layers "B.Cu" "B.Mask" "B.Paste")
			(net "XM_DATA_3")
		)
		(pad "42" smd rect
			(at -0.25019 -9.6139 90)
			(size 0.3048 1.524)
			(layers "B.Cu" "B.Mask" "B.Paste")
			(net "XM_DATA_11")
		)
		(pad "43" smd rect
			(at 0.25019 -9.6139 90)
			(size 0.3048 1.524)
			(layers "B.Cu" "B.Mask" "B.Paste")
			(net "P3V3")
		)
		(pad "44" smd rect
			(at 0.75057 -9.6139 90)
			(size 0.3048 1.524)
			(layers "B.Cu" "B.Mask" "B.Paste")
			(net "XM_DATA_4")
		)
		(pad "45" smd rect
			(at 1.24968 -9.6139 90)
			(size 0.3048 1.524)
			(layers "B.Cu" "B.Mask" "B.Paste")
			(net "XM_DATA_12")
		)
		(pad "46" smd rect
			(at 1.75006 -9.6139 90)
			(size 0.3048 1.524)
			(layers "B.Cu" "B.Mask" "B.Paste")
			(net "XM_DATA_5")
		)
		(pad "47" smd rect
			(at 2.25044 -9.6139 90)
			(size 0.3048 1.524)
			(layers "B.Cu" "B.Mask" "B.Paste")
			(net "XM_DATA_13")
		)
		(pad "48" smd rect
			(at 2.74955 -9.6139 90)
			(size 0.3048 1.524)
			(layers "B.Cu" "B.Mask" "B.Paste")
			(net "XM_DATA_6")
		)
		(pad "49" smd rect
			(at 3.24993 -9.6139 90)
			(size 0.3048 1.524)
			(layers "B.Cu" "B.Mask" "B.Paste")
			(net "XM_DATA_14")
		)
		(pad "50" smd rect
			(at 3.75031 -9.6139 90)
			(size 0.3048 1.524)
			(layers "B.Cu" "B.Mask" "B.Paste")
			(net "XM_DATA_7")
		)
		(pad "51" smd rect
			(at 4.24942 -9.6139 90)
			(size 0.3048 1.524)
			(layers "B.Cu" "B.Mask" "B.Paste")
			(net "XM_DATA_15")
		)
		(pad "52" smd rect
			(at 4.7498 -9.6139 90)
			(size 0.3048 1.524)
			(layers "B.Cu" "B.Mask" "B.Paste")
			(net "GND")
		)
		(pad "53" smd rect
			(at 5.25018 -9.6139 90)
			(size 0.3048 1.524)
			(layers "B.Cu" "B.Mask" "B.Paste")
			(net "IOC_BYTE_N")
		)
		(pad "54" smd rect
			(at 5.75056 -9.6139 90)
			(size 0.3048 1.524)
			(layers "B.Cu" "B.Mask" "B.Paste")
			(net "XM_ADDR_17")
		)
		(pad "55" smd rect
			(at 6.24967 -9.6139 90)
			(size 0.3048 1.524)
			(layers "B.Cu" "B.Mask" "B.Paste")
			(net "Net_764")
		)
		(pad "56" smd rect
			(at 6.75005 -9.6139 90)
			(size 0.3048 1.524)
			(layers "B.Cu" "B.Mask" "B.Paste")
			(net "Net_765")
		)
	)
	(footprint ""
		(layer "B.Cu")
		(at 92.119958 -78.247748)
		(property "Reference" "C208"
			(at 0 0 0)
			(layer "B.SilkS")
			(hide yes)
			(effects
				(font
					(size 1.27 1.27)
				)
				(justify mirror)
			)
		)
		(property "Value" "SC22U6D3V3MX-9-GP-U"
			(at 0 -2.8194 0)
			(unlocked yes)
			(layer "B.Fab")
			(hide yes)
			(effects
				(font
					(size 1.016 1.016)
					(thickness 0.1524)
				)
				(justify mirror)
			)
		)
		(property "Device Type" "C603H40"
			(at 0 -4.3434 0)
			(unlocked yes)
			(layer "B.Fab")
			(hide yes)
			(effects
				(font
					(size 1.016 1.016)
					(thickness 0.1524)
				)
				(justify mirror)
			)
		)
		(duplicate_pad_numbers_are_jumpers no)
		(fp_line
			(start -0.508 0)
			(end 0.508 0)
			(stroke
				(width 0.2032)
				(type default)
			)
			(layer "B.SilkS")
		)
		(fp_rect
			(start 0.5842 1.3335)
			(end -0.5842 -1.3335)
			(stroke
				(width 0)
				(type default)
			)
			(fill no)
			(layer "B.CrtYd")
		)
		(fp_rect
			(start 0.5842 1.3335)
			(end -0.5842 -1.3335)
			(stroke
				(width 0)
				(type default)
			)
			(fill no)
			(layer "B.Fab")
		)
		(pad "1" smd custom
			(at 0 -0.762 180)
			(size 0.2159 0.2159)
			(layers "B.Cu" "B.Mask" "B.Paste")
			(net "SYSPLL_VDDA09")
			(options
				(clearance outline)
				(anchor circle)
			)
			(primitives
				(gr_poly
					(pts
						(arc
							(start -0.3302 0.4318)
							(mid -0.402042 0.402042)
							(end -0.4318 0.3302)
						)
						(arc
							(start -0.4318 -0.3302)
							(mid -0.402042 -0.402042)
							(end -0.3302 -0.4318)
						)
						(arc
							(start 0.3302 -0.4318)
							(mid 0.402042 -0.402042)
							(end 0.4318 -0.3302)
						)
						(arc
							(start 0.4318 0.3302)
							(mid 0.402042 0.402042)
							(end 0.3302 0.4318)
						)
					)
					(width 0)
					(fill yes)
				)
			)
		)
		(pad "2" smd custom
			(at 0 0.762 180)
			(size 0.2159 0.2159)
			(layers "B.Cu" "B.Mask" "B.Paste")
			(net "GND")
			(options
				(clearance outline)
				(anchor circle)
			)
			(primitives
				(gr_poly
					(pts
						(arc
							(start -0.3302 0.4318)
							(mid -0.402042 0.402042)
							(end -0.4318 0.3302)
						)
						(arc
							(start -0.4318 -0.3302)
							(mid -0.402042 -0.402042)
							(end -0.3302 -0.4318)
						)
						(arc
							(start 0.3302 -0.4318)
							(mid 0.402042 -0.402042)
							(end 0.4318 -0.3302)
						)
						(arc
							(start 0.4318 0.3302)
							(mid 0.402042 0.402042)
							(end 0.3302 0.4318)
						)
					)
					(width 0)
					(fill yes)
				)
			)
		)
	)
	(footprint ""
		(layer "B.Cu")
		(at 189.9158 -29.1592 90)
		(property "Reference" "TP74"
			(at 0 0 90)
			(layer "B.SilkS")
			(hide yes)
			(effects
				(font
					(size 1.27 1.27)
				)
				(justify mirror)
			)
		)
		(property "Value" "TPAD28-2-GP"
			(at 0.0127 -1.6637 90)
			(unlocked yes)
			(layer "B.Fab")
			(hide yes)
			(effects
				(font
					(size 1.016 1.016)
					(thickness 0.1524)
				)
				(justify mirror)
			)
		)
		(property "Device Type" "TPAD28"
			(at 0.0127 -3.1877 90)
			(unlocked yes)
			(layer "B.Fab")
			(hide yes)
			(effects
				(font
					(size 1.016 1.016)
					(thickness 0.1524)
				)
				(justify mirror)
			)
		)
		(duplicate_pad_numbers_are_jumpers no)
		(fp_poly
			(pts
				(arc
					(start 0 0.3556)
					(mid 0 -0.3556)
					(end 0 0.3556)
				)
			)
			(stroke
				(width 0)
				(type default)
			)
			(fill no)
			(layer "B.CrtYd")
		)
		(fp_poly
			(pts
				(arc
					(start 0 0.6096)
					(mid 0 -0.6096)
					(end 0 0.6096)
				)
			)
			(stroke
				(width 0)
				(type default)
			)
			(fill no)
			(layer "B.Fab")
		)
		(pad "1" smd circle
			(at 0 0 270)
			(size 0.7112 0.7112)
			(layers "B.Cu" "B.Mask" "B.Paste")
			(net "IOC_GPIO_21")
		)
	)
	(footprint ""
		(layer "B.Cu")
		(at 198.374 -23.749 180)
		(property "Reference" "R238"
			(at 0 0 0)
			(layer "B.SilkS")
			(hide yes)
			(effects
				(font
					(size 1.27 1.27)
				)
				(justify mirror)
			)
		)
		(property "Value" "150R2F-1-GP"
			(at -0.064008 -3.993896 180)
			(unlocked yes)
			(layer "B.Fab")
			(hide yes)
			(effects
				(font
					(size 1.016 1.016)
					(thickness 0.1524)
				)
				(justify mirror)
			)
		)
		(property "Device Type" "R402H16"
			(at -0.064008 -5.517896 180)
			(unlocked yes)
			(layer "B.Fab")
			(hide yes)
			(effects
				(font
					(size 1.016 1.016)
					(thickness 0.1524)
				)
				(justify mirror)
			)
		)
		(duplicate_pad_numbers_are_jumpers no)
		(fp_line
			(start 0.508 -0.9398)
			(end 0.508 0.9398)
			(stroke
				(width 0.1524)
				(type default)
			)
			(layer "B.SilkS")
		)
		(fp_line
			(start -0.508 -0.9398)
			(end 0.508 -0.9398)
			(stroke
				(width 0.1524)
				(type default)
			)
			(layer "B.SilkS")
		)
		(fp_rect
			(start 0.508 0.9398)
			(end -0.508 -0.9398)
			(stroke
				(width 0)
				(type default)
			)
			(fill no)
			(layer "B.CrtYd")
		)
		(fp_rect
			(start 0.508 0.9398)
			(end -0.508 -0.9398)
			(stroke
				(width 0)
				(type default)
			)
			(fill no)
			(layer "B.Fab")
		)
		(pad "1" smd custom
			(at 0 -0.4445)
			(size 0.1397 0.1397)
			(layers "B.Cu" "B.Mask" "B.Paste")
			(net "P3V3")
			(options
				(clearance outline)
				(anchor circle)
			)
			(primitives
				(gr_poly
					(pts
						(arc
							(start -0.1778 0.2794)
							(mid -0.249642 0.249642)
							(end -0.2794 0.1778)
						)
						(arc
							(start -0.2794 -0.1778)
							(mid -0.249642 -0.249642)
							(end -0.1778 -0.2794)
						)
						(arc
							(start 0.1778 -0.2794)
							(mid 0.249642 -0.249642)
							(end 0.2794 -0.1778)
						)
						(arc
							(start 0.2794 0.1778)
							(mid 0.249642 0.249642)
							(end 0.1778 0.2794)
						)
					)
					(width 0)
					(fill yes)
				)
			)
		)
		(pad "2" smd custom
			(at 0 0.4445)
			(size 0.1397 0.1397)
			(layers "B.Cu" "B.Mask" "B.Paste")
			(net "SYS_HB_LED_R")
			(options
				(clearance outline)
				(anchor circle)
			)
			(primitives
				(gr_poly
					(pts
						(arc
							(start -0.1778 0.2794)
							(mid -0.249642 0.249642)
							(end -0.2794 0.1778)
						)
						(arc
							(start -0.2794 -0.1778)
							(mid -0.249642 -0.249642)
							(end -0.1778 -0.2794)
						)
						(arc
							(start 0.1778 -0.2794)
							(mid 0.249642 -0.249642)
							(end 0.2794 -0.1778)
						)
						(arc
							(start 0.2794 0.1778)
							(mid 0.249642 0.249642)
							(end 0.1778 0.2794)
						)
					)
					(width 0)
					(fill yes)
				)
			)
		)
	)
	(footprint ""
		(layer "B.Cu")
		(at 38.592252 -109.59338 90)
		(property "Reference" "C563"
			(at 0 0 90)
			(layer "B.SilkS")
			(hide yes)
			(effects
				(font
					(size 1.27 1.27)
				)
				(justify mirror)
			)
		)
		(property "Value" "SC10U16V5KX-7-GP-U"
			(at 0.0762 -6.1214 90)
			(unlocked yes)
			(layer "B.Fab")
			(hide yes)
			(effects
				(font
					(size 1.016 1.016)
					(thickness 0.1524)
				)
				(justify mirror)
			)
		)
		(property "Device Type" "C805H58"
			(at 0.0762 -8.1534 90)
			(unlocked yes)
			(layer "B.Fab")
			(hide yes)
			(effects
				(font
					(size 1.016 1.016)
					(thickness 0.1524)
				)
				(justify mirror)
			)
		)
		(duplicate_pad_numbers_are_jumpers no)
		(fp_line
			(start -0.635 0)
			(end 0.635 0)
			(stroke
				(width 0.508)
				(type default)
			)
			(layer "B.SilkS")
		)
		(fp_rect
			(start 0.9652 1.778)
			(end -0.9652 -1.778)
			(stroke
				(width 0)
				(type default)
			)
			(fill no)
			(layer "B.CrtYd")
		)
		(fp_poly
			(pts
				(xy 0.9652 -1.778) (xy -0.9652 -1.778) (xy -0.9652 1.778) (xy 0.9652 1.778)
			)
			(stroke
				(width 0)
				(type default)
			)
			(fill no)
			(layer "B.Fab")
		)
		(pad "1" smd rect
			(at 0 -0.9652 270)
			(size 1.397 1.143)
			(layers "B.Cu" "B.Mask" "B.Paste")
			(net "P5V")
		)
		(pad "2" smd rect
			(at 0 0.9652 270)
			(size 1.397 1.143)
			(layers "B.Cu" "B.Mask" "B.Paste")
			(net "GND")
		)
	)
	(footprint ""
		(layer "B.Cu")
		(at 120.5484 -64.7192 -90)
		(property "Reference" "C218"
			(at 0 0 90)
			(layer "B.SilkS")
			(hide yes)
			(effects
				(font
					(size 1.27 1.27)
				)
				(justify mirror)
			)
		)
		(property "Value" "SCD1U16V2KX-3GP"
			(at -1.1811 -2.7051 270)
			(unlocked yes)
			(layer "B.Fab")
			(hide yes)
			(effects
				(font
					(size 1.016 1.016)
					(thickness 0.1524)
				)
				(justify mirror)
			)
		)
		(property "Device Type" "C402H22"
			(at -1.1811 -4.2291 270)
			(unlocked yes)
			(layer "B.Fab")
			(hide yes)
			(effects
				(font
					(size 1.016 1.016)
					(thickness 0.1524)
				)
				(justify mirror)
			)
		)
		(duplicate_pad_numbers_are_jumpers no)
		(fp_rect
			(start 0.4318 0.9525)
			(end -0.4318 -0.9525)
			(stroke
				(width 0)
				(type default)
			)
			(fill no)
			(layer "B.CrtYd")
		)
		(fp_rect
			(start 0.4318 0.9525)
			(end -0.4318 -0.9525)
			(stroke
				(width 0)
				(type default)
			)
			(fill no)
			(layer "B.Fab")
		)
		(pad "1" smd custom
			(at 0 -0.4445 90)
			(size 0.1524 0.1524)
			(layers "B.Cu" "B.Mask" "B.Paste")
			(net "GB_VDDH")
			(options
				(clearance outline)
				(anchor circle)
			)
			(primitives
				(gr_poly
					(pts
						(arc
							(start 0.3048 0.2032)
							(mid 0.275042 0.275042)
							(end 0.2032 0.3048)
						)
						(arc
							(start -0.2032 0.3048)
							(mid -0.275042 0.275042)
							(end -0.3048 0.2032)
						)
						(arc
							(start -0.3048 -0.2032)
							(mid -0.275042 -0.275042)
							(end -0.2032 -0.3048)
						)
						(arc
							(start 0.2032 -0.3048)
							(mid 0.275042 -0.275042)
							(end 0.3048 -0.2032)
						)
					)
					(width 0)
					(fill yes)
				)
			)
		)
		(pad "2" smd custom
			(at 0 0.4445 90)
			(size 0.1524 0.1524)
			(layers "B.Cu" "B.Mask" "B.Paste")
			(net "GND")
			(options
				(clearance outline)
				(anchor circle)
			)
			(primitives
				(gr_poly
					(pts
						(arc
							(start 0.3048 0.2032)
							(mid 0.275042 0.275042)
							(end 0.2032 0.3048)
						)
						(arc
							(start -0.2032 0.3048)
							(mid -0.275042 0.275042)
							(end -0.3048 0.2032)
						)
						(arc
							(start -0.3048 -0.2032)
							(mid -0.275042 -0.275042)
							(end -0.2032 -0.3048)
						)
						(arc
							(start 0.2032 -0.3048)
							(mid 0.275042 -0.275042)
							(end 0.3048 -0.2032)
						)
					)
					(width 0)
					(fill yes)
				)
			)
		)
	)
	(footprint ""
		(layer "B.Cu")
		(at 96.497394 -51.763168 90)
		(property "Reference" "C91"
			(at 0 0 90)
			(layer "B.SilkS")
			(hide yes)
			(effects
				(font
					(size 1.27 1.27)
				)
				(justify mirror)
			)
		)
		(property "Value" "SCD01U16V1KX-GP"
			(at 2.8321 -1.7399 90)
			(unlocked yes)
			(layer "B.Fab")
			(hide yes)
			(effects
				(font
					(size 1.016 1.016)
					(thickness 0.1524)
				)
				(justify mirror)
			)
		)
		(property "Device Type" "C0201H13"
			(at 2.8321 -3.2639 90)
			(unlocked yes)
			(layer "B.Fab")
			(hide yes)
			(effects
				(font
					(size 1.016 1.016)
					(thickness 0.1524)
				)
				(justify mirror)
			)
		)
		(duplicate_pad_numbers_are_jumpers no)
		(fp_rect
			(start 0.2794 0.6477)
			(end -0.2794 -0.6477)
			(stroke
				(width 0)
				(type default)
			)
			(fill no)
			(layer "B.CrtYd")
		)
		(fp_rect
			(start 0.2794 0.6477)
			(end -0.2794 -0.6477)
			(stroke
				(width 0)
				(type default)
			)
			(fill no)
			(layer "B.Fab")
		)
		(pad "1" smd custom
			(at 0 -0.2794 270)
			(size 0.0762 0.0762)
			(layers "B.Cu" "B.Mask" "B.Paste")
			(net "PHY_DPB_TO_SCC_14_DP")
			(options
				(clearance outline)
				(anchor circle)
			)
			(primitives
				(gr_poly
					(pts
						(arc
							(start 0.1524 0.127)
							(mid 0.137521 0.162921)
							(end 0.1016 0.1778)
						)
						(arc
							(start -0.1016 0.1778)
							(mid -0.137521 0.162921)
							(end -0.1524 0.127)
						)
						(arc
							(start -0.1524 -0.127)
							(mid -0.137521 -0.162921)
							(end -0.1016 -0.1778)
						)
						(arc
							(start 0.1016 -0.1778)
							(mid 0.137521 -0.162921)
							(end 0.1524 -0.127)
						)
					)
					(width 0)
					(fill yes)
				)
			)
		)
		(pad "2" smd custom
			(at 0 0.2794 270)
			(size 0.0762 0.0762)
			(layers "B.Cu" "B.Mask" "B.Paste")
			(net "PHY_DPB_TO_SCC_C_14_DP")
			(options
				(clearance outline)
				(anchor circle)
			)
			(primitives
				(gr_poly
					(pts
						(arc
							(start 0.1524 0.127)
							(mid 0.137521 0.162921)
							(end 0.1016 0.1778)
						)
						(arc
							(start -0.1016 0.1778)
							(mid -0.137521 0.162921)
							(end -0.1524 0.127)
						)
						(arc
							(start -0.1524 -0.127)
							(mid -0.137521 -0.162921)
							(end -0.1016 -0.1778)
						)
						(arc
							(start 0.1016 -0.1778)
							(mid 0.137521 -0.162921)
							(end 0.1524 -0.127)
						)
					)
					(width 0)
					(fill yes)
				)
			)
		)
	)
	(footprint ""
		(layer "B.Cu")
		(at 120.52808 -72.263)
		(property "Reference" "C124"
			(at 0 0 0)
			(layer "B.SilkS")
			(hide yes)
			(effects
				(font
					(size 1.27 1.27)
				)
				(justify mirror)
			)
		)
		(property "Value" "SC1KP25V1KX-GP"
			(at 2.8321 -1.7399 0)
			(unlocked yes)
			(layer "B.Fab")
			(hide yes)
			(effects
				(font
					(size 1.016 1.016)
					(thickness 0.1524)
				)
				(justify mirror)
			)
		)
		(property "Device Type" "C0201H13"
			(at 2.8321 -3.2639 0)
			(unlocked yes)
			(layer "B.Fab")
			(hide yes)
			(effects
				(font
					(size 1.016 1.016)
					(thickness 0.1524)
				)
				(justify mirror)
			)
		)
		(duplicate_pad_numbers_are_jumpers no)
		(fp_rect
			(start 0.2794 0.6477)
			(end -0.2794 -0.6477)
			(stroke
				(width 0)
				(type default)
			)
			(fill no)
			(layer "B.CrtYd")
		)
		(fp_rect
			(start 0.2794 0.6477)
			(end -0.2794 -0.6477)
			(stroke
				(width 0)
				(type default)
			)
			(fill no)
			(layer "B.Fab")
		)
		(pad "1" smd custom
			(at 0 -0.2794 180)
			(size 0.0762 0.0762)
			(layers "B.Cu" "B.Mask" "B.Paste")
			(net "P1V8_E")
			(options
				(clearance outline)
				(anchor circle)
			)
			(primitives
				(gr_poly
					(pts
						(arc
							(start 0.1524 0.127)
							(mid 0.137521 0.162921)
							(end 0.1016 0.1778)
						)
						(arc
							(start -0.1016 0.1778)
							(mid -0.137521 0.162921)
							(end -0.1524 0.127)
						)
						(arc
							(start -0.1524 -0.127)
							(mid -0.137521 -0.162921)
							(end -0.1016 -0.1778)
						)
						(arc
							(start 0.1016 -0.1778)
							(mid 0.137521 -0.162921)
							(end 0.1524 -0.127)
						)
					)
					(width 0)
					(fill yes)
				)
			)
		)
		(pad "2" smd custom
			(at 0 0.2794 180)
			(size 0.0762 0.0762)
			(layers "B.Cu" "B.Mask" "B.Paste")
			(net "GND")
			(options
				(clearance outline)
				(anchor circle)
			)
			(primitives
				(gr_poly
					(pts
						(arc
							(start 0.1524 0.127)
							(mid 0.137521 0.162921)
							(end 0.1016 0.1778)
						)
						(arc
							(start -0.1016 0.1778)
							(mid -0.137521 0.162921)
							(end -0.1524 0.127)
						)
						(arc
							(start -0.1524 -0.127)
							(mid -0.137521 -0.162921)
							(end -0.1016 -0.1778)
						)
						(arc
							(start 0.1016 -0.1778)
							(mid 0.137521 -0.162921)
							(end 0.1524 -0.127)
						)
					)
					(width 0)
					(fill yes)
				)
			)
		)
	)
	(footprint ""
		(layer "B.Cu")
		(at 179.430934 -40.289226 90)
		(property "Reference" "C440"
			(at 0 0 90)
			(layer "B.SilkS")
			(hide yes)
			(effects
				(font
					(size 1.27 1.27)
				)
				(justify mirror)
			)
		)
		(property "Value" "SCD1U6D3V1KX-GP"
			(at 2.8321 -1.7399 90)
			(unlocked yes)
			(layer "B.Fab")
			(hide yes)
			(effects
				(font
					(size 1.016 1.016)
					(thickness 0.1524)
				)
				(justify mirror)
			)
		)
		(property "Device Type" "C0201H13"
			(at 2.8321 -3.2639 90)
			(unlocked yes)
			(layer "B.Fab")
			(hide yes)
			(effects
				(font
					(size 1.016 1.016)
					(thickness 0.1524)
				)
				(justify mirror)
			)
		)
		(duplicate_pad_numbers_are_jumpers no)
		(fp_rect
			(start 0.2794 0.6477)
			(end -0.2794 -0.6477)
			(stroke
				(width 0)
				(type default)
			)
			(fill no)
			(layer "B.CrtYd")
		)
		(fp_rect
			(start 0.2794 0.6477)
			(end -0.2794 -0.6477)
			(stroke
				(width 0)
				(type default)
			)
			(fill no)
			(layer "B.Fab")
		)
		(pad "1" smd custom
			(at 0 -0.2794 270)
			(size 0.0762 0.0762)
			(layers "B.Cu" "B.Mask" "B.Paste")
			(net "P0V975")
			(options
				(clearance outline)
				(anchor circle)
			)
			(primitives
				(gr_poly
					(pts
						(arc
							(start 0.1524 0.127)
							(mid 0.137521 0.162921)
							(end 0.1016 0.1778)
						)
						(arc
							(start -0.1016 0.1778)
							(mid -0.137521 0.162921)
							(end -0.1524 0.127)
						)
						(arc
							(start -0.1524 -0.127)
							(mid -0.137521 -0.162921)
							(end -0.1016 -0.1778)
						)
						(arc
							(start 0.1016 -0.1778)
							(mid 0.137521 -0.162921)
							(end 0.1524 -0.127)
						)
					)
					(width 0)
					(fill yes)
				)
			)
		)
		(pad "2" smd custom
			(at 0 0.2794 270)
			(size 0.0762 0.0762)
			(layers "B.Cu" "B.Mask" "B.Paste")
			(net "GND")
			(options
				(clearance outline)
				(anchor circle)
			)
			(primitives
				(gr_poly
					(pts
						(arc
							(start 0.1524 0.127)
							(mid 0.137521 0.162921)
							(end 0.1016 0.1778)
						)
						(arc
							(start -0.1016 0.1778)
							(mid -0.137521 0.162921)
							(end -0.1524 0.127)
						)
						(arc
							(start -0.1524 -0.127)
							(mid -0.137521 -0.162921)
							(end -0.1016 -0.1778)
						)
						(arc
							(start 0.1016 -0.1778)
							(mid 0.137521 -0.162921)
							(end 0.1524 -0.127)
						)
					)
					(width 0)
					(fill yes)
				)
			)
		)
	)
	(footprint ""
		(layer "B.Cu")
		(at 116.5098 -70.3834 180)
		(property "Reference" "C173"
			(at 0 0 0)
			(layer "B.SilkS")
			(hide yes)
			(effects
				(font
					(size 1.27 1.27)
				)
				(justify mirror)
			)
		)
		(property "Value" "SCD1U6D3V1KX-GP"
			(at 2.8321 -1.7399 180)
			(unlocked yes)
			(layer "B.Fab")
			(hide yes)
			(effects
				(font
					(size 1.016 1.016)
					(thickness 0.1524)
				)
				(justify mirror)
			)
		)
		(property "Device Type" "C0201H13"
			(at 2.8321 -3.2639 180)
			(unlocked yes)
			(layer "B.Fab")
			(hide yes)
			(effects
				(font
					(size 1.016 1.016)
					(thickness 0.1524)
				)
				(justify mirror)
			)
		)
		(duplicate_pad_numbers_are_jumpers no)
		(fp_rect
			(start 0.2794 0.6477)
			(end -0.2794 -0.6477)
			(stroke
				(width 0)
				(type default)
			)
			(fill no)
			(layer "B.CrtYd")
		)
		(fp_rect
			(start 0.2794 0.6477)
			(end -0.2794 -0.6477)
			(stroke
				(width 0)
				(type default)
			)
			(fill no)
			(layer "B.Fab")
		)
		(pad "1" smd custom
			(at 0 -0.2794)
			(size 0.0762 0.0762)
			(layers "B.Cu" "B.Mask" "B.Paste")
			(net "P0V9")
			(options
				(clearance outline)
				(anchor circle)
			)
			(primitives
				(gr_poly
					(pts
						(arc
							(start 0.1524 0.127)
							(mid 0.137521 0.162921)
							(end 0.1016 0.1778)
						)
						(arc
							(start -0.1016 0.1778)
							(mid -0.137521 0.162921)
							(end -0.1524 0.127)
						)
						(arc
							(start -0.1524 -0.127)
							(mid -0.137521 -0.162921)
							(end -0.1016 -0.1778)
						)
						(arc
							(start 0.1016 -0.1778)
							(mid 0.137521 -0.162921)
							(end 0.1524 -0.127)
						)
					)
					(width 0)
					(fill yes)
				)
			)
		)
		(pad "2" smd custom
			(at 0 0.2794)
			(size 0.0762 0.0762)
			(layers "B.Cu" "B.Mask" "B.Paste")
			(net "GND")
			(options
				(clearance outline)
				(anchor circle)
			)
			(primitives
				(gr_poly
					(pts
						(arc
							(start 0.1524 0.127)
							(mid 0.137521 0.162921)
							(end 0.1016 0.1778)
						)
						(arc
							(start -0.1016 0.1778)
							(mid -0.137521 0.162921)
							(end -0.1524 0.127)
						)
						(arc
							(start -0.1524 -0.127)
							(mid -0.137521 -0.162921)
							(end -0.1016 -0.1778)
						)
						(arc
							(start 0.1016 -0.1778)
							(mid 0.137521 -0.162921)
							(end 0.1524 -0.127)
						)
					)
					(width 0)
					(fill yes)
				)
			)
		)
	)
	(footprint ""
		(layer "B.Cu")
		(at 133.5913 -120.904 -90)
		(property "Reference" "R602"
			(at 0 0 90)
			(layer "B.SilkS")
			(hide yes)
			(effects
				(font
					(size 1.27 1.27)
				)
				(justify mirror)
			)
		)
		(property "Value" "4K7R2F-GP"
			(at -0.064008 -3.993896 270)
			(unlocked yes)
			(layer "B.Fab")
			(hide yes)
			(effects
				(font
					(size 1.016 1.016)
					(thickness 0.1524)
				)
				(justify mirror)
			)
		)
		(property "Device Type" "R402H16"
			(at -0.064008 -5.517896 270)
			(unlocked yes)
			(layer "B.Fab")
			(hide yes)
			(effects
				(font
					(size 1.016 1.016)
					(thickness 0.1524)
				)
				(justify mirror)
			)
		)
		(duplicate_pad_numbers_are_jumpers no)
		(fp_line
			(start -0.508 -0.9398)
			(end 0.508 -0.9398)
			(stroke
				(width 0.1524)
				(type default)
			)
			(layer "B.SilkS")
		)
		(fp_line
			(start 0.508 -0.9398)
			(end 0.508 0.9398)
			(stroke
				(width 0.1524)
				(type default)
			)
			(layer "B.SilkS")
		)
		(fp_rect
			(start 0.508 0.9398)
			(end -0.508 -0.9398)
			(stroke
				(width 0)
				(type default)
			)
			(fill no)
			(layer "B.CrtYd")
		)
		(fp_rect
			(start 0.508 0.9398)
			(end -0.508 -0.9398)
			(stroke
				(width 0)
				(type default)
			)
			(fill no)
			(layer "B.Fab")
		)
		(pad "1" smd custom
			(at 0 -0.4445 90)
			(size 0.1397 0.1397)
			(layers "B.Cu" "B.Mask" "B.Paste")
			(net "P1V5_C_G")
			(options
				(clearance outline)
				(anchor circle)
			)
			(primitives
				(gr_poly
					(pts
						(arc
							(start -0.1778 0.2794)
							(mid -0.249642 0.249642)
							(end -0.2794 0.1778)
						)
						(arc
							(start -0.2794 -0.1778)
							(mid -0.249642 -0.249642)
							(end -0.1778 -0.2794)
						)
						(arc
							(start 0.1778 -0.2794)
							(mid 0.249642 -0.249642)
							(end 0.2794 -0.1778)
						)
						(arc
							(start 0.2794 0.1778)
							(mid 0.249642 0.249642)
							(end 0.1778 0.2794)
						)
					)
					(width 0)
					(fill yes)
				)
			)
		)
		(pad "2" smd custom
			(at 0 0.4445 90)
			(size 0.1397 0.1397)
			(layers "B.Cu" "B.Mask" "B.Paste")
			(net "P1V5_C")
			(options
				(clearance outline)
				(anchor circle)
			)
			(primitives
				(gr_poly
					(pts
						(arc
							(start -0.1778 0.2794)
							(mid -0.249642 0.249642)
							(end -0.2794 0.1778)
						)
						(arc
							(start -0.2794 -0.1778)
							(mid -0.249642 -0.249642)
							(end -0.1778 -0.2794)
						)
						(arc
							(start 0.1778 -0.2794)
							(mid 0.249642 -0.249642)
							(end 0.2794 -0.1778)
						)
						(arc
							(start 0.2794 0.1778)
							(mid 0.249642 0.249642)
							(end 0.1778 0.2794)
						)
					)
					(width 0)
					(fill yes)
				)
			)
		)
	)
	(footprint ""
		(layer "B.Cu")
		(at 115.40236 -59.4487)
		(property "Reference" "C584"
			(at 0 0 0)
			(layer "B.SilkS")
			(hide yes)
			(effects
				(font
					(size 1.27 1.27)
				)
				(justify mirror)
			)
		)
		(property "Value" "SCD1U6D3V1KX-GP"
			(at 2.8321 -1.7399 0)
			(unlocked yes)
			(layer "B.Fab")
			(hide yes)
			(effects
				(font
					(size 1.016 1.016)
					(thickness 0.1524)
				)
				(justify mirror)
			)
		)
		(property "Device Type" "C0201H13"
			(at 2.8321 -3.2639 0)
			(unlocked yes)
			(layer "B.Fab")
			(hide yes)
			(effects
				(font
					(size 1.016 1.016)
					(thickness 0.1524)
				)
				(justify mirror)
			)
		)
		(duplicate_pad_numbers_are_jumpers no)
		(fp_rect
			(start 0.2794 0.6477)
			(end -0.2794 -0.6477)
			(stroke
				(width 0)
				(type default)
			)
			(fill no)
			(layer "B.CrtYd")
		)
		(fp_rect
			(start 0.2794 0.6477)
			(end -0.2794 -0.6477)
			(stroke
				(width 0)
				(type default)
			)
			(fill no)
			(layer "B.Fab")
		)
		(pad "1" smd custom
			(at 0 -0.2794 180)
			(size 0.0762 0.0762)
			(layers "B.Cu" "B.Mask" "B.Paste")
			(net "GB_VDDA")
			(options
				(clearance outline)
				(anchor circle)
			)
			(primitives
				(gr_poly
					(pts
						(arc
							(start 0.1524 0.127)
							(mid 0.137521 0.162921)
							(end 0.1016 0.1778)
						)
						(arc
							(start -0.1016 0.1778)
							(mid -0.137521 0.162921)
							(end -0.1524 0.127)
						)
						(arc
							(start -0.1524 -0.127)
							(mid -0.137521 -0.162921)
							(end -0.1016 -0.1778)
						)
						(arc
							(start 0.1016 -0.1778)
							(mid 0.137521 -0.162921)
							(end 0.1524 -0.127)
						)
					)
					(width 0)
					(fill yes)
				)
			)
		)
		(pad "2" smd custom
			(at 0 0.2794 180)
			(size 0.0762 0.0762)
			(layers "B.Cu" "B.Mask" "B.Paste")
			(net "GND")
			(options
				(clearance outline)
				(anchor circle)
			)
			(primitives
				(gr_poly
					(pts
						(arc
							(start 0.1524 0.127)
							(mid 0.137521 0.162921)
							(end 0.1016 0.1778)
						)
						(arc
							(start -0.1016 0.1778)
							(mid -0.137521 0.162921)
							(end -0.1524 0.127)
						)
						(arc
							(start -0.1524 -0.127)
							(mid -0.137521 -0.162921)
							(end -0.1016 -0.1778)
						)
						(arc
							(start 0.1016 -0.1778)
							(mid 0.137521 -0.162921)
							(end 0.1524 -0.127)
						)
					)
					(width 0)
					(fill yes)
				)
			)
		)
	)
	(footprint ""
		(layer "B.Cu")
		(at 177.771806 -43.139868 90)
		(property "Reference" "C450"
			(at 0 0 90)
			(layer "B.SilkS")
			(hide yes)
			(effects
				(font
					(size 1.27 1.27)
				)
				(justify mirror)
			)
		)
		(property "Value" "SC1KP50V2KX-1GP"
			(at -1.1811 -2.7051 90)
			(unlocked yes)
			(layer "B.Fab")
			(hide yes)
			(effects
				(font
					(size 1.016 1.016)
					(thickness 0.1524)
				)
				(justify mirror)
			)
		)
		(property "Device Type" "C402H22"
			(at -1.1811 -4.2291 90)
			(unlocked yes)
			(layer "B.Fab")
			(hide yes)
			(effects
				(font
					(size 1.016 1.016)
					(thickness 0.1524)
				)
				(justify mirror)
			)
		)
		(duplicate_pad_numbers_are_jumpers no)
		(fp_rect
			(start 0.4318 0.9525)
			(end -0.4318 -0.9525)
			(stroke
				(width 0)
				(type default)
			)
			(fill no)
			(layer "B.CrtYd")
		)
		(fp_rect
			(start 0.4318 0.9525)
			(end -0.4318 -0.9525)
			(stroke
				(width 0)
				(type default)
			)
			(fill no)
			(layer "B.Fab")
		)
		(pad "1" smd custom
			(at 0 -0.4445 270)
			(size 0.1524 0.1524)
			(layers "B.Cu" "B.Mask" "B.Paste")
			(net "P0V975")
			(options
				(clearance outline)
				(anchor circle)
			)
			(primitives
				(gr_poly
					(pts
						(arc
							(start 0.3048 0.2032)
							(mid 0.275042 0.275042)
							(end 0.2032 0.3048)
						)
						(arc
							(start -0.2032 0.3048)
							(mid -0.275042 0.275042)
							(end -0.3048 0.2032)
						)
						(arc
							(start -0.3048 -0.2032)
							(mid -0.275042 -0.275042)
							(end -0.2032 -0.3048)
						)
						(arc
							(start 0.2032 -0.3048)
							(mid 0.275042 -0.275042)
							(end 0.3048 -0.2032)
						)
					)
					(width 0)
					(fill yes)
				)
			)
		)
		(pad "2" smd custom
			(at 0 0.4445 270)
			(size 0.1524 0.1524)
			(layers "B.Cu" "B.Mask" "B.Paste")
			(net "GND")
			(options
				(clearance outline)
				(anchor circle)
			)
			(primitives
				(gr_poly
					(pts
						(arc
							(start 0.3048 0.2032)
							(mid 0.275042 0.275042)
							(end 0.2032 0.3048)
						)
						(arc
							(start -0.2032 0.3048)
							(mid -0.275042 0.275042)
							(end -0.3048 0.2032)
						)
						(arc
							(start -0.3048 -0.2032)
							(mid -0.275042 -0.275042)
							(end -0.2032 -0.3048)
						)
						(arc
							(start 0.2032 -0.3048)
							(mid 0.275042 -0.275042)
							(end 0.3048 -0.2032)
						)
					)
					(width 0)
					(fill yes)
				)
			)
		)
	)
	(footprint ""
		(layer "B.Cu")
		(at 110.6424 -57.4802)
		(property "Reference" "C580"
			(at 0 0 0)
			(layer "B.SilkS")
			(hide yes)
			(effects
				(font
					(size 1.27 1.27)
				)
				(justify mirror)
			)
		)
		(property "Value" "SCD1U6D3V1KX-GP"
			(at 2.8321 -1.7399 0)
			(unlocked yes)
			(layer "B.Fab")
			(hide yes)
			(effects
				(font
					(size 1.016 1.016)
					(thickness 0.1524)
				)
				(justify mirror)
			)
		)
		(property "Device Type" "C0201H13"
			(at 2.8321 -3.2639 0)
			(unlocked yes)
			(layer "B.Fab")
			(hide yes)
			(effects
				(font
					(size 1.016 1.016)
					(thickness 0.1524)
				)
				(justify mirror)
			)
		)
		(duplicate_pad_numbers_are_jumpers no)
		(fp_rect
			(start 0.2794 0.6477)
			(end -0.2794 -0.6477)
			(stroke
				(width 0)
				(type default)
			)
			(fill no)
			(layer "B.CrtYd")
		)
		(fp_rect
			(start 0.2794 0.6477)
			(end -0.2794 -0.6477)
			(stroke
				(width 0)
				(type default)
			)
			(fill no)
			(layer "B.Fab")
		)
		(pad "1" smd custom
			(at 0 -0.2794 180)
			(size 0.0762 0.0762)
			(layers "B.Cu" "B.Mask" "B.Paste")
			(net "GB_VDDA")
			(options
				(clearance outline)
				(anchor circle)
			)
			(primitives
				(gr_poly
					(pts
						(arc
							(start 0.1524 0.127)
							(mid 0.137521 0.162921)
							(end 0.1016 0.1778)
						)
						(arc
							(start -0.1016 0.1778)
							(mid -0.137521 0.162921)
							(end -0.1524 0.127)
						)
						(arc
							(start -0.1524 -0.127)
							(mid -0.137521 -0.162921)
							(end -0.1016 -0.1778)
						)
						(arc
							(start 0.1016 -0.1778)
							(mid 0.137521 -0.162921)
							(end 0.1524 -0.127)
						)
					)
					(width 0)
					(fill yes)
				)
			)
		)
		(pad "2" smd custom
			(at 0 0.2794 180)
			(size 0.0762 0.0762)
			(layers "B.Cu" "B.Mask" "B.Paste")
			(net "GND")
			(options
				(clearance outline)
				(anchor circle)
			)
			(primitives
				(gr_poly
					(pts
						(arc
							(start 0.1524 0.127)
							(mid 0.137521 0.162921)
							(end 0.1016 0.1778)
						)
						(arc
							(start -0.1016 0.1778)
							(mid -0.137521 0.162921)
							(end -0.1524 0.127)
						)
						(arc
							(start -0.1524 -0.127)
							(mid -0.137521 -0.162921)
							(end -0.1016 -0.1778)
						)
						(arc
							(start 0.1016 -0.1778)
							(mid 0.137521 -0.162921)
							(end 0.1524 -0.127)
						)
					)
					(width 0)
					(fill yes)
				)
			)
		)
	)
	(footprint ""
		(layer "B.Cu")
		(at 193.25336 -19.76374 90)
		(property "Reference" "R243"
			(at 0 0 90)
			(layer "B.SilkS")
			(hide yes)
			(effects
				(font
					(size 1.27 1.27)
				)
				(justify mirror)
			)
		)
		(property "Value" "0R2J-2-GP"
			(at -0.064008 -3.993896 90)
			(unlocked yes)
			(layer "B.Fab")
			(hide yes)
			(effects
				(font
					(size 1.016 1.016)
					(thickness 0.1524)
				)
				(justify mirror)
			)
		)
		(property "Device Type" "R402H16"
			(at -0.064008 -5.517896 90)
			(unlocked yes)
			(layer "B.Fab")
			(hide yes)
			(effects
				(font
					(size 1.016 1.016)
					(thickness 0.1524)
				)
				(justify mirror)
			)
		)
		(duplicate_pad_numbers_are_jumpers no)
		(fp_line
			(start 0.508 -0.9398)
			(end 0.508 0.9398)
			(stroke
				(width 0.1524)
				(type default)
			)
			(layer "B.SilkS")
		)
		(fp_line
			(start -0.508 -0.9398)
			(end 0.508 -0.9398)
			(stroke
				(width 0.1524)
				(type default)
			)
			(layer "B.SilkS")
		)
		(fp_rect
			(start 0.508 0.9398)
			(end -0.508 -0.9398)
			(stroke
				(width 0)
				(type default)
			)
			(fill no)
			(layer "B.CrtYd")
		)
		(fp_rect
			(start 0.508 0.9398)
			(end -0.508 -0.9398)
			(stroke
				(width 0)
				(type default)
			)
			(fill no)
			(layer "B.Fab")
		)
		(pad "1" smd custom
			(at 0 -0.4445 270)
			(size 0.1397 0.1397)
			(layers "B.Cu" "B.Mask" "B.Paste")
			(net "PCIE_RST_N")
			(options
				(clearance outline)
				(anchor circle)
			)
			(primitives
				(gr_poly
					(pts
						(arc
							(start -0.1778 0.2794)
							(mid -0.249642 0.249642)
							(end -0.2794 0.1778)
						)
						(arc
							(start -0.2794 -0.1778)
							(mid -0.249642 -0.249642)
							(end -0.1778 -0.2794)
						)
						(arc
							(start 0.1778 -0.2794)
							(mid 0.249642 -0.249642)
							(end 0.2794 -0.1778)
						)
						(arc
							(start 0.2794 0.1778)
							(mid 0.249642 0.249642)
							(end 0.1778 0.2794)
						)
					)
					(width 0)
					(fill yes)
				)
			)
		)
		(pad "2" smd custom
			(at 0 0.4445 270)
			(size 0.1397 0.1397)
			(layers "B.Cu" "B.Mask" "B.Paste")
			(net "SYS_RST")
			(options
				(clearance outline)
				(anchor circle)
			)
			(primitives
				(gr_poly
					(pts
						(arc
							(start -0.1778 0.2794)
							(mid -0.249642 0.249642)
							(end -0.2794 0.1778)
						)
						(arc
							(start -0.2794 -0.1778)
							(mid -0.249642 -0.249642)
							(end -0.1778 -0.2794)
						)
						(arc
							(start 0.1778 -0.2794)
							(mid 0.249642 -0.249642)
							(end 0.2794 -0.1778)
						)
						(arc
							(start 0.2794 0.1778)
							(mid 0.249642 0.249642)
							(end 0.1778 0.2794)
						)
					)
					(width 0)
					(fill yes)
				)
			)
		)
	)
	(footprint ""
		(layer "B.Cu")
		(at 125.5776 -39.4716 180)
		(property "Reference" "C51"
			(at 0 0 0)
			(layer "B.SilkS")
			(hide yes)
			(effects
				(font
					(size 1.27 1.27)
				)
				(justify mirror)
			)
		)
		(property "Value" "SCD01U16V1KX-GP"
			(at 2.8321 -1.7399 180)
			(unlocked yes)
			(layer "B.Fab")
			(hide yes)
			(effects
				(font
					(size 1.016 1.016)
					(thickness 0.1524)
				)
				(justify mirror)
			)
		)
		(property "Device Type" "C0201H13"
			(at 2.8321 -3.2639 180)
			(unlocked yes)
			(layer "B.Fab")
			(hide yes)
			(effects
				(font
					(size 1.016 1.016)
					(thickness 0.1524)
				)
				(justify mirror)
			)
		)
		(duplicate_pad_numbers_are_jumpers no)
		(fp_rect
			(start 0.2794 0.6477)
			(end -0.2794 -0.6477)
			(stroke
				(width 0)
				(type default)
			)
			(fill no)
			(layer "B.CrtYd")
		)
		(fp_rect
			(start 0.2794 0.6477)
			(end -0.2794 -0.6477)
			(stroke
				(width 0)
				(type default)
			)
			(fill no)
			(layer "B.Fab")
		)
		(pad "1" smd custom
			(at 0 -0.2794)
			(size 0.0762 0.0762)
			(layers "B.Cu" "B.Mask" "B.Paste")
			(net "PHY_DPB_TO_SCC_38_DP")
			(options
				(clearance outline)
				(anchor circle)
			)
			(primitives
				(gr_poly
					(pts
						(arc
							(start 0.1524 0.127)
							(mid 0.137521 0.162921)
							(end 0.1016 0.1778)
						)
						(arc
							(start -0.1016 0.1778)
							(mid -0.137521 0.162921)
							(end -0.1524 0.127)
						)
						(arc
							(start -0.1524 -0.127)
							(mid -0.137521 -0.162921)
							(end -0.1016 -0.1778)
						)
						(arc
							(start 0.1016 -0.1778)
							(mid 0.137521 -0.162921)
							(end 0.1524 -0.127)
						)
					)
					(width 0)
					(fill yes)
				)
			)
		)
		(pad "2" smd custom
			(at 0 0.2794)
			(size 0.0762 0.0762)
			(layers "B.Cu" "B.Mask" "B.Paste")
			(net "PHY_DPB_TO_SCC_C_38_DP")
			(options
				(clearance outline)
				(anchor circle)
			)
			(primitives
				(gr_poly
					(pts
						(arc
							(start 0.1524 0.127)
							(mid 0.137521 0.162921)
							(end 0.1016 0.1778)
						)
						(arc
							(start -0.1016 0.1778)
							(mid -0.137521 0.162921)
							(end -0.1524 0.127)
						)
						(arc
							(start -0.1524 -0.127)
							(mid -0.137521 -0.162921)
							(end -0.1016 -0.1778)
						)
						(arc
							(start 0.1016 -0.1778)
							(mid 0.137521 -0.162921)
							(end 0.1524 -0.127)
						)
					)
					(width 0)
					(fill yes)
				)
			)
		)
	)
	(footprint ""
		(layer "B.Cu")
		(at 166.906702 -50.39741)
		(property "Reference" "TP126"
			(at 0 0 0)
			(layer "B.SilkS")
			(hide yes)
			(effects
				(font
					(size 1.27 1.27)
				)
				(justify mirror)
			)
		)
		(property "Value" "TPAD28-2-GP"
			(at 0.0127 -1.6637 0)
			(unlocked yes)
			(layer "B.Fab")
			(hide yes)
			(effects
				(font
					(size 1.016 1.016)
					(thickness 0.1524)
				)
				(justify mirror)
			)
		)
		(property "Device Type" "TPAD28"
			(at 0.0127 -3.1877 0)
			(unlocked yes)
			(layer "B.Fab")
			(hide yes)
			(effects
				(font
					(size 1.016 1.016)
					(thickness 0.1524)
				)
				(justify mirror)
			)
		)
		(duplicate_pad_numbers_are_jumpers no)
		(fp_poly
			(pts
				(arc
					(start 0.3556 0)
					(mid -0.3556 0)
					(end 0.3556 0)
				)
			)
			(stroke
				(width 0)
				(type default)
			)
			(fill no)
			(layer "B.CrtYd")
		)
		(fp_poly
			(pts
				(arc
					(start 0.6096 0)
					(mid -0.6096 0)
					(end 0.6096 0)
				)
			)
			(stroke
				(width 0)
				(type default)
			)
			(fill no)
			(layer "B.Fab")
		)
		(pad "1" smd circle
			(at 0 0 180)
			(size 0.7112 0.7112)
			(layers "B.Cu" "B.Mask" "B.Paste")
			(net "ICE1_TDI")
		)
	)
	(footprint ""
		(layer "B.Cu")
		(at 170.721274 -97.760282)
		(property "Reference" "R496"
			(at 0 0 0)
			(layer "B.SilkS")
			(hide yes)
			(effects
				(font
					(size 1.27 1.27)
				)
				(justify mirror)
			)
		)
		(property "Value" "100KR2F-L1-GP"
			(at -0.064008 -3.993896 0)
			(unlocked yes)
			(layer "B.Fab")
			(hide yes)
			(effects
				(font
					(size 1.016 1.016)
					(thickness 0.1524)
				)
				(justify mirror)
			)
		)
		(property "Device Type" "R402H16"
			(at -0.064008 -5.517896 0)
			(unlocked yes)
			(layer "B.Fab")
			(hide yes)
			(effects
				(font
					(size 1.016 1.016)
					(thickness 0.1524)
				)
				(justify mirror)
			)
		)
		(duplicate_pad_numbers_are_jumpers no)
		(fp_line
			(start -0.508 -0.9398)
			(end 0.508 -0.9398)
			(stroke
				(width 0.1524)
				(type default)
			)
			(layer "B.SilkS")
		)
		(fp_line
			(start 0.508 -0.9398)
			(end 0.508 0.9398)
			(stroke
				(width 0.1524)
				(type default)
			)
			(layer "B.SilkS")
		)
		(fp_rect
			(start 0.508 0.9398)
			(end -0.508 -0.9398)
			(stroke
				(width 0)
				(type default)
			)
			(fill no)
			(layer "B.CrtYd")
		)
		(fp_rect
			(start 0.508 0.9398)
			(end -0.508 -0.9398)
			(stroke
				(width 0)
				(type default)
			)
			(fill no)
			(layer "B.Fab")
		)
		(pad "1" smd custom
			(at 0 -0.4445 180)
			(size 0.1397 0.1397)
			(layers "B.Cu" "B.Mask" "B.Paste")
			(net "VT235_VDES")
			(options
				(clearance outline)
				(anchor circle)
			)
			(primitives
				(gr_poly
					(pts
						(arc
							(start -0.1778 0.2794)
							(mid -0.249642 0.249642)
							(end -0.2794 0.1778)
						)
						(arc
							(start -0.2794 -0.1778)
							(mid -0.249642 -0.249642)
							(end -0.1778 -0.2794)
						)
						(arc
							(start 0.1778 -0.2794)
							(mid 0.249642 -0.249642)
							(end 0.2794 -0.1778)
						)
						(arc
							(start 0.2794 0.1778)
							(mid 0.249642 0.249642)
							(end 0.1778 0.2794)
						)
					)
					(width 0)
					(fill yes)
				)
			)
		)
		(pad "2" smd custom
			(at 0 0.4445 180)
			(size 0.1397 0.1397)
			(layers "B.Cu" "B.Mask" "B.Paste")
			(net "AVSO_VREF")
			(options
				(clearance outline)
				(anchor circle)
			)
			(primitives
				(gr_poly
					(pts
						(arc
							(start -0.1778 0.2794)
							(mid -0.249642 0.249642)
							(end -0.2794 0.1778)
						)
						(arc
							(start -0.2794 -0.1778)
							(mid -0.249642 -0.249642)
							(end -0.1778 -0.2794)
						)
						(arc
							(start 0.1778 -0.2794)
							(mid 0.249642 -0.249642)
							(end 0.2794 -0.1778)
						)
						(arc
							(start 0.2794 0.1778)
							(mid 0.249642 0.249642)
							(end 0.1778 0.2794)
						)
					)
					(width 0)
					(fill yes)
				)
			)
		)
	)
	(footprint ""
		(layer "B.Cu")
		(at 109.2962 -72.009)
		(property "Reference" "C148"
			(at 0 0 0)
			(layer "B.SilkS")
			(hide yes)
			(effects
				(font
					(size 1.27 1.27)
				)
				(justify mirror)
			)
		)
		(property "Value" "SCD1U6D3V1KX-GP"
			(at 2.8321 -1.7399 0)
			(unlocked yes)
			(layer "B.Fab")
			(hide yes)
			(effects
				(font
					(size 1.016 1.016)
					(thickness 0.1524)
				)
				(justify mirror)
			)
		)
		(property "Device Type" "C0201H13"
			(at 2.8321 -3.2639 0)
			(unlocked yes)
			(layer "B.Fab")
			(hide yes)
			(effects
				(font
					(size 1.016 1.016)
					(thickness 0.1524)
				)
				(justify mirror)
			)
		)
		(duplicate_pad_numbers_are_jumpers no)
		(fp_rect
			(start 0.2794 0.6477)
			(end -0.2794 -0.6477)
			(stroke
				(width 0)
				(type default)
			)
			(fill no)
			(layer "B.CrtYd")
		)
		(fp_rect
			(start 0.2794 0.6477)
			(end -0.2794 -0.6477)
			(stroke
				(width 0)
				(type default)
			)
			(fill no)
			(layer "B.Fab")
		)
		(pad "1" smd custom
			(at 0 -0.2794 180)
			(size 0.0762 0.0762)
			(layers "B.Cu" "B.Mask" "B.Paste")
			(net "P1V8_E")
			(options
				(clearance outline)
				(anchor circle)
			)
			(primitives
				(gr_poly
					(pts
						(arc
							(start 0.1524 0.127)
							(mid 0.137521 0.162921)
							(end 0.1016 0.1778)
						)
						(arc
							(start -0.1016 0.1778)
							(mid -0.137521 0.162921)
							(end -0.1524 0.127)
						)
						(arc
							(start -0.1524 -0.127)
							(mid -0.137521 -0.162921)
							(end -0.1016 -0.1778)
						)
						(arc
							(start 0.1016 -0.1778)
							(mid 0.137521 -0.162921)
							(end 0.1524 -0.127)
						)
					)
					(width 0)
					(fill yes)
				)
			)
		)
		(pad "2" smd custom
			(at 0 0.2794 180)
			(size 0.0762 0.0762)
			(layers "B.Cu" "B.Mask" "B.Paste")
			(net "GND")
			(options
				(clearance outline)
				(anchor circle)
			)
			(primitives
				(gr_poly
					(pts
						(arc
							(start 0.1524 0.127)
							(mid 0.137521 0.162921)
							(end 0.1016 0.1778)
						)
						(arc
							(start -0.1016 0.1778)
							(mid -0.137521 0.162921)
							(end -0.1524 0.127)
						)
						(arc
							(start -0.1524 -0.127)
							(mid -0.137521 -0.162921)
							(end -0.1016 -0.1778)
						)
						(arc
							(start 0.1016 -0.1778)
							(mid 0.137521 -0.162921)
							(end 0.1524 -0.127)
						)
					)
					(width 0)
					(fill yes)
				)
			)
		)
	)
	(footprint ""
		(layer "B.Cu")
		(at 163.302442 -36.807394 90)
		(property "Reference" "C376"
			(at 0 0 90)
			(layer "B.SilkS")
			(hide yes)
			(effects
				(font
					(size 1.27 1.27)
				)
				(justify mirror)
			)
		)
		(property "Value" "SCD1U16V2KX-3GP"
			(at -1.1811 -2.7051 90)
			(unlocked yes)
			(layer "B.Fab")
			(hide yes)
			(effects
				(font
					(size 1.016 1.016)
					(thickness 0.1524)
				)
				(justify mirror)
			)
		)
		(property "Device Type" "C402H22"
			(at -1.1811 -4.2291 90)
			(unlocked yes)
			(layer "B.Fab")
			(hide yes)
			(effects
				(font
					(size 1.016 1.016)
					(thickness 0.1524)
				)
				(justify mirror)
			)
		)
		(duplicate_pad_numbers_are_jumpers no)
		(fp_rect
			(start 0.4318 0.9525)
			(end -0.4318 -0.9525)
			(stroke
				(width 0)
				(type default)
			)
			(fill no)
			(layer "B.CrtYd")
		)
		(fp_rect
			(start 0.4318 0.9525)
			(end -0.4318 -0.9525)
			(stroke
				(width 0)
				(type default)
			)
			(fill no)
			(layer "B.Fab")
		)
		(pad "1" smd custom
			(at 0 -0.4445 270)
			(size 0.1524 0.1524)
			(layers "B.Cu" "B.Mask" "B.Paste")
			(net "SAS0_VDDH")
			(options
				(clearance outline)
				(anchor circle)
			)
			(primitives
				(gr_poly
					(pts
						(arc
							(start 0.3048 0.2032)
							(mid 0.275042 0.275042)
							(end 0.2032 0.3048)
						)
						(arc
							(start -0.2032 0.3048)
							(mid -0.275042 0.275042)
							(end -0.3048 0.2032)
						)
						(arc
							(start -0.3048 -0.2032)
							(mid -0.275042 -0.275042)
							(end -0.2032 -0.3048)
						)
						(arc
							(start 0.2032 -0.3048)
							(mid 0.275042 -0.275042)
							(end 0.3048 -0.2032)
						)
					)
					(width 0)
					(fill yes)
				)
			)
		)
		(pad "2" smd custom
			(at 0 0.4445 270)
			(size 0.1524 0.1524)
			(layers "B.Cu" "B.Mask" "B.Paste")
			(net "GND")
			(options
				(clearance outline)
				(anchor circle)
			)
			(primitives
				(gr_poly
					(pts
						(arc
							(start 0.3048 0.2032)
							(mid 0.275042 0.275042)
							(end 0.2032 0.3048)
						)
						(arc
							(start -0.2032 0.3048)
							(mid -0.275042 0.275042)
							(end -0.3048 0.2032)
						)
						(arc
							(start -0.3048 -0.2032)
							(mid -0.275042 -0.275042)
							(end -0.2032 -0.3048)
						)
						(arc
							(start 0.2032 -0.3048)
							(mid 0.275042 -0.275042)
							(end 0.3048 -0.2032)
						)
					)
					(width 0)
					(fill yes)
				)
			)
		)
	)
	(footprint ""
		(layer "B.Cu")
		(at 174.216568 -48.194722 -90)
		(property "Reference" "C460"
			(at 0 0 90)
			(layer "B.SilkS")
			(hide yes)
			(effects
				(font
					(size 1.27 1.27)
				)
				(justify mirror)
			)
		)
		(property "Value" "SCD1U6D3V1KX-GP"
			(at 2.8321 -1.7399 270)
			(unlocked yes)
			(layer "B.Fab")
			(hide yes)
			(effects
				(font
					(size 1.016 1.016)
					(thickness 0.1524)
				)
				(justify mirror)
			)
		)
		(property "Device Type" "C0201H13"
			(at 2.8321 -3.2639 270)
			(unlocked yes)
			(layer "B.Fab")
			(hide yes)
			(effects
				(font
					(size 1.016 1.016)
					(thickness 0.1524)
				)
				(justify mirror)
			)
		)
		(duplicate_pad_numbers_are_jumpers no)
		(fp_rect
			(start 0.2794 0.6477)
			(end -0.2794 -0.6477)
			(stroke
				(width 0)
				(type default)
			)
			(fill no)
			(layer "B.CrtYd")
		)
		(fp_rect
			(start 0.2794 0.6477)
			(end -0.2794 -0.6477)
			(stroke
				(width 0)
				(type default)
			)
			(fill no)
			(layer "B.Fab")
		)
		(pad "1" smd custom
			(at 0 -0.2794 90)
			(size 0.0762 0.0762)
			(layers "B.Cu" "B.Mask" "B.Paste")
			(net "P1V8_C")
			(options
				(clearance outline)
				(anchor circle)
			)
			(primitives
				(gr_poly
					(pts
						(arc
							(start 0.1524 0.127)
							(mid 0.137521 0.162921)
							(end 0.1016 0.1778)
						)
						(arc
							(start -0.1016 0.1778)
							(mid -0.137521 0.162921)
							(end -0.1524 0.127)
						)
						(arc
							(start -0.1524 -0.127)
							(mid -0.137521 -0.162921)
							(end -0.1016 -0.1778)
						)
						(arc
							(start 0.1016 -0.1778)
							(mid 0.137521 -0.162921)
							(end 0.1524 -0.127)
						)
					)
					(width 0)
					(fill yes)
				)
			)
		)
		(pad "2" smd custom
			(at 0 0.2794 90)
			(size 0.0762 0.0762)
			(layers "B.Cu" "B.Mask" "B.Paste")
			(net "GND")
			(options
				(clearance outline)
				(anchor circle)
			)
			(primitives
				(gr_poly
					(pts
						(arc
							(start 0.1524 0.127)
							(mid 0.137521 0.162921)
							(end 0.1016 0.1778)
						)
						(arc
							(start -0.1016 0.1778)
							(mid -0.137521 0.162921)
							(end -0.1524 0.127)
						)
						(arc
							(start -0.1524 -0.127)
							(mid -0.137521 -0.162921)
							(end -0.1016 -0.1778)
						)
						(arc
							(start 0.1016 -0.1778)
							(mid 0.137521 -0.162921)
							(end 0.1524 -0.127)
						)
					)
					(width 0)
					(fill yes)
				)
			)
		)
	)
	(footprint ""
		(layer "B.Cu")
		(at 183.21528 -32.40913)
		(property "Reference" "C459"
			(at 0 0 0)
			(layer "B.SilkS")
			(hide yes)
			(effects
				(font
					(size 1.27 1.27)
				)
				(justify mirror)
			)
		)
		(property "Value" "SCD1U6D3V1KX-GP"
			(at 2.8321 -1.7399 0)
			(unlocked yes)
			(layer "B.Fab")
			(hide yes)
			(effects
				(font
					(size 1.016 1.016)
					(thickness 0.1524)
				)
				(justify mirror)
			)
		)
		(property "Device Type" "C0201H13"
			(at 2.8321 -3.2639 0)
			(unlocked yes)
			(layer "B.Fab")
			(hide yes)
			(effects
				(font
					(size 1.016 1.016)
					(thickness 0.1524)
				)
				(justify mirror)
			)
		)
		(duplicate_pad_numbers_are_jumpers no)
		(fp_rect
			(start 0.2794 0.6477)
			(end -0.2794 -0.6477)
			(stroke
				(width 0)
				(type default)
			)
			(fill no)
			(layer "B.CrtYd")
		)
		(fp_rect
			(start 0.2794 0.6477)
			(end -0.2794 -0.6477)
			(stroke
				(width 0)
				(type default)
			)
			(fill no)
			(layer "B.Fab")
		)
		(pad "1" smd custom
			(at 0 -0.2794 180)
			(size 0.0762 0.0762)
			(layers "B.Cu" "B.Mask" "B.Paste")
			(net "P1V8_C")
			(options
				(clearance outline)
				(anchor circle)
			)
			(primitives
				(gr_poly
					(pts
						(arc
							(start 0.1524 0.127)
							(mid 0.137521 0.162921)
							(end 0.1016 0.1778)
						)
						(arc
							(start -0.1016 0.1778)
							(mid -0.137521 0.162921)
							(end -0.1524 0.127)
						)
						(arc
							(start -0.1524 -0.127)
							(mid -0.137521 -0.162921)
							(end -0.1016 -0.1778)
						)
						(arc
							(start 0.1016 -0.1778)
							(mid 0.137521 -0.162921)
							(end 0.1524 -0.127)
						)
					)
					(width 0)
					(fill yes)
				)
			)
		)
		(pad "2" smd custom
			(at 0 0.2794 180)
			(size 0.0762 0.0762)
			(layers "B.Cu" "B.Mask" "B.Paste")
			(net "GND")
			(options
				(clearance outline)
				(anchor circle)
			)
			(primitives
				(gr_poly
					(pts
						(arc
							(start 0.1524 0.127)
							(mid 0.137521 0.162921)
							(end 0.1016 0.1778)
						)
						(arc
							(start -0.1016 0.1778)
							(mid -0.137521 0.162921)
							(end -0.1524 0.127)
						)
						(arc
							(start -0.1524 -0.127)
							(mid -0.137521 -0.162921)
							(end -0.1016 -0.1778)
						)
						(arc
							(start 0.1016 -0.1778)
							(mid 0.137521 -0.162921)
							(end 0.1524 -0.127)
						)
					)
					(width 0)
					(fill yes)
				)
			)
		)
	)
	(footprint ""
		(layer "B.Cu")
		(at 184.412128 -52.299616 -90)
		(property "Reference" "TP111"
			(at 0 0 90)
			(layer "B.SilkS")
			(hide yes)
			(effects
				(font
					(size 1.27 1.27)
				)
				(justify mirror)
			)
		)
		(property "Value" "TPAD28-2-GP"
			(at 0.0127 -1.6637 270)
			(unlocked yes)
			(layer "B.Fab")
			(hide yes)
			(effects
				(font
					(size 1.016 1.016)
					(thickness 0.1524)
				)
				(justify mirror)
			)
		)
		(property "Device Type" "TPAD28"
			(at 0.0127 -3.1877 270)
			(unlocked yes)
			(layer "B.Fab")
			(hide yes)
			(effects
				(font
					(size 1.016 1.016)
					(thickness 0.1524)
				)
				(justify mirror)
			)
		)
		(duplicate_pad_numbers_are_jumpers no)
		(fp_poly
			(pts
				(arc
					(start 0 -0.3556)
					(mid 0 0.3556)
					(end 0 -0.3556)
				)
			)
			(stroke
				(width 0)
				(type default)
			)
			(fill no)
			(layer "B.CrtYd")
		)
		(fp_poly
			(pts
				(arc
					(start 0 -0.6096)
					(mid 0 0.6096)
					(end 0 -0.6096)
				)
			)
			(stroke
				(width 0)
				(type default)
			)
			(fill no)
			(layer "B.Fab")
		)
		(pad "1" smd circle
			(at 0 0 90)
			(size 0.7112 0.7112)
			(layers "B.Cu" "B.Mask" "B.Paste")
			(net "XM_ALE")
		)
	)
	(footprint ""
		(layer "B.Cu")
		(at 111.499904 -76.499974)
		(property "Reference" "TP48"
			(at 0 0 0)
			(layer "B.SilkS")
			(hide yes)
			(effects
				(font
					(size 1.27 1.27)
				)
				(justify mirror)
			)
		)
		(property "Value" "TPAD28-2-GP"
			(at 0.0127 -1.6637 0)
			(unlocked yes)
			(layer "B.Fab")
			(hide yes)
			(effects
				(font
					(size 1.016 1.016)
					(thickness 0.1524)
				)
				(justify mirror)
			)
		)
		(property "Device Type" "TPAD28"
			(at 0.0127 -3.1877 0)
			(unlocked yes)
			(layer "B.Fab")
			(hide yes)
			(effects
				(font
					(size 1.016 1.016)
					(thickness 0.1524)
				)
				(justify mirror)
			)
		)
		(duplicate_pad_numbers_are_jumpers no)
		(fp_poly
			(pts
				(arc
					(start 0.3556 0)
					(mid -0.3556 0)
					(end 0.3556 0)
				)
			)
			(stroke
				(width 0)
				(type default)
			)
			(fill no)
			(layer "B.CrtYd")
		)
		(fp_poly
			(pts
				(arc
					(start 0.6096 0)
					(mid -0.6096 0)
					(end 0.6096 0)
				)
			)
			(stroke
				(width 0)
				(type default)
			)
			(fill no)
			(layer "B.Fab")
		)
		(pad "1" smd circle
			(at 0 0 180)
			(size 0.7112 0.7112)
			(layers "B.Cu" "B.Mask" "B.Paste")
			(net "XM_GP_CS_2#_TP")
		)
	)
	(footprint ""
		(layer "B.Cu")
		(at 96.497394 -52.347368 90)
		(property "Reference" "C92"
			(at 0 0 90)
			(layer "B.SilkS")
			(hide yes)
			(effects
				(font
					(size 1.27 1.27)
				)
				(justify mirror)
			)
		)
		(property "Value" "SCD01U16V1KX-GP"
			(at 2.8321 -1.7399 90)
			(unlocked yes)
			(layer "B.Fab")
			(hide yes)
			(effects
				(font
					(size 1.016 1.016)
					(thickness 0.1524)
				)
				(justify mirror)
			)
		)
		(property "Device Type" "C0201H13"
			(at 2.8321 -3.2639 90)
			(unlocked yes)
			(layer "B.Fab")
			(hide yes)
			(effects
				(font
					(size 1.016 1.016)
					(thickness 0.1524)
				)
				(justify mirror)
			)
		)
		(duplicate_pad_numbers_are_jumpers no)
		(fp_rect
			(start 0.2794 0.6477)
			(end -0.2794 -0.6477)
			(stroke
				(width 0)
				(type default)
			)
			(fill no)
			(layer "B.CrtYd")
		)
		(fp_rect
			(start 0.2794 0.6477)
			(end -0.2794 -0.6477)
			(stroke
				(width 0)
				(type default)
			)
			(fill no)
			(layer "B.Fab")
		)
		(pad "1" smd custom
			(at 0 -0.2794 270)
			(size 0.0762 0.0762)
			(layers "B.Cu" "B.Mask" "B.Paste")
			(net "PHY_DPB_TO_SCC_14_DN")
			(options
				(clearance outline)
				(anchor circle)
			)
			(primitives
				(gr_poly
					(pts
						(arc
							(start 0.1524 0.127)
							(mid 0.137521 0.162921)
							(end 0.1016 0.1778)
						)
						(arc
							(start -0.1016 0.1778)
							(mid -0.137521 0.162921)
							(end -0.1524 0.127)
						)
						(arc
							(start -0.1524 -0.127)
							(mid -0.137521 -0.162921)
							(end -0.1016 -0.1778)
						)
						(arc
							(start 0.1016 -0.1778)
							(mid 0.137521 -0.162921)
							(end 0.1524 -0.127)
						)
					)
					(width 0)
					(fill yes)
				)
			)
		)
		(pad "2" smd custom
			(at 0 0.2794 270)
			(size 0.0762 0.0762)
			(layers "B.Cu" "B.Mask" "B.Paste")
			(net "PHY_DPB_TO_SCC_C_14_DN")
			(options
				(clearance outline)
				(anchor circle)
			)
			(primitives
				(gr_poly
					(pts
						(arc
							(start 0.1524 0.127)
							(mid 0.137521 0.162921)
							(end 0.1016 0.1778)
						)
						(arc
							(start -0.1016 0.1778)
							(mid -0.137521 0.162921)
							(end -0.1524 0.127)
						)
						(arc
							(start -0.1524 -0.127)
							(mid -0.137521 -0.162921)
							(end -0.1016 -0.1778)
						)
						(arc
							(start 0.1016 -0.1778)
							(mid 0.137521 -0.162921)
							(end 0.1524 -0.127)
						)
					)
					(width 0)
					(fill yes)
				)
			)
		)
	)
	(footprint ""
		(layer "B.Cu")
		(at 107.315 -44.2214 180)
		(property "Reference" "C74"
			(at 0 0 0)
			(layer "B.SilkS")
			(hide yes)
			(effects
				(font
					(size 1.27 1.27)
				)
				(justify mirror)
			)
		)
		(property "Value" "SCD01U16V1KX-GP"
			(at 2.8321 -1.7399 180)
			(unlocked yes)
			(layer "B.Fab")
			(hide yes)
			(effects
				(font
					(size 1.016 1.016)
					(thickness 0.1524)
				)
				(justify mirror)
			)
		)
		(property "Device Type" "C0201H13"
			(at 2.8321 -3.2639 180)
			(unlocked yes)
			(layer "B.Fab")
			(hide yes)
			(effects
				(font
					(size 1.016 1.016)
					(thickness 0.1524)
				)
				(justify mirror)
			)
		)
		(duplicate_pad_numbers_are_jumpers no)
		(fp_rect
			(start 0.2794 0.6477)
			(end -0.2794 -0.6477)
			(stroke
				(width 0)
				(type default)
			)
			(fill no)
			(layer "B.CrtYd")
		)
		(fp_rect
			(start 0.2794 0.6477)
			(end -0.2794 -0.6477)
			(stroke
				(width 0)
				(type default)
			)
			(fill no)
			(layer "B.Fab")
		)
		(pad "1" smd custom
			(at 0 -0.2794)
			(size 0.0762 0.0762)
			(layers "B.Cu" "B.Mask" "B.Paste")
			(net "PHY_DPB_TO_SCC_23_DN")
			(options
				(clearance outline)
				(anchor circle)
			)
			(primitives
				(gr_poly
					(pts
						(arc
							(start 0.1524 0.127)
							(mid 0.137521 0.162921)
							(end 0.1016 0.1778)
						)
						(arc
							(start -0.1016 0.1778)
							(mid -0.137521 0.162921)
							(end -0.1524 0.127)
						)
						(arc
							(start -0.1524 -0.127)
							(mid -0.137521 -0.162921)
							(end -0.1016 -0.1778)
						)
						(arc
							(start 0.1016 -0.1778)
							(mid 0.137521 -0.162921)
							(end 0.1524 -0.127)
						)
					)
					(width 0)
					(fill yes)
				)
			)
		)
		(pad "2" smd custom
			(at 0 0.2794)
			(size 0.0762 0.0762)
			(layers "B.Cu" "B.Mask" "B.Paste")
			(net "PHY_DPB_TO_SCC_C_23_DN")
			(options
				(clearance outline)
				(anchor circle)
			)
			(primitives
				(gr_poly
					(pts
						(arc
							(start 0.1524 0.127)
							(mid 0.137521 0.162921)
							(end 0.1016 0.1778)
						)
						(arc
							(start -0.1016 0.1778)
							(mid -0.137521 0.162921)
							(end -0.1524 0.127)
						)
						(arc
							(start -0.1524 -0.127)
							(mid -0.137521 -0.162921)
							(end -0.1016 -0.1778)
						)
						(arc
							(start 0.1016 -0.1778)
							(mid 0.137521 -0.162921)
							(end 0.1524 -0.127)
						)
					)
					(width 0)
					(fill yes)
				)
			)
		)
	)
	(footprint ""
		(layer "B.Cu")
		(at 107.88523 -58.6867 -90)
		(property "Reference" "C294"
			(at 0 0 90)
			(layer "B.SilkS")
			(hide yes)
			(effects
				(font
					(size 1.27 1.27)
				)
				(justify mirror)
			)
		)
		(property "Value" "SC1U6D3V1MX-GP"
			(at -1.9177 2.0193 270)
			(unlocked yes)
			(layer "B.Fab")
			(hide yes)
			(effects
				(font
					(size 1.016 1.016)
					(thickness 0.1524)
				)
				(justify mirror)
			)
		)
		(property "Device Type" "C0201H14"
			(at -1.9177 0.4953 270)
			(unlocked yes)
			(layer "B.Fab")
			(hide yes)
			(effects
				(font
					(size 1.016 1.016)
					(thickness 0.1524)
				)
				(justify mirror)
			)
		)
		(duplicate_pad_numbers_are_jumpers no)
		(fp_rect
			(start 0.1524 0.3048)
			(end -0.1524 -0.3048)
			(stroke
				(width 0)
				(type default)
			)
			(fill no)
			(layer "B.CrtYd")
		)
		(fp_poly
			(pts
				(xy 0.2794 0.6477) (xy 0.2794 -0.6477) (xy -0.2794 -0.6477) (xy -0.2794 -0.1905) (xy -0.1524 -0.1905)
				(xy -0.1524 -0.3048) (xy 0.1524 -0.3048) (xy 0.1524 0.3048) (xy -0.1524 0.3048) (xy -0.1524 -0.1778)
				(xy -0.2794 -0.1778) (xy -0.2794 0.6477)
			)
			(stroke
				(width 0)
				(type default)
			)
			(fill no)
			(layer "B.CrtYd")
		)
		(fp_rect
			(start 0.2794 0.6477)
			(end -0.2794 -0.6477)
			(stroke
				(width 0)
				(type default)
			)
			(fill no)
			(layer "B.Fab")
		)
		(pad "1" smd custom
			(at 0 -0.2794 90)
			(size 0.0762 0.0762)
			(layers "B.Cu" "B.Mask" "B.Paste")
			(net "GB_VDDA")
			(options
				(clearance outline)
				(anchor circle)
			)
			(primitives
				(gr_poly
					(pts
						(arc
							(start 0.1524 0.127)
							(mid 0.137521 0.162921)
							(end 0.1016 0.1778)
						)
						(arc
							(start -0.1016 0.1778)
							(mid -0.137521 0.162921)
							(end -0.1524 0.127)
						)
						(arc
							(start -0.1524 -0.127)
							(mid -0.137521 -0.162921)
							(end -0.1016 -0.1778)
						)
						(arc
							(start 0.1016 -0.1778)
							(mid 0.137521 -0.162921)
							(end 0.1524 -0.127)
						)
					)
					(width 0)
					(fill yes)
				)
			)
		)
		(pad "2" smd custom
			(at 0 0.2794 90)
			(size 0.0762 0.0762)
			(layers "B.Cu" "B.Mask" "B.Paste")
			(net "GND")
			(options
				(clearance outline)
				(anchor circle)
			)
			(primitives
				(gr_poly
					(pts
						(arc
							(start 0.1524 0.127)
							(mid 0.137521 0.162921)
							(end 0.1016 0.1778)
						)
						(arc
							(start -0.1016 0.1778)
							(mid -0.137521 0.162921)
							(end -0.1524 0.127)
						)
						(arc
							(start -0.1524 -0.127)
							(mid -0.137521 -0.162921)
							(end -0.1016 -0.1778)
						)
						(arc
							(start 0.1016 -0.1778)
							(mid 0.137521 -0.162921)
							(end 0.1524 -0.127)
						)
					)
					(width 0)
					(fill yes)
				)
			)
		)
	)
	(footprint ""
		(layer "B.Cu")
		(at 183.668416 -85.988652 90)
		(property "Reference" "C660"
			(at 0 0 90)
			(layer "B.SilkS")
			(hide yes)
			(effects
				(font
					(size 1.27 1.27)
				)
				(justify mirror)
			)
		)
		(property "Value" "SCD1U50V3KX-GP"
			(at 0 -2.8194 90)
			(unlocked yes)
			(layer "B.Fab")
			(hide yes)
			(effects
				(font
					(size 1.016 1.016)
					(thickness 0.1524)
				)
				(justify mirror)
			)
		)
		(property "Device Type" "C603H36"
			(at 0 -4.3434 90)
			(unlocked yes)
			(layer "B.Fab")
			(hide yes)
			(effects
				(font
					(size 1.016 1.016)
					(thickness 0.1524)
				)
				(justify mirror)
			)
		)
		(duplicate_pad_numbers_are_jumpers no)
		(fp_line
			(start -0.508 0)
			(end 0.508 0)
			(stroke
				(width 0.2032)
				(type default)
			)
			(layer "B.SilkS")
		)
		(fp_rect
			(start 0.5842 1.3335)
			(end -0.5842 -1.3335)
			(stroke
				(width 0)
				(type default)
			)
			(fill no)
			(layer "B.CrtYd")
		)
		(fp_rect
			(start 0.5842 1.3335)
			(end -0.5842 -1.3335)
			(stroke
				(width 0)
				(type default)
			)
			(fill no)
			(layer "B.Fab")
		)
		(pad "1" smd custom
			(at 0 -0.762 270)
			(size 0.2159 0.2159)
			(layers "B.Cu" "B.Mask" "B.Paste")
			(net "P0V975")
			(options
				(clearance outline)
				(anchor circle)
			)
			(primitives
				(gr_poly
					(pts
						(arc
							(start -0.3302 0.4318)
							(mid -0.402042 0.402042)
							(end -0.4318 0.3302)
						)
						(arc
							(start -0.4318 -0.3302)
							(mid -0.402042 -0.402042)
							(end -0.3302 -0.4318)
						)
						(arc
							(start 0.3302 -0.4318)
							(mid 0.402042 -0.402042)
							(end 0.4318 -0.3302)
						)
						(arc
							(start 0.4318 0.3302)
							(mid 0.402042 0.402042)
							(end 0.3302 0.4318)
						)
					)
					(width 0)
					(fill yes)
				)
			)
		)
		(pad "2" smd custom
			(at 0 0.762 270)
			(size 0.2159 0.2159)
			(layers "B.Cu" "B.Mask" "B.Paste")
			(net "GND")
			(options
				(clearance outline)
				(anchor circle)
			)
			(primitives
				(gr_poly
					(pts
						(arc
							(start -0.3302 0.4318)
							(mid -0.402042 0.402042)
							(end -0.4318 0.3302)
						)
						(arc
							(start -0.4318 -0.3302)
							(mid -0.402042 -0.402042)
							(end -0.3302 -0.4318)
						)
						(arc
							(start 0.3302 -0.4318)
							(mid 0.402042 -0.402042)
							(end 0.4318 -0.3302)
						)
						(arc
							(start 0.4318 0.3302)
							(mid 0.402042 0.402042)
							(end 0.3302 0.4318)
						)
					)
					(width 0)
					(fill yes)
				)
			)
		)
	)
	(footprint ""
		(layer "B.Cu")
		(at 121.2596 -57.4802)
		(property "Reference" "C259"
			(at 0 0 0)
			(layer "B.SilkS")
			(hide yes)
			(effects
				(font
					(size 1.27 1.27)
				)
				(justify mirror)
			)
		)
		(property "Value" "SCD1U6D3V1KX-GP"
			(at 2.8321 -1.7399 0)
			(unlocked yes)
			(layer "B.Fab")
			(hide yes)
			(effects
				(font
					(size 1.016 1.016)
					(thickness 0.1524)
				)
				(justify mirror)
			)
		)
		(property "Device Type" "C0201H13"
			(at 2.8321 -3.2639 0)
			(unlocked yes)
			(layer "B.Fab")
			(hide yes)
			(effects
				(font
					(size 1.016 1.016)
					(thickness 0.1524)
				)
				(justify mirror)
			)
		)
		(duplicate_pad_numbers_are_jumpers no)
		(fp_rect
			(start 0.2794 0.6477)
			(end -0.2794 -0.6477)
			(stroke
				(width 0)
				(type default)
			)
			(fill no)
			(layer "B.CrtYd")
		)
		(fp_rect
			(start 0.2794 0.6477)
			(end -0.2794 -0.6477)
			(stroke
				(width 0)
				(type default)
			)
			(fill no)
			(layer "B.Fab")
		)
		(pad "1" smd custom
			(at 0 -0.2794 180)
			(size 0.0762 0.0762)
			(layers "B.Cu" "B.Mask" "B.Paste")
			(net "GB_VDDA")
			(options
				(clearance outline)
				(anchor circle)
			)
			(primitives
				(gr_poly
					(pts
						(arc
							(start 0.1524 0.127)
							(mid 0.137521 0.162921)
							(end 0.1016 0.1778)
						)
						(arc
							(start -0.1016 0.1778)
							(mid -0.137521 0.162921)
							(end -0.1524 0.127)
						)
						(arc
							(start -0.1524 -0.127)
							(mid -0.137521 -0.162921)
							(end -0.1016 -0.1778)
						)
						(arc
							(start 0.1016 -0.1778)
							(mid 0.137521 -0.162921)
							(end 0.1524 -0.127)
						)
					)
					(width 0)
					(fill yes)
				)
			)
		)
		(pad "2" smd custom
			(at 0 0.2794 180)
			(size 0.0762 0.0762)
			(layers "B.Cu" "B.Mask" "B.Paste")
			(net "GND")
			(options
				(clearance outline)
				(anchor circle)
			)
			(primitives
				(gr_poly
					(pts
						(arc
							(start 0.1524 0.127)
							(mid 0.137521 0.162921)
							(end 0.1016 0.1778)
						)
						(arc
							(start -0.1016 0.1778)
							(mid -0.137521 0.162921)
							(end -0.1524 0.127)
						)
						(arc
							(start -0.1524 -0.127)
							(mid -0.137521 -0.162921)
							(end -0.1016 -0.1778)
						)
						(arc
							(start 0.1016 -0.1778)
							(mid 0.137521 -0.162921)
							(end 0.1524 -0.127)
						)
					)
					(width 0)
					(fill yes)
				)
			)
		)
	)
	(footprint ""
		(layer "B.Cu")
		(at 182.753 -26.1366 90)
		(property "Reference" "TP66"
			(at 0 0 90)
			(layer "B.SilkS")
			(hide yes)
			(effects
				(font
					(size 1.27 1.27)
				)
				(justify mirror)
			)
		)
		(property "Value" "TPAD28-2-GP"
			(at 0.0127 -1.6637 90)
			(unlocked yes)
			(layer "B.Fab")
			(hide yes)
			(effects
				(font
					(size 1.016 1.016)
					(thickness 0.1524)
				)
				(justify mirror)
			)
		)
		(property "Device Type" "TPAD28"
			(at 0.0127 -3.1877 90)
			(unlocked yes)
			(layer "B.Fab")
			(hide yes)
			(effects
				(font
					(size 1.016 1.016)
					(thickness 0.1524)
				)
				(justify mirror)
			)
		)
		(duplicate_pad_numbers_are_jumpers no)
		(fp_poly
			(pts
				(arc
					(start 0 0.3556)
					(mid 0 -0.3556)
					(end 0 0.3556)
				)
			)
			(stroke
				(width 0)
				(type default)
			)
			(fill no)
			(layer "B.CrtYd")
		)
		(fp_poly
			(pts
				(arc
					(start 0 0.6096)
					(mid 0 -0.6096)
					(end 0 0.6096)
				)
			)
			(stroke
				(width 0)
				(type default)
			)
			(fill no)
			(layer "B.Fab")
		)
		(pad "1" smd circle
			(at 0 0 270)
			(size 0.7112 0.7112)
			(layers "B.Cu" "B.Mask" "B.Paste")
			(net "IOC_GPIO_13")
		)
	)
	(footprint ""
		(layer "B.Cu")
		(at 180.514498 -51.451256 -90)
		(property "Reference" "TP112"
			(at 0 0 90)
			(layer "B.SilkS")
			(hide yes)
			(effects
				(font
					(size 1.27 1.27)
				)
				(justify mirror)
			)
		)
		(property "Value" "TPAD28-2-GP"
			(at 0.0127 -1.6637 270)
			(unlocked yes)
			(layer "B.Fab")
			(hide yes)
			(effects
				(font
					(size 1.016 1.016)
					(thickness 0.1524)
				)
				(justify mirror)
			)
		)
		(property "Device Type" "TPAD28"
			(at 0.0127 -3.1877 270)
			(unlocked yes)
			(layer "B.Fab")
			(hide yes)
			(effects
				(font
					(size 1.016 1.016)
					(thickness 0.1524)
				)
				(justify mirror)
			)
		)
		(duplicate_pad_numbers_are_jumpers no)
		(fp_poly
			(pts
				(arc
					(start 0 -0.3556)
					(mid 0 0.3556)
					(end 0 -0.3556)
				)
			)
			(stroke
				(width 0)
				(type default)
			)
			(fill no)
			(layer "B.CrtYd")
		)
		(fp_poly
			(pts
				(arc
					(start 0 -0.6096)
					(mid 0 0.6096)
					(end 0 -0.6096)
				)
			)
			(stroke
				(width 0)
				(type default)
			)
			(fill no)
			(layer "B.Fab")
		)
		(pad "1" smd circle
			(at 0 0 90)
			(size 0.7112 0.7112)
			(layers "B.Cu" "B.Mask" "B.Paste")
			(net "XM_CLE")
		)
	)
	(footprint ""
		(layer "B.Cu")
		(at 184.465468 -40.05961 90)
		(property "Reference" "C489"
			(at 0 0 90)
			(layer "B.SilkS")
			(hide yes)
			(effects
				(font
					(size 1.27 1.27)
				)
				(justify mirror)
			)
		)
		(property "Value" "SCD1U6D3V1KX-GP"
			(at 2.8321 -1.7399 90)
			(unlocked yes)
			(layer "B.Fab")
			(hide yes)
			(effects
				(font
					(size 1.016 1.016)
					(thickness 0.1524)
				)
				(justify mirror)
			)
		)
		(property "Device Type" "C0201H13"
			(at 2.8321 -3.2639 90)
			(unlocked yes)
			(layer "B.Fab")
			(hide yes)
			(effects
				(font
					(size 1.016 1.016)
					(thickness 0.1524)
				)
				(justify mirror)
			)
		)
		(duplicate_pad_numbers_are_jumpers no)
		(fp_rect
			(start 0.2794 0.6477)
			(end -0.2794 -0.6477)
			(stroke
				(width 0)
				(type default)
			)
			(fill no)
			(layer "B.CrtYd")
		)
		(fp_rect
			(start 0.2794 0.6477)
			(end -0.2794 -0.6477)
			(stroke
				(width 0)
				(type default)
			)
			(fill no)
			(layer "B.Fab")
		)
		(pad "1" smd custom
			(at 0 -0.2794 270)
			(size 0.0762 0.0762)
			(layers "B.Cu" "B.Mask" "B.Paste")
			(net "P1V8_C")
			(options
				(clearance outline)
				(anchor circle)
			)
			(primitives
				(gr_poly
					(pts
						(arc
							(start 0.1524 0.127)
							(mid 0.137521 0.162921)
							(end 0.1016 0.1778)
						)
						(arc
							(start -0.1016 0.1778)
							(mid -0.137521 0.162921)
							(end -0.1524 0.127)
						)
						(arc
							(start -0.1524 -0.127)
							(mid -0.137521 -0.162921)
							(end -0.1016 -0.1778)
						)
						(arc
							(start 0.1016 -0.1778)
							(mid 0.137521 -0.162921)
							(end 0.1524 -0.127)
						)
					)
					(width 0)
					(fill yes)
				)
			)
		)
		(pad "2" smd custom
			(at 0 0.2794 270)
			(size 0.0762 0.0762)
			(layers "B.Cu" "B.Mask" "B.Paste")
			(net "GND")
			(options
				(clearance outline)
				(anchor circle)
			)
			(primitives
				(gr_poly
					(pts
						(arc
							(start 0.1524 0.127)
							(mid 0.137521 0.162921)
							(end 0.1016 0.1778)
						)
						(arc
							(start -0.1016 0.1778)
							(mid -0.137521 0.162921)
							(end -0.1524 0.127)
						)
						(arc
							(start -0.1524 -0.127)
							(mid -0.137521 -0.162921)
							(end -0.1016 -0.1778)
						)
						(arc
							(start 0.1016 -0.1778)
							(mid 0.137521 -0.162921)
							(end 0.1524 -0.127)
						)
					)
					(width 0)
					(fill yes)
				)
			)
		)
	)
	(footprint ""
		(layer "B.Cu")
		(at 124.5362 -73.4822 -90)
		(property "Reference" "C244"
			(at 0 0 90)
			(layer "B.SilkS")
			(hide yes)
			(effects
				(font
					(size 1.27 1.27)
				)
				(justify mirror)
			)
		)
		(property "Value" "SCD1U6D3V1KX-GP"
			(at 2.8321 -1.7399 270)
			(unlocked yes)
			(layer "B.Fab")
			(hide yes)
			(effects
				(font
					(size 1.016 1.016)
					(thickness 0.1524)
				)
				(justify mirror)
			)
		)
		(property "Device Type" "C0201H13"
			(at 2.8321 -3.2639 270)
			(unlocked yes)
			(layer "B.Fab")
			(hide yes)
			(effects
				(font
					(size 1.016 1.016)
					(thickness 0.1524)
				)
				(justify mirror)
			)
		)
		(duplicate_pad_numbers_are_jumpers no)
		(fp_rect
			(start 0.2794 0.6477)
			(end -0.2794 -0.6477)
			(stroke
				(width 0)
				(type default)
			)
			(fill no)
			(layer "B.CrtYd")
		)
		(fp_rect
			(start 0.2794 0.6477)
			(end -0.2794 -0.6477)
			(stroke
				(width 0)
				(type default)
			)
			(fill no)
			(layer "B.Fab")
		)
		(pad "1" smd custom
			(at 0 -0.2794 90)
			(size 0.0762 0.0762)
			(layers "B.Cu" "B.Mask" "B.Paste")
			(net "GB_VDDA")
			(options
				(clearance outline)
				(anchor circle)
			)
			(primitives
				(gr_poly
					(pts
						(arc
							(start 0.1524 0.127)
							(mid 0.137521 0.162921)
							(end 0.1016 0.1778)
						)
						(arc
							(start -0.1016 0.1778)
							(mid -0.137521 0.162921)
							(end -0.1524 0.127)
						)
						(arc
							(start -0.1524 -0.127)
							(mid -0.137521 -0.162921)
							(end -0.1016 -0.1778)
						)
						(arc
							(start 0.1016 -0.1778)
							(mid 0.137521 -0.162921)
							(end 0.1524 -0.127)
						)
					)
					(width 0)
					(fill yes)
				)
			)
		)
		(pad "2" smd custom
			(at 0 0.2794 90)
			(size 0.0762 0.0762)
			(layers "B.Cu" "B.Mask" "B.Paste")
			(net "GND")
			(options
				(clearance outline)
				(anchor circle)
			)
			(primitives
				(gr_poly
					(pts
						(arc
							(start 0.1524 0.127)
							(mid 0.137521 0.162921)
							(end 0.1016 0.1778)
						)
						(arc
							(start -0.1016 0.1778)
							(mid -0.137521 0.162921)
							(end -0.1524 0.127)
						)
						(arc
							(start -0.1524 -0.127)
							(mid -0.137521 -0.162921)
							(end -0.1016 -0.1778)
						)
						(arc
							(start 0.1016 -0.1778)
							(mid 0.137521 -0.162921)
							(end 0.1524 -0.127)
						)
					)
					(width 0)
					(fill yes)
				)
			)
		)
	)
	(footprint ""
		(layer "B.Cu")
		(at 94.398592 -85.095842)
		(property "Reference" "TP28"
			(at 0 0 0)
			(layer "B.SilkS")
			(hide yes)
			(effects
				(font
					(size 1.27 1.27)
				)
				(justify mirror)
			)
		)
		(property "Value" "TPAD28-2-GP"
			(at 0.0127 -1.6637 0)
			(unlocked yes)
			(layer "B.Fab")
			(hide yes)
			(effects
				(font
					(size 1.016 1.016)
					(thickness 0.1524)
				)
				(justify mirror)
			)
		)
		(property "Device Type" "TPAD28"
			(at 0.0127 -3.1877 0)
			(unlocked yes)
			(layer "B.Fab")
			(hide yes)
			(effects
				(font
					(size 1.016 1.016)
					(thickness 0.1524)
				)
				(justify mirror)
			)
		)
		(duplicate_pad_numbers_are_jumpers no)
		(fp_poly
			(pts
				(arc
					(start 0.3556 0)
					(mid -0.3556 0)
					(end 0.3556 0)
				)
			)
			(stroke
				(width 0)
				(type default)
			)
			(fill no)
			(layer "B.CrtYd")
		)
		(fp_poly
			(pts
				(arc
					(start 0.6096 0)
					(mid -0.6096 0)
					(end 0.6096 0)
				)
			)
			(stroke
				(width 0)
				(type default)
			)
			(fill no)
			(layer "B.Fab")
		)
		(pad "1" smd circle
			(at 0 0 180)
			(size 0.7112 0.7112)
			(layers "B.Cu" "B.Mask" "B.Paste")
			(net "ICE_RESET_N")
		)
	)
	(footprint ""
		(layer "B.Cu")
		(at 181.269386 -21.841968 90)
		(property "Reference" "C326"
			(at 0 0 90)
			(layer "B.SilkS")
			(hide yes)
			(effects
				(font
					(size 1.27 1.27)
				)
				(justify mirror)
			)
		)
		(property "Value" "SCD22U10V1KX-GP"
			(at 2.8321 -1.7399 90)
			(unlocked yes)
			(layer "B.Fab")
			(hide yes)
			(effects
				(font
					(size 1.016 1.016)
					(thickness 0.1524)
				)
				(justify mirror)
			)
		)
		(property "Device Type" "C0201H13"
			(at 2.8321 -3.2639 90)
			(unlocked yes)
			(layer "B.Fab")
			(hide yes)
			(effects
				(font
					(size 1.016 1.016)
					(thickness 0.1524)
				)
				(justify mirror)
			)
		)
		(duplicate_pad_numbers_are_jumpers no)
		(fp_rect
			(start 0.2794 0.6477)
			(end -0.2794 -0.6477)
			(stroke
				(width 0)
				(type default)
			)
			(fill no)
			(layer "B.CrtYd")
		)
		(fp_rect
			(start 0.2794 0.6477)
			(end -0.2794 -0.6477)
			(stroke
				(width 0)
				(type default)
			)
			(fill no)
			(layer "B.Fab")
		)
		(pad "1" smd custom
			(at 0 -0.2794 270)
			(size 0.0762 0.0762)
			(layers "B.Cu" "B.Mask" "B.Paste")
			(net "PCIE_SCC_TO_COMP_C_7_DN")
			(options
				(clearance outline)
				(anchor circle)
			)
			(primitives
				(gr_poly
					(pts
						(arc
							(start 0.1524 0.127)
							(mid 0.137521 0.162921)
							(end 0.1016 0.1778)
						)
						(arc
							(start -0.1016 0.1778)
							(mid -0.137521 0.162921)
							(end -0.1524 0.127)
						)
						(arc
							(start -0.1524 -0.127)
							(mid -0.137521 -0.162921)
							(end -0.1016 -0.1778)
						)
						(arc
							(start 0.1016 -0.1778)
							(mid 0.137521 -0.162921)
							(end 0.1524 -0.127)
						)
					)
					(width 0)
					(fill yes)
				)
			)
		)
		(pad "2" smd custom
			(at 0 0.2794 270)
			(size 0.0762 0.0762)
			(layers "B.Cu" "B.Mask" "B.Paste")
			(net "PCIE_SCC_TO_COMP_7_DN")
			(options
				(clearance outline)
				(anchor circle)
			)
			(primitives
				(gr_poly
					(pts
						(arc
							(start 0.1524 0.127)
							(mid 0.137521 0.162921)
							(end 0.1016 0.1778)
						)
						(arc
							(start -0.1016 0.1778)
							(mid -0.137521 0.162921)
							(end -0.1524 0.127)
						)
						(arc
							(start -0.1524 -0.127)
							(mid -0.137521 -0.162921)
							(end -0.1016 -0.1778)
						)
						(arc
							(start 0.1016 -0.1778)
							(mid 0.137521 -0.162921)
							(end 0.1524 -0.127)
						)
					)
					(width 0)
					(fill yes)
				)
			)
		)
	)
	(footprint ""
		(layer "B.Cu")
		(at 118.8466 -89.535 180)
		(property "Reference" "R565"
			(at 0 0 0)
			(layer "B.SilkS")
			(hide yes)
			(effects
				(font
					(size 1.27 1.27)
				)
				(justify mirror)
			)
		)
		(property "Value" "10KR2F-2-GP"
			(at -0.064008 -3.993896 180)
			(unlocked yes)
			(layer "B.Fab")
			(hide yes)
			(effects
				(font
					(size 1.016 1.016)
					(thickness 0.1524)
				)
				(justify mirror)
			)
		)
		(property "Device Type" "R402H16"
			(at -0.064008 -5.517896 180)
			(unlocked yes)
			(layer "B.Fab")
			(hide yes)
			(effects
				(font
					(size 1.016 1.016)
					(thickness 0.1524)
				)
				(justify mirror)
			)
		)
		(duplicate_pad_numbers_are_jumpers no)
		(fp_line
			(start 0.508 -0.9398)
			(end 0.508 0.9398)
			(stroke
				(width 0.1524)
				(type default)
			)
			(layer "B.SilkS")
		)
		(fp_line
			(start -0.508 -0.9398)
			(end 0.508 -0.9398)
			(stroke
				(width 0.1524)
				(type default)
			)
			(layer "B.SilkS")
		)
		(fp_rect
			(start 0.508 0.9398)
			(end -0.508 -0.9398)
			(stroke
				(width 0)
				(type default)
			)
			(fill no)
			(layer "B.CrtYd")
		)
		(fp_rect
			(start 0.508 0.9398)
			(end -0.508 -0.9398)
			(stroke
				(width 0)
				(type default)
			)
			(fill no)
			(layer "B.Fab")
		)
		(pad "1" smd custom
			(at 0 -0.4445)
			(size 0.1397 0.1397)
			(layers "B.Cu" "B.Mask" "B.Paste")
			(net "COMP_SPARE_0_LS")
			(options
				(clearance outline)
				(anchor circle)
			)
			(primitives
				(gr_poly
					(pts
						(arc
							(start -0.1778 0.2794)
							(mid -0.249642 0.249642)
							(end -0.2794 0.1778)
						)
						(arc
							(start -0.2794 -0.1778)
							(mid -0.249642 -0.249642)
							(end -0.1778 -0.2794)
						)
						(arc
							(start 0.1778 -0.2794)
							(mid 0.249642 -0.249642)
							(end 0.2794 -0.1778)
						)
						(arc
							(start 0.2794 0.1778)
							(mid 0.249642 0.249642)
							(end 0.1778 0.2794)
						)
					)
					(width 0)
					(fill yes)
				)
			)
		)
		(pad "2" smd custom
			(at 0 0.4445)
			(size 0.1397 0.1397)
			(layers "B.Cu" "B.Mask" "B.Paste")
			(net "P1V8_E")
			(options
				(clearance outline)
				(anchor circle)
			)
			(primitives
				(gr_poly
					(pts
						(arc
							(start -0.1778 0.2794)
							(mid -0.249642 0.249642)
							(end -0.2794 0.1778)
						)
						(arc
							(start -0.2794 -0.1778)
							(mid -0.249642 -0.249642)
							(end -0.1778 -0.2794)
						)
						(arc
							(start 0.1778 -0.2794)
							(mid 0.249642 -0.249642)
							(end 0.2794 -0.1778)
						)
						(arc
							(start 0.2794 0.1778)
							(mid 0.249642 0.249642)
							(end 0.1778 0.2794)
						)
					)
					(width 0)
					(fill yes)
				)
			)
		)
	)
	(footprint ""
		(layer "B.Cu")
		(at 187.12942 -42.296588 90)
		(property "Reference" "TP91"
			(at 0 0 90)
			(layer "B.SilkS")
			(hide yes)
			(effects
				(font
					(size 1.27 1.27)
				)
				(justify mirror)
			)
		)
		(property "Value" "TPAD28-2-GP"
			(at 0.0127 -1.6637 90)
			(unlocked yes)
			(layer "B.Fab")
			(hide yes)
			(effects
				(font
					(size 1.016 1.016)
					(thickness 0.1524)
				)
				(justify mirror)
			)
		)
		(property "Device Type" "TPAD28"
			(at 0.0127 -3.1877 90)
			(unlocked yes)
			(layer "B.Fab")
			(hide yes)
			(effects
				(font
					(size 1.016 1.016)
					(thickness 0.1524)
				)
				(justify mirror)
			)
		)
		(duplicate_pad_numbers_are_jumpers no)
		(fp_poly
			(pts
				(arc
					(start 0 0.3556)
					(mid 0 -0.3556)
					(end 0 0.3556)
				)
			)
			(stroke
				(width 0)
				(type default)
			)
			(fill no)
			(layer "B.CrtYd")
		)
		(fp_poly
			(pts
				(arc
					(start 0 0.6096)
					(mid 0 -0.6096)
					(end 0 0.6096)
				)
			)
			(stroke
				(width 0)
				(type default)
			)
			(fill no)
			(layer "B.Fab")
		)
		(pad "1" smd circle
			(at 0 0 270)
			(size 0.7112 0.7112)
			(layers "B.Cu" "B.Mask" "B.Paste")
			(net "IOC_GPIO_32")
		)
	)
	(footprint ""
		(layer "B.Cu")
		(at 116.459 -44.2214 180)
		(property "Reference" "C62"
			(at 0 0 0)
			(layer "B.SilkS")
			(hide yes)
			(effects
				(font
					(size 1.27 1.27)
				)
				(justify mirror)
			)
		)
		(property "Value" "SCD01U16V1KX-GP"
			(at 2.8321 -1.7399 180)
			(unlocked yes)
			(layer "B.Fab")
			(hide yes)
			(effects
				(font
					(size 1.016 1.016)
					(thickness 0.1524)
				)
				(justify mirror)
			)
		)
		(property "Device Type" "C0201H13"
			(at 2.8321 -3.2639 180)
			(unlocked yes)
			(layer "B.Fab")
			(hide yes)
			(effects
				(font
					(size 1.016 1.016)
					(thickness 0.1524)
				)
				(justify mirror)
			)
		)
		(duplicate_pad_numbers_are_jumpers no)
		(fp_rect
			(start 0.2794 0.6477)
			(end -0.2794 -0.6477)
			(stroke
				(width 0)
				(type default)
			)
			(fill no)
			(layer "B.CrtYd")
		)
		(fp_rect
			(start 0.2794 0.6477)
			(end -0.2794 -0.6477)
			(stroke
				(width 0)
				(type default)
			)
			(fill no)
			(layer "B.Fab")
		)
		(pad "1" smd custom
			(at 0 -0.2794)
			(size 0.0762 0.0762)
			(layers "B.Cu" "B.Mask" "B.Paste")
			(net "PHY_DPB_TO_SCC_33_DN")
			(options
				(clearance outline)
				(anchor circle)
			)
			(primitives
				(gr_poly
					(pts
						(arc
							(start 0.1524 0.127)
							(mid 0.137521 0.162921)
							(end 0.1016 0.1778)
						)
						(arc
							(start -0.1016 0.1778)
							(mid -0.137521 0.162921)
							(end -0.1524 0.127)
						)
						(arc
							(start -0.1524 -0.127)
							(mid -0.137521 -0.162921)
							(end -0.1016 -0.1778)
						)
						(arc
							(start 0.1016 -0.1778)
							(mid 0.137521 -0.162921)
							(end 0.1524 -0.127)
						)
					)
					(width 0)
					(fill yes)
				)
			)
		)
		(pad "2" smd custom
			(at 0 0.2794)
			(size 0.0762 0.0762)
			(layers "B.Cu" "B.Mask" "B.Paste")
			(net "PHY_DPB_TO_SCC_C_33_DN")
			(options
				(clearance outline)
				(anchor circle)
			)
			(primitives
				(gr_poly
					(pts
						(arc
							(start 0.1524 0.127)
							(mid 0.137521 0.162921)
							(end 0.1016 0.1778)
						)
						(arc
							(start -0.1016 0.1778)
							(mid -0.137521 0.162921)
							(end -0.1524 0.127)
						)
						(arc
							(start -0.1524 -0.127)
							(mid -0.137521 -0.162921)
							(end -0.1016 -0.1778)
						)
						(arc
							(start 0.1016 -0.1778)
							(mid 0.137521 -0.162921)
							(end 0.1524 -0.127)
						)
					)
					(width 0)
					(fill yes)
				)
			)
		)
	)
	(footprint ""
		(layer "B.Cu")
		(at 112.649 -68.6562)
		(property "Reference" "C177"
			(at 0 0 0)
			(layer "B.SilkS")
			(hide yes)
			(effects
				(font
					(size 1.27 1.27)
				)
				(justify mirror)
			)
		)
		(property "Value" "SCD1U6D3V1KX-GP"
			(at 2.8321 -1.7399 0)
			(unlocked yes)
			(layer "B.Fab")
			(hide yes)
			(effects
				(font
					(size 1.016 1.016)
					(thickness 0.1524)
				)
				(justify mirror)
			)
		)
		(property "Device Type" "C0201H13"
			(at 2.8321 -3.2639 0)
			(unlocked yes)
			(layer "B.Fab")
			(hide yes)
			(effects
				(font
					(size 1.016 1.016)
					(thickness 0.1524)
				)
				(justify mirror)
			)
		)
		(duplicate_pad_numbers_are_jumpers no)
		(fp_rect
			(start 0.2794 0.6477)
			(end -0.2794 -0.6477)
			(stroke
				(width 0)
				(type default)
			)
			(fill no)
			(layer "B.CrtYd")
		)
		(fp_rect
			(start 0.2794 0.6477)
			(end -0.2794 -0.6477)
			(stroke
				(width 0)
				(type default)
			)
			(fill no)
			(layer "B.Fab")
		)
		(pad "1" smd custom
			(at 0 -0.2794 180)
			(size 0.0762 0.0762)
			(layers "B.Cu" "B.Mask" "B.Paste")
			(net "P0V9")
			(options
				(clearance outline)
				(anchor circle)
			)
			(primitives
				(gr_poly
					(pts
						(arc
							(start 0.1524 0.127)
							(mid 0.137521 0.162921)
							(end 0.1016 0.1778)
						)
						(arc
							(start -0.1016 0.1778)
							(mid -0.137521 0.162921)
							(end -0.1524 0.127)
						)
						(arc
							(start -0.1524 -0.127)
							(mid -0.137521 -0.162921)
							(end -0.1016 -0.1778)
						)
						(arc
							(start 0.1016 -0.1778)
							(mid 0.137521 -0.162921)
							(end 0.1524 -0.127)
						)
					)
					(width 0)
					(fill yes)
				)
			)
		)
		(pad "2" smd custom
			(at 0 0.2794 180)
			(size 0.0762 0.0762)
			(layers "B.Cu" "B.Mask" "B.Paste")
			(net "GND")
			(options
				(clearance outline)
				(anchor circle)
			)
			(primitives
				(gr_poly
					(pts
						(arc
							(start 0.1524 0.127)
							(mid 0.137521 0.162921)
							(end 0.1016 0.1778)
						)
						(arc
							(start -0.1016 0.1778)
							(mid -0.137521 0.162921)
							(end -0.1524 0.127)
						)
						(arc
							(start -0.1524 -0.127)
							(mid -0.137521 -0.162921)
							(end -0.1016 -0.1778)
						)
						(arc
							(start 0.1016 -0.1778)
							(mid 0.137521 -0.162921)
							(end 0.1524 -0.127)
						)
					)
					(width 0)
					(fill yes)
				)
			)
		)
	)
	(footprint ""
		(layer "B.Cu")
		(at 186.563 -28.8036 90)
		(property "Reference" "TP73"
			(at 0 0 90)
			(layer "B.SilkS")
			(hide yes)
			(effects
				(font
					(size 1.27 1.27)
				)
				(justify mirror)
			)
		)
		(property "Value" "TPAD28-2-GP"
			(at 0.0127 -1.6637 90)
			(unlocked yes)
			(layer "B.Fab")
			(hide yes)
			(effects
				(font
					(size 1.016 1.016)
					(thickness 0.1524)
				)
				(justify mirror)
			)
		)
		(property "Device Type" "TPAD28"
			(at 0.0127 -3.1877 90)
			(unlocked yes)
			(layer "B.Fab")
			(hide yes)
			(effects
				(font
					(size 1.016 1.016)
					(thickness 0.1524)
				)
				(justify mirror)
			)
		)
		(duplicate_pad_numbers_are_jumpers no)
		(fp_poly
			(pts
				(arc
					(start 0 0.3556)
					(mid 0 -0.3556)
					(end 0 0.3556)
				)
			)
			(stroke
				(width 0)
				(type default)
			)
			(fill no)
			(layer "B.CrtYd")
		)
		(fp_poly
			(pts
				(arc
					(start 0 0.6096)
					(mid 0 -0.6096)
					(end 0 0.6096)
				)
			)
			(stroke
				(width 0)
				(type default)
			)
			(fill no)
			(layer "B.Fab")
		)
		(pad "1" smd circle
			(at 0 0 270)
			(size 0.7112 0.7112)
			(layers "B.Cu" "B.Mask" "B.Paste")
			(net "IOC_GPIO_20")
		)
	)
	(footprint ""
		(layer "B.Cu")
		(at 107.500166 -81.500218)
		(property "Reference" "TP41"
			(at 0 0 0)
			(layer "B.SilkS")
			(hide yes)
			(effects
				(font
					(size 1.27 1.27)
				)
				(justify mirror)
			)
		)
		(property "Value" "TPAD28-2-GP"
			(at 0.0127 -1.6637 0)
			(unlocked yes)
			(layer "B.Fab")
			(hide yes)
			(effects
				(font
					(size 1.016 1.016)
					(thickness 0.1524)
				)
				(justify mirror)
			)
		)
		(property "Device Type" "TPAD28"
			(at 0.0127 -3.1877 0)
			(unlocked yes)
			(layer "B.Fab")
			(hide yes)
			(effects
				(font
					(size 1.016 1.016)
					(thickness 0.1524)
				)
				(justify mirror)
			)
		)
		(duplicate_pad_numbers_are_jumpers no)
		(fp_poly
			(pts
				(arc
					(start 0.3556 0)
					(mid -0.3556 0)
					(end 0.3556 0)
				)
			)
			(stroke
				(width 0)
				(type default)
			)
			(fill no)
			(layer "B.CrtYd")
		)
		(fp_poly
			(pts
				(arc
					(start 0.6096 0)
					(mid -0.6096 0)
					(end 0.6096 0)
				)
			)
			(stroke
				(width 0)
				(type default)
			)
			(fill no)
			(layer "B.Fab")
		)
		(pad "1" smd circle
			(at 0 0 180)
			(size 0.7112 0.7112)
			(layers "B.Cu" "B.Mask" "B.Paste")
			(net "LSI_TRST_N")
		)
	)
	(footprint ""
		(layer "B.Cu")
		(at 156.978604 -66.866008)
		(property "Reference" "R279"
			(at 0 0 0)
			(layer "B.SilkS")
			(hide yes)
			(effects
				(font
					(size 1.27 1.27)
				)
				(justify mirror)
			)
		)
		(property "Value" "10R2F-L-GP"
			(at -0.064008 -3.993896 0)
			(unlocked yes)
			(layer "B.Fab")
			(hide yes)
			(effects
				(font
					(size 1.016 1.016)
					(thickness 0.1524)
				)
				(justify mirror)
			)
		)
		(property "Device Type" "R402H14"
			(at -0.064008 -5.517896 0)
			(unlocked yes)
			(layer "B.Fab")
			(hide yes)
			(effects
				(font
					(size 1.016 1.016)
					(thickness 0.1524)
				)
				(justify mirror)
			)
		)
		(duplicate_pad_numbers_are_jumpers no)
		(fp_line
			(start -0.508 -0.9398)
			(end 0.508 -0.9398)
			(stroke
				(width 0.1524)
				(type default)
			)
			(layer "B.SilkS")
		)
		(fp_line
			(start 0.508 -0.9398)
			(end 0.508 0.9398)
			(stroke
				(width 0.1524)
				(type default)
			)
			(layer "B.SilkS")
		)
		(fp_rect
			(start 0.508 0.9398)
			(end -0.508 -0.9398)
			(stroke
				(width 0)
				(type default)
			)
			(fill no)
			(layer "B.CrtYd")
		)
		(fp_rect
			(start 0.508 0.9398)
			(end -0.508 -0.9398)
			(stroke
				(width 0)
				(type default)
			)
			(fill no)
			(layer "B.Fab")
		)
		(pad "1" smd custom
			(at 0 -0.4445 180)
			(size 0.1397 0.1397)
			(layers "B.Cu" "B.Mask" "B.Paste")
			(net "P1V8_C")
			(options
				(clearance outline)
				(anchor circle)
			)
			(primitives
				(gr_poly
					(pts
						(arc
							(start -0.1778 0.2794)
							(mid -0.249642 0.249642)
							(end -0.2794 0.1778)
						)
						(arc
							(start -0.2794 -0.1778)
							(mid -0.249642 -0.249642)
							(end -0.1778 -0.2794)
						)
						(arc
							(start 0.1778 -0.2794)
							(mid 0.249642 -0.249642)
							(end 0.2794 -0.1778)
						)
						(arc
							(start 0.2794 0.1778)
							(mid 0.249642 0.249642)
							(end 0.1778 0.2794)
						)
					)
					(width 0)
					(fill yes)
				)
			)
		)
		(pad "2" smd custom
			(at 0 0.4445 180)
			(size 0.1397 0.1397)
			(layers "B.Cu" "B.Mask" "B.Paste")
			(net "SHELL_PLL_VDD")
			(options
				(clearance outline)
				(anchor circle)
			)
			(primitives
				(gr_poly
					(pts
						(arc
							(start -0.1778 0.2794)
							(mid -0.249642 0.249642)
							(end -0.2794 0.1778)
						)
						(arc
							(start -0.2794 -0.1778)
							(mid -0.249642 -0.249642)
							(end -0.1778 -0.2794)
						)
						(arc
							(start 0.1778 -0.2794)
							(mid 0.249642 -0.249642)
							(end 0.2794 -0.1778)
						)
						(arc
							(start 0.2794 0.1778)
							(mid 0.249642 0.249642)
							(end 0.1778 0.2794)
						)
					)
					(width 0)
					(fill yes)
				)
			)
		)
	)
	(footprint ""
		(layer "B.Cu")
		(at 187.452 -34.0106 90)
		(property "Reference" "TP95"
			(at 0 0 90)
			(layer "B.SilkS")
			(hide yes)
			(effects
				(font
					(size 1.27 1.27)
				)
				(justify mirror)
			)
		)
		(property "Value" "TPAD28-2-GP"
			(at 0.0127 -1.6637 90)
			(unlocked yes)
			(layer "B.Fab")
			(hide yes)
			(effects
				(font
					(size 1.016 1.016)
					(thickness 0.1524)
				)
				(justify mirror)
			)
		)
		(property "Device Type" "TPAD28"
			(at 0.0127 -3.1877 90)
			(unlocked yes)
			(layer "B.Fab")
			(hide yes)
			(effects
				(font
					(size 1.016 1.016)
					(thickness 0.1524)
				)
				(justify mirror)
			)
		)
		(duplicate_pad_numbers_are_jumpers no)
		(fp_poly
			(pts
				(arc
					(start 0 0.3556)
					(mid 0 -0.3556)
					(end 0 0.3556)
				)
			)
			(stroke
				(width 0)
				(type default)
			)
			(fill no)
			(layer "B.CrtYd")
		)
		(fp_poly
			(pts
				(arc
					(start 0 0.6096)
					(mid 0 -0.6096)
					(end 0 0.6096)
				)
			)
			(stroke
				(width 0)
				(type default)
			)
			(fill no)
			(layer "B.Fab")
		)
		(pad "1" smd circle
			(at 0 0 270)
			(size 0.7112 0.7112)
			(layers "B.Cu" "B.Mask" "B.Paste")
			(net "IOC_GPIO_34")
		)
	)
	(footprint ""
		(layer "B.Cu")
		(at 184.3024 -26.3144 90)
		(property "Reference" "TP54"
			(at 0 0 90)
			(layer "B.SilkS")
			(hide yes)
			(effects
				(font
					(size 1.27 1.27)
				)
				(justify mirror)
			)
		)
		(property "Value" "TPAD28-2-GP"
			(at 0.0127 -1.6637 90)
			(unlocked yes)
			(layer "B.Fab")
			(hide yes)
			(effects
				(font
					(size 1.016 1.016)
					(thickness 0.1524)
				)
				(justify mirror)
			)
		)
		(property "Device Type" "TPAD28"
			(at 0.0127 -3.1877 90)
			(unlocked yes)
			(layer "B.Fab")
			(hide yes)
			(effects
				(font
					(size 1.016 1.016)
					(thickness 0.1524)
				)
				(justify mirror)
			)
		)
		(duplicate_pad_numbers_are_jumpers no)
		(fp_poly
			(pts
				(arc
					(start 0 0.3556)
					(mid 0 -0.3556)
					(end 0 0.3556)
				)
			)
			(stroke
				(width 0)
				(type default)
			)
			(fill no)
			(layer "B.CrtYd")
		)
		(fp_poly
			(pts
				(arc
					(start 0 0.6096)
					(mid 0 -0.6096)
					(end 0 0.6096)
				)
			)
			(stroke
				(width 0)
				(type default)
			)
			(fill no)
			(layer "B.Fab")
		)
		(pad "1" smd circle
			(at 0 0 270)
			(size 0.7112 0.7112)
			(layers "B.Cu" "B.Mask" "B.Paste")
			(net "IOC_GPIO_1")
		)
	)
	(footprint ""
		(layer "B.Cu")
		(at 66.7004 -105.1306 180)
		(property "Reference" "R515"
			(at 0 0 0)
			(layer "B.SilkS")
			(hide yes)
			(effects
				(font
					(size 1.27 1.27)
				)
				(justify mirror)
			)
		)
		(property "Value" "2D2R3-1-U-GP"
			(at 0.0254 -2.5146 180)
			(unlocked yes)
			(layer "B.Fab")
			(hide yes)
			(effects
				(font
					(size 1.016 1.016)
					(thickness 0.1524)
				)
				(justify mirror)
			)
		)
		(property "Device Type" "R603H22"
			(at 0.0254 -4.0386 180)
			(unlocked yes)
			(layer "B.Fab")
			(hide yes)
			(effects
				(font
					(size 1.016 1.016)
					(thickness 0.1524)
				)
				(justify mirror)
			)
		)
		(duplicate_pad_numbers_are_jumpers no)
		(fp_line
			(start 0.4826 0)
			(end 0.2032 0)
			(stroke
				(width 0.2032)
				(type default)
			)
			(layer "B.SilkS")
		)
		(fp_line
			(start -0.2032 0)
			(end -0.4826 0)
			(stroke
				(width 0.2032)
				(type default)
			)
			(layer "B.SilkS")
		)
		(fp_rect
			(start 0.5842 1.3335)
			(end -0.5842 -1.3335)
			(stroke
				(width 0)
				(type default)
			)
			(fill no)
			(layer "B.CrtYd")
		)
		(fp_rect
			(start 0.5842 1.3335)
			(end -0.5842 -1.3335)
			(stroke
				(width 0)
				(type default)
			)
			(fill no)
			(layer "B.Fab")
		)
		(pad "1" smd custom
			(at 0 -0.762)
			(size 0.2159 0.2159)
			(layers "B.Cu" "B.Mask" "B.Paste")
			(net "P3V3_VBST")
			(options
				(clearance outline)
				(anchor circle)
			)
			(primitives
				(gr_poly
					(pts
						(arc
							(start -0.3302 0.4318)
							(mid -0.402042 0.402042)
							(end -0.4318 0.3302)
						)
						(arc
							(start -0.4318 -0.3302)
							(mid -0.402042 -0.402042)
							(end -0.3302 -0.4318)
						)
						(arc
							(start 0.3302 -0.4318)
							(mid 0.402042 -0.402042)
							(end 0.4318 -0.3302)
						)
						(arc
							(start 0.4318 0.3302)
							(mid 0.402042 0.402042)
							(end 0.3302 0.4318)
						)
					)
					(width 0)
					(fill yes)
				)
			)
		)
		(pad "2" smd custom
			(at 0 0.762)
			(size 0.2159 0.2159)
			(layers "B.Cu" "B.Mask" "B.Paste")
			(net "P3V3_VBST_RC")
			(options
				(clearance outline)
				(anchor circle)
			)
			(primitives
				(gr_poly
					(pts
						(arc
							(start -0.3302 0.4318)
							(mid -0.402042 0.402042)
							(end -0.4318 0.3302)
						)
						(arc
							(start -0.4318 -0.3302)
							(mid -0.402042 -0.402042)
							(end -0.3302 -0.4318)
						)
						(arc
							(start 0.3302 -0.4318)
							(mid 0.402042 -0.402042)
							(end 0.4318 -0.3302)
						)
						(arc
							(start 0.4318 0.3302)
							(mid 0.402042 0.402042)
							(end 0.3302 0.4318)
						)
					)
					(width 0)
					(fill yes)
				)
			)
		)
	)
	(footprint ""
		(layer "B.Cu")
		(at 136.2202 -79.0448 -90)
		(property "Reference" "C3"
			(at 0 0 90)
			(layer "B.SilkS")
			(hide yes)
			(effects
				(font
					(size 1.27 1.27)
				)
				(justify mirror)
			)
		)
		(property "Value" "SCD01U16V1KX-GP"
			(at 2.8321 -1.7399 270)
			(unlocked yes)
			(layer "B.Fab")
			(hide yes)
			(effects
				(font
					(size 1.016 1.016)
					(thickness 0.1524)
				)
				(justify mirror)
			)
		)
		(property "Device Type" "C0201H13"
			(at 2.8321 -3.2639 270)
			(unlocked yes)
			(layer "B.Fab")
			(hide yes)
			(effects
				(font
					(size 1.016 1.016)
					(thickness 0.1524)
				)
				(justify mirror)
			)
		)
		(duplicate_pad_numbers_are_jumpers no)
		(fp_rect
			(start 0.2794 0.6477)
			(end -0.2794 -0.6477)
			(stroke
				(width 0)
				(type default)
			)
			(fill no)
			(layer "B.CrtYd")
		)
		(fp_rect
			(start 0.2794 0.6477)
			(end -0.2794 -0.6477)
			(stroke
				(width 0)
				(type default)
			)
			(fill no)
			(layer "B.Fab")
		)
		(pad "1" smd custom
			(at 0 -0.2794 90)
			(size 0.0762 0.0762)
			(layers "B.Cu" "B.Mask" "B.Paste")
			(net "PHY_CONN_TO_EXP_10_DP")
			(options
				(clearance outline)
				(anchor circle)
			)
			(primitives
				(gr_poly
					(pts
						(arc
							(start 0.1524 0.127)
							(mid 0.137521 0.162921)
							(end 0.1016 0.1778)
						)
						(arc
							(start -0.1016 0.1778)
							(mid -0.137521 0.162921)
							(end -0.1524 0.127)
						)
						(arc
							(start -0.1524 -0.127)
							(mid -0.137521 -0.162921)
							(end -0.1016 -0.1778)
						)
						(arc
							(start 0.1016 -0.1778)
							(mid 0.137521 -0.162921)
							(end 0.1524 -0.127)
						)
					)
					(width 0)
					(fill yes)
				)
			)
		)
		(pad "2" smd custom
			(at 0 0.2794 90)
			(size 0.0762 0.0762)
			(layers "B.Cu" "B.Mask" "B.Paste")
			(net "PHY_CONN_TO_EXP_C_10_DP")
			(options
				(clearance outline)
				(anchor circle)
			)
			(primitives
				(gr_poly
					(pts
						(arc
							(start 0.1524 0.127)
							(mid 0.137521 0.162921)
							(end 0.1016 0.1778)
						)
						(arc
							(start -0.1016 0.1778)
							(mid -0.137521 0.162921)
							(end -0.1524 0.127)
						)
						(arc
							(start -0.1524 -0.127)
							(mid -0.137521 -0.162921)
							(end -0.1016 -0.1778)
						)
						(arc
							(start 0.1016 -0.1778)
							(mid 0.137521 -0.162921)
							(end 0.1524 -0.127)
						)
					)
					(width 0)
					(fill yes)
				)
			)
		)
	)
	(footprint ""
		(layer "B.Cu")
		(at 105.283 -67.056)
		(property "Reference" "C211"
			(at 0 0 0)
			(layer "B.SilkS")
			(hide yes)
			(effects
				(font
					(size 1.27 1.27)
				)
				(justify mirror)
			)
		)
		(property "Value" "SCD1U6D3V1KX-GP"
			(at 2.8321 -1.7399 0)
			(unlocked yes)
			(layer "B.Fab")
			(hide yes)
			(effects
				(font
					(size 1.016 1.016)
					(thickness 0.1524)
				)
				(justify mirror)
			)
		)
		(property "Device Type" "C0201H13"
			(at 2.8321 -3.2639 0)
			(unlocked yes)
			(layer "B.Fab")
			(hide yes)
			(effects
				(font
					(size 1.016 1.016)
					(thickness 0.1524)
				)
				(justify mirror)
			)
		)
		(duplicate_pad_numbers_are_jumpers no)
		(fp_rect
			(start 0.2794 0.6477)
			(end -0.2794 -0.6477)
			(stroke
				(width 0)
				(type default)
			)
			(fill no)
			(layer "B.CrtYd")
		)
		(fp_rect
			(start 0.2794 0.6477)
			(end -0.2794 -0.6477)
			(stroke
				(width 0)
				(type default)
			)
			(fill no)
			(layer "B.Fab")
		)
		(pad "1" smd custom
			(at 0 -0.2794 180)
			(size 0.0762 0.0762)
			(layers "B.Cu" "B.Mask" "B.Paste")
			(net "SYSPLL_VDDA09")
			(options
				(clearance outline)
				(anchor circle)
			)
			(primitives
				(gr_poly
					(pts
						(arc
							(start 0.1524 0.127)
							(mid 0.137521 0.162921)
							(end 0.1016 0.1778)
						)
						(arc
							(start -0.1016 0.1778)
							(mid -0.137521 0.162921)
							(end -0.1524 0.127)
						)
						(arc
							(start -0.1524 -0.127)
							(mid -0.137521 -0.162921)
							(end -0.1016 -0.1778)
						)
						(arc
							(start 0.1016 -0.1778)
							(mid 0.137521 -0.162921)
							(end 0.1524 -0.127)
						)
					)
					(width 0)
					(fill yes)
				)
			)
		)
		(pad "2" smd custom
			(at 0 0.2794 180)
			(size 0.0762 0.0762)
			(layers "B.Cu" "B.Mask" "B.Paste")
			(net "GND")
			(options
				(clearance outline)
				(anchor circle)
			)
			(primitives
				(gr_poly
					(pts
						(arc
							(start 0.1524 0.127)
							(mid 0.137521 0.162921)
							(end 0.1016 0.1778)
						)
						(arc
							(start -0.1016 0.1778)
							(mid -0.137521 0.162921)
							(end -0.1524 0.127)
						)
						(arc
							(start -0.1524 -0.127)
							(mid -0.137521 -0.162921)
							(end -0.1016 -0.1778)
						)
						(arc
							(start 0.1016 -0.1778)
							(mid 0.137521 -0.162921)
							(end 0.1524 -0.127)
						)
					)
					(width 0)
					(fill yes)
				)
			)
		)
	)
	(footprint ""
		(layer "B.Cu")
		(at 118.754398 -68.629784)
		(property "Reference" "C183"
			(at 0 0 0)
			(layer "B.SilkS")
			(hide yes)
			(effects
				(font
					(size 1.27 1.27)
				)
				(justify mirror)
			)
		)
		(property "Value" "SC10U6D3V2MX-GP-U"
			(at 1.524 -1.905 0)
			(unlocked yes)
			(layer "B.Fab")
			(hide yes)
			(effects
				(font
					(size 1.016 1.016)
					(thickness 0.1524)
				)
				(justify mirror)
			)
		)
		(property "Device Type" "C402-TO0D2H28"
			(at 1.524 -3.429 0)
			(unlocked yes)
			(layer "B.Fab")
			(hide yes)
			(effects
				(font
					(size 1.016 1.016)
					(thickness 0.1524)
				)
				(justify mirror)
			)
		)
		(duplicate_pad_numbers_are_jumpers no)
		(fp_rect
			(start 0.4826 0.889)
			(end -0.4826 -0.889)
			(stroke
				(width 0)
				(type default)
			)
			(fill no)
			(layer "B.CrtYd")
		)
		(fp_rect
			(start 0.4826 0.889)
			(end -0.4826 -0.889)
			(stroke
				(width 0)
				(type default)
			)
			(fill no)
			(layer "B.Fab")
		)
		(pad "1" smd custom
			(at 0 -0.4572 180)
			(size 0.1524 0.1524)
			(layers "B.Cu" "B.Mask" "B.Paste")
			(net "P0V9")
			(options
				(clearance outline)
				(anchor circle)
			)
			(primitives
				(gr_poly
					(pts
						(arc
							(start -0.254 -0.3048)
							(mid -0.325842 -0.275042)
							(end -0.3556 -0.2032)
						)
						(arc
							(start -0.3556 0.2032)
							(mid -0.325842 0.275042)
							(end -0.254 0.3048)
						)
						(arc
							(start 0.254 0.3048)
							(mid 0.325842 0.275042)
							(end 0.3556 0.2032)
						)
						(arc
							(start 0.3556 -0.2032)
							(mid 0.325842 -0.275042)
							(end 0.254 -0.3048)
						)
					)
					(width 0)
					(fill yes)
				)
			)
		)
		(pad "2" smd custom
			(at 0 0.4572 180)
			(size 0.1524 0.1524)
			(layers "B.Cu" "B.Mask" "B.Paste")
			(net "GND")
			(options
				(clearance outline)
				(anchor circle)
			)
			(primitives
				(gr_poly
					(pts
						(arc
							(start -0.254 -0.3048)
							(mid -0.325842 -0.275042)
							(end -0.3556 -0.2032)
						)
						(arc
							(start -0.3556 0.2032)
							(mid -0.325842 0.275042)
							(end -0.254 0.3048)
						)
						(arc
							(start 0.254 0.3048)
							(mid 0.325842 0.275042)
							(end 0.3556 0.2032)
						)
						(arc
							(start 0.3556 -0.2032)
							(mid 0.325842 -0.275042)
							(end 0.254 -0.3048)
						)
					)
					(width 0)
					(fill yes)
				)
			)
		)
	)
	(footprint ""
		(layer "B.Cu")
		(at 170.602148 -41.194482 -90)
		(property "Reference" "C409"
			(at 0 0 90)
			(layer "B.SilkS")
			(hide yes)
			(effects
				(font
					(size 1.27 1.27)
				)
				(justify mirror)
			)
		)
		(property "Value" "SC10U6D3V5KX-4GP"
			(at 0.0762 -6.1214 270)
			(unlocked yes)
			(layer "B.Fab")
			(hide yes)
			(effects
				(font
					(size 1.016 1.016)
					(thickness 0.1524)
				)
				(justify mirror)
			)
		)
		(property "Device Type" "C805H58"
			(at 0.0762 -8.1534 270)
			(unlocked yes)
			(layer "B.Fab")
			(hide yes)
			(effects
				(font
					(size 1.016 1.016)
					(thickness 0.1524)
				)
				(justify mirror)
			)
		)
		(duplicate_pad_numbers_are_jumpers no)
		(fp_line
			(start -0.635 0)
			(end 0.635 0)
			(stroke
				(width 0.508)
				(type default)
			)
			(layer "B.SilkS")
		)
		(fp_rect
			(start 0.9652 1.778)
			(end -0.9652 -1.778)
			(stroke
				(width 0)
				(type default)
			)
			(fill no)
			(layer "B.CrtYd")
		)
		(fp_poly
			(pts
				(xy 0.9652 -1.778) (xy -0.9652 -1.778) (xy -0.9652 1.778) (xy 0.9652 1.778)
			)
			(stroke
				(width 0)
				(type default)
			)
			(fill no)
			(layer "B.Fab")
		)
		(pad "1" smd rect
			(at 0 -0.9652 90)
			(size 1.397 1.143)
			(layers "B.Cu" "B.Mask" "B.Paste")
			(net "P0V975")
		)
		(pad "2" smd rect
			(at 0 0.9652 90)
			(size 1.397 1.143)
			(layers "B.Cu" "B.Mask" "B.Paste")
			(net "GND")
		)
	)
	(footprint ""
		(layer "B.Cu")
		(at 136.1694 -76.1492 -90)
		(property "Reference" "C8"
			(at 0 0 90)
			(layer "B.SilkS")
			(hide yes)
			(effects
				(font
					(size 1.27 1.27)
				)
				(justify mirror)
			)
		)
		(property "Value" "SCD01U16V1KX-GP"
			(at 2.8321 -1.7399 270)
			(unlocked yes)
			(layer "B.Fab")
			(hide yes)
			(effects
				(font
					(size 1.016 1.016)
					(thickness 0.1524)
				)
				(justify mirror)
			)
		)
		(property "Device Type" "C0201H13"
			(at 2.8321 -3.2639 270)
			(unlocked yes)
			(layer "B.Fab")
			(hide yes)
			(effects
				(font
					(size 1.016 1.016)
					(thickness 0.1524)
				)
				(justify mirror)
			)
		)
		(duplicate_pad_numbers_are_jumpers no)
		(fp_rect
			(start 0.2794 0.6477)
			(end -0.2794 -0.6477)
			(stroke
				(width 0)
				(type default)
			)
			(fill no)
			(layer "B.CrtYd")
		)
		(fp_rect
			(start 0.2794 0.6477)
			(end -0.2794 -0.6477)
			(stroke
				(width 0)
				(type default)
			)
			(fill no)
			(layer "B.Fab")
		)
		(pad "1" smd custom
			(at 0 -0.2794 90)
			(size 0.0762 0.0762)
			(layers "B.Cu" "B.Mask" "B.Paste")
			(net "PHY_CONN_TO_EXP_8_DN")
			(options
				(clearance outline)
				(anchor circle)
			)
			(primitives
				(gr_poly
					(pts
						(arc
							(start 0.1524 0.127)
							(mid 0.137521 0.162921)
							(end 0.1016 0.1778)
						)
						(arc
							(start -0.1016 0.1778)
							(mid -0.137521 0.162921)
							(end -0.1524 0.127)
						)
						(arc
							(start -0.1524 -0.127)
							(mid -0.137521 -0.162921)
							(end -0.1016 -0.1778)
						)
						(arc
							(start 0.1016 -0.1778)
							(mid 0.137521 -0.162921)
							(end 0.1524 -0.127)
						)
					)
					(width 0)
					(fill yes)
				)
			)
		)
		(pad "2" smd custom
			(at 0 0.2794 90)
			(size 0.0762 0.0762)
			(layers "B.Cu" "B.Mask" "B.Paste")
			(net "PHY_CONN_TO_EXP_C_8_DN")
			(options
				(clearance outline)
				(anchor circle)
			)
			(primitives
				(gr_poly
					(pts
						(arc
							(start 0.1524 0.127)
							(mid 0.137521 0.162921)
							(end 0.1016 0.1778)
						)
						(arc
							(start -0.1016 0.1778)
							(mid -0.137521 0.162921)
							(end -0.1524 0.127)
						)
						(arc
							(start -0.1524 -0.127)
							(mid -0.137521 -0.162921)
							(end -0.1016 -0.1778)
						)
						(arc
							(start 0.1016 -0.1778)
							(mid 0.137521 -0.162921)
							(end 0.1524 -0.127)
						)
					)
					(width 0)
					(fill yes)
				)
			)
		)
	)
	(footprint ""
		(layer "B.Cu")
		(at 119.117872 -70.427596 180)
		(property "Reference" "C188"
			(at 0 0 0)
			(layer "B.SilkS")
			(hide yes)
			(effects
				(font
					(size 1.27 1.27)
				)
				(justify mirror)
			)
		)
		(property "Value" "SC1KP25V1KX-GP"
			(at 2.8321 -1.7399 180)
			(unlocked yes)
			(layer "B.Fab")
			(hide yes)
			(effects
				(font
					(size 1.016 1.016)
					(thickness 0.1524)
				)
				(justify mirror)
			)
		)
		(property "Device Type" "C0201H13"
			(at 2.8321 -3.2639 180)
			(unlocked yes)
			(layer "B.Fab")
			(hide yes)
			(effects
				(font
					(size 1.016 1.016)
					(thickness 0.1524)
				)
				(justify mirror)
			)
		)
		(duplicate_pad_numbers_are_jumpers no)
		(fp_rect
			(start 0.2794 0.6477)
			(end -0.2794 -0.6477)
			(stroke
				(width 0)
				(type default)
			)
			(fill no)
			(layer "B.CrtYd")
		)
		(fp_rect
			(start 0.2794 0.6477)
			(end -0.2794 -0.6477)
			(stroke
				(width 0)
				(type default)
			)
			(fill no)
			(layer "B.Fab")
		)
		(pad "1" smd custom
			(at 0 -0.2794)
			(size 0.0762 0.0762)
			(layers "B.Cu" "B.Mask" "B.Paste")
			(net "P0V9")
			(options
				(clearance outline)
				(anchor circle)
			)
			(primitives
				(gr_poly
					(pts
						(arc
							(start 0.1524 0.127)
							(mid 0.137521 0.162921)
							(end 0.1016 0.1778)
						)
						(arc
							(start -0.1016 0.1778)
							(mid -0.137521 0.162921)
							(end -0.1524 0.127)
						)
						(arc
							(start -0.1524 -0.127)
							(mid -0.137521 -0.162921)
							(end -0.1016 -0.1778)
						)
						(arc
							(start 0.1016 -0.1778)
							(mid 0.137521 -0.162921)
							(end 0.1524 -0.127)
						)
					)
					(width 0)
					(fill yes)
				)
			)
		)
		(pad "2" smd custom
			(at 0 0.2794)
			(size 0.0762 0.0762)
			(layers "B.Cu" "B.Mask" "B.Paste")
			(net "GND")
			(options
				(clearance outline)
				(anchor circle)
			)
			(primitives
				(gr_poly
					(pts
						(arc
							(start 0.1524 0.127)
							(mid 0.137521 0.162921)
							(end 0.1016 0.1778)
						)
						(arc
							(start -0.1016 0.1778)
							(mid -0.137521 0.162921)
							(end -0.1524 0.127)
						)
						(arc
							(start -0.1524 -0.127)
							(mid -0.137521 -0.162921)
							(end -0.1016 -0.1778)
						)
						(arc
							(start 0.1016 -0.1778)
							(mid 0.137521 -0.162921)
							(end 0.1524 -0.127)
						)
					)
					(width 0)
					(fill yes)
				)
			)
		)
	)
	(footprint ""
		(layer "B.Cu")
		(at 202.820778 -33.170622 -90)
		(property "Reference" "R280"
			(at 0 0 90)
			(layer "B.SilkS")
			(hide yes)
			(effects
				(font
					(size 1.27 1.27)
				)
				(justify mirror)
			)
		)
		(property "Value" "10R2F-L-GP"
			(at -0.064008 -3.993896 270)
			(unlocked yes)
			(layer "B.Fab")
			(hide yes)
			(effects
				(font
					(size 1.016 1.016)
					(thickness 0.1524)
				)
				(justify mirror)
			)
		)
		(property "Device Type" "R402H14"
			(at -0.064008 -5.517896 270)
			(unlocked yes)
			(layer "B.Fab")
			(hide yes)
			(effects
				(font
					(size 1.016 1.016)
					(thickness 0.1524)
				)
				(justify mirror)
			)
		)
		(duplicate_pad_numbers_are_jumpers no)
		(fp_line
			(start -0.508 -0.9398)
			(end 0.508 -0.9398)
			(stroke
				(width 0.1524)
				(type default)
			)
			(layer "B.SilkS")
		)
		(fp_line
			(start 0.508 -0.9398)
			(end 0.508 0.9398)
			(stroke
				(width 0.1524)
				(type default)
			)
			(layer "B.SilkS")
		)
		(fp_rect
			(start 0.508 0.9398)
			(end -0.508 -0.9398)
			(stroke
				(width 0)
				(type default)
			)
			(fill no)
			(layer "B.CrtYd")
		)
		(fp_rect
			(start 0.508 0.9398)
			(end -0.508 -0.9398)
			(stroke
				(width 0)
				(type default)
			)
			(fill no)
			(layer "B.Fab")
		)
		(pad "1" smd custom
			(at 0 -0.4445 90)
			(size 0.1397 0.1397)
			(layers "B.Cu" "B.Mask" "B.Paste")
			(net "P1V8_C")
			(options
				(clearance outline)
				(anchor circle)
			)
			(primitives
				(gr_poly
					(pts
						(arc
							(start -0.1778 0.2794)
							(mid -0.249642 0.249642)
							(end -0.2794 0.1778)
						)
						(arc
							(start -0.2794 -0.1778)
							(mid -0.249642 -0.249642)
							(end -0.1778 -0.2794)
						)
						(arc
							(start 0.1778 -0.2794)
							(mid 0.249642 -0.249642)
							(end 0.2794 -0.1778)
						)
						(arc
							(start 0.2794 0.1778)
							(mid 0.249642 0.249642)
							(end 0.1778 0.2794)
						)
					)
					(width 0)
					(fill yes)
				)
			)
		)
		(pad "2" smd custom
			(at 0 0.4445 90)
			(size 0.1397 0.1397)
			(layers "B.Cu" "B.Mask" "B.Paste")
			(net "PLL_VDD")
			(options
				(clearance outline)
				(anchor circle)
			)
			(primitives
				(gr_poly
					(pts
						(arc
							(start -0.1778 0.2794)
							(mid -0.249642 0.249642)
							(end -0.2794 0.1778)
						)
						(arc
							(start -0.2794 -0.1778)
							(mid -0.249642 -0.249642)
							(end -0.1778 -0.2794)
						)
						(arc
							(start 0.1778 -0.2794)
							(mid 0.249642 -0.249642)
							(end 0.2794 -0.1778)
						)
						(arc
							(start 0.2794 0.1778)
							(mid 0.249642 0.249642)
							(end 0.1778 0.2794)
						)
					)
					(width 0)
					(fill yes)
				)
			)
		)
	)
	(footprint ""
		(layer "B.Cu")
		(at 176.22139 -40.268144 90)
		(property "Reference" "C430"
			(at 0 0 90)
			(layer "B.SilkS")
			(hide yes)
			(effects
				(font
					(size 1.27 1.27)
				)
				(justify mirror)
			)
		)
		(property "Value" "SCD1U6D3V1KX-GP"
			(at 2.8321 -1.7399 90)
			(unlocked yes)
			(layer "B.Fab")
			(hide yes)
			(effects
				(font
					(size 1.016 1.016)
					(thickness 0.1524)
				)
				(justify mirror)
			)
		)
		(property "Device Type" "C0201H13"
			(at 2.8321 -3.2639 90)
			(unlocked yes)
			(layer "B.Fab")
			(hide yes)
			(effects
				(font
					(size 1.016 1.016)
					(thickness 0.1524)
				)
				(justify mirror)
			)
		)
		(duplicate_pad_numbers_are_jumpers no)
		(fp_rect
			(start 0.2794 0.6477)
			(end -0.2794 -0.6477)
			(stroke
				(width 0)
				(type default)
			)
			(fill no)
			(layer "B.CrtYd")
		)
		(fp_rect
			(start 0.2794 0.6477)
			(end -0.2794 -0.6477)
			(stroke
				(width 0)
				(type default)
			)
			(fill no)
			(layer "B.Fab")
		)
		(pad "1" smd custom
			(at 0 -0.2794 270)
			(size 0.0762 0.0762)
			(layers "B.Cu" "B.Mask" "B.Paste")
			(net "P0V975")
			(options
				(clearance outline)
				(anchor circle)
			)
			(primitives
				(gr_poly
					(pts
						(arc
							(start 0.1524 0.127)
							(mid 0.137521 0.162921)
							(end 0.1016 0.1778)
						)
						(arc
							(start -0.1016 0.1778)
							(mid -0.137521 0.162921)
							(end -0.1524 0.127)
						)
						(arc
							(start -0.1524 -0.127)
							(mid -0.137521 -0.162921)
							(end -0.1016 -0.1778)
						)
						(arc
							(start 0.1016 -0.1778)
							(mid 0.137521 -0.162921)
							(end 0.1524 -0.127)
						)
					)
					(width 0)
					(fill yes)
				)
			)
		)
		(pad "2" smd custom
			(at 0 0.2794 270)
			(size 0.0762 0.0762)
			(layers "B.Cu" "B.Mask" "B.Paste")
			(net "GND")
			(options
				(clearance outline)
				(anchor circle)
			)
			(primitives
				(gr_poly
					(pts
						(arc
							(start 0.1524 0.127)
							(mid 0.137521 0.162921)
							(end 0.1016 0.1778)
						)
						(arc
							(start -0.1016 0.1778)
							(mid -0.137521 0.162921)
							(end -0.1524 0.127)
						)
						(arc
							(start -0.1524 -0.127)
							(mid -0.137521 -0.162921)
							(end -0.1016 -0.1778)
						)
						(arc
							(start 0.1016 -0.1778)
							(mid 0.137521 -0.162921)
							(end 0.1524 -0.127)
						)
					)
					(width 0)
					(fill yes)
				)
			)
		)
	)
	(footprint ""
		(layer "B.Cu")
		(at 127.5588 -92.026486)
		(property "Reference" "R110"
			(at 0 0 0)
			(layer "B.SilkS")
			(hide yes)
			(effects
				(font
					(size 1.27 1.27)
				)
				(justify mirror)
			)
		)
		(property "Value" "4K75R2F-1-GP"
			(at -0.064008 -3.993896 0)
			(unlocked yes)
			(layer "B.Fab")
			(hide yes)
			(effects
				(font
					(size 1.016 1.016)
					(thickness 0.1524)
				)
				(justify mirror)
			)
		)
		(property "Device Type" "R402H16"
			(at -0.064008 -5.517896 0)
			(unlocked yes)
			(layer "B.Fab")
			(hide yes)
			(effects
				(font
					(size 1.016 1.016)
					(thickness 0.1524)
				)
				(justify mirror)
			)
		)
		(duplicate_pad_numbers_are_jumpers no)
		(fp_line
			(start -0.508 -0.9398)
			(end 0.508 -0.9398)
			(stroke
				(width 0.1524)
				(type default)
			)
			(layer "B.SilkS")
		)
		(fp_line
			(start 0.508 -0.9398)
			(end 0.508 0.9398)
			(stroke
				(width 0.1524)
				(type default)
			)
			(layer "B.SilkS")
		)
		(fp_rect
			(start 0.508 0.9398)
			(end -0.508 -0.9398)
			(stroke
				(width 0)
				(type default)
			)
			(fill no)
			(layer "B.CrtYd")
		)
		(fp_rect
			(start 0.508 0.9398)
			(end -0.508 -0.9398)
			(stroke
				(width 0)
				(type default)
			)
			(fill no)
			(layer "B.Fab")
		)
		(pad "1" smd custom
			(at 0 -0.4445 180)
			(size 0.1397 0.1397)
			(layers "B.Cu" "B.Mask" "B.Paste")
			(net "GND")
			(options
				(clearance outline)
				(anchor circle)
			)
			(primitives
				(gr_poly
					(pts
						(arc
							(start -0.1778 0.2794)
							(mid -0.249642 0.249642)
							(end -0.2794 0.1778)
						)
						(arc
							(start -0.2794 -0.1778)
							(mid -0.249642 -0.249642)
							(end -0.1778 -0.2794)
						)
						(arc
							(start 0.1778 -0.2794)
							(mid 0.249642 -0.249642)
							(end 0.2794 -0.1778)
						)
						(arc
							(start 0.2794 0.1778)
							(mid 0.249642 0.249642)
							(end 0.1778 0.2794)
						)
					)
					(width 0)
					(fill yes)
				)
			)
		)
		(pad "2" smd custom
			(at 0 0.4445 180)
			(size 0.1397 0.1397)
			(layers "B.Cu" "B.Mask" "B.Paste")
			(net "LSI_EFUSE")
			(options
				(clearance outline)
				(anchor circle)
			)
			(primitives
				(gr_poly
					(pts
						(arc
							(start -0.1778 0.2794)
							(mid -0.249642 0.249642)
							(end -0.2794 0.1778)
						)
						(arc
							(start -0.2794 -0.1778)
							(mid -0.249642 -0.249642)
							(end -0.1778 -0.2794)
						)
						(arc
							(start 0.1778 -0.2794)
							(mid 0.249642 -0.249642)
							(end 0.2794 -0.1778)
						)
						(arc
							(start 0.2794 0.1778)
							(mid 0.249642 0.249642)
							(end 0.1778 0.2794)
						)
					)
					(width 0)
					(fill yes)
				)
			)
		)
	)
	(footprint ""
		(layer "B.Cu")
		(at 90.988388 -74.762614)
		(property "Reference" "R154"
			(at 0 0 0)
			(layer "B.SilkS")
			(hide yes)
			(effects
				(font
					(size 1.27 1.27)
				)
				(justify mirror)
			)
		)
		(property "Value" "10R2F-L-GP"
			(at -0.064008 -3.993896 0)
			(unlocked yes)
			(layer "B.Fab")
			(hide yes)
			(effects
				(font
					(size 1.016 1.016)
					(thickness 0.1524)
				)
				(justify mirror)
			)
		)
		(property "Device Type" "R402H14"
			(at -0.064008 -5.517896 0)
			(unlocked yes)
			(layer "B.Fab")
			(hide yes)
			(effects
				(font
					(size 1.016 1.016)
					(thickness 0.1524)
				)
				(justify mirror)
			)
		)
		(duplicate_pad_numbers_are_jumpers no)
		(fp_line
			(start -0.508 -0.9398)
			(end 0.508 -0.9398)
			(stroke
				(width 0.1524)
				(type default)
			)
			(layer "B.SilkS")
		)
		(fp_line
			(start 0.508 -0.9398)
			(end 0.508 0.9398)
			(stroke
				(width 0.1524)
				(type default)
			)
			(layer "B.SilkS")
		)
		(fp_rect
			(start 0.508 0.9398)
			(end -0.508 -0.9398)
			(stroke
				(width 0)
				(type default)
			)
			(fill no)
			(layer "B.CrtYd")
		)
		(fp_rect
			(start 0.508 0.9398)
			(end -0.508 -0.9398)
			(stroke
				(width 0)
				(type default)
			)
			(fill no)
			(layer "B.Fab")
		)
		(pad "1" smd custom
			(at 0 -0.4445 180)
			(size 0.1397 0.1397)
			(layers "B.Cu" "B.Mask" "B.Paste")
			(net "P0V9")
			(options
				(clearance outline)
				(anchor circle)
			)
			(primitives
				(gr_poly
					(pts
						(arc
							(start -0.1778 0.2794)
							(mid -0.249642 0.249642)
							(end -0.2794 0.1778)
						)
						(arc
							(start -0.2794 -0.1778)
							(mid -0.249642 -0.249642)
							(end -0.1778 -0.2794)
						)
						(arc
							(start 0.1778 -0.2794)
							(mid 0.249642 -0.249642)
							(end 0.2794 -0.1778)
						)
						(arc
							(start 0.2794 0.1778)
							(mid 0.249642 0.249642)
							(end 0.1778 0.2794)
						)
					)
					(width 0)
					(fill yes)
				)
			)
		)
		(pad "2" smd custom
			(at 0 0.4445 180)
			(size 0.1397 0.1397)
			(layers "B.Cu" "B.Mask" "B.Paste")
			(net "XTAL_VDDA09")
			(options
				(clearance outline)
				(anchor circle)
			)
			(primitives
				(gr_poly
					(pts
						(arc
							(start -0.1778 0.2794)
							(mid -0.249642 0.249642)
							(end -0.2794 0.1778)
						)
						(arc
							(start -0.2794 -0.1778)
							(mid -0.249642 -0.249642)
							(end -0.1778 -0.2794)
						)
						(arc
							(start 0.1778 -0.2794)
							(mid 0.249642 -0.249642)
							(end 0.2794 -0.1778)
						)
						(arc
							(start 0.2794 0.1778)
							(mid 0.249642 0.249642)
							(end 0.1778 0.2794)
						)
					)
					(width 0)
					(fill yes)
				)
			)
		)
	)
	(footprint ""
		(layer "B.Cu")
		(at 122.4788 -63.4873 -90)
		(property "Reference" "C536"
			(at 0 0 90)
			(layer "B.SilkS")
			(hide yes)
			(effects
				(font
					(size 1.27 1.27)
				)
				(justify mirror)
			)
		)
		(property "Value" "SCD1U6D3V1KX-GP"
			(at 2.8321 -1.7399 270)
			(unlocked yes)
			(layer "B.Fab")
			(hide yes)
			(effects
				(font
					(size 1.016 1.016)
					(thickness 0.1524)
				)
				(justify mirror)
			)
		)
		(property "Device Type" "C0201H13"
			(at 2.8321 -3.2639 270)
			(unlocked yes)
			(layer "B.Fab")
			(hide yes)
			(effects
				(font
					(size 1.016 1.016)
					(thickness 0.1524)
				)
				(justify mirror)
			)
		)
		(duplicate_pad_numbers_are_jumpers no)
		(fp_rect
			(start 0.2794 0.6477)
			(end -0.2794 -0.6477)
			(stroke
				(width 0)
				(type default)
			)
			(fill no)
			(layer "B.CrtYd")
		)
		(fp_rect
			(start 0.2794 0.6477)
			(end -0.2794 -0.6477)
			(stroke
				(width 0)
				(type default)
			)
			(fill no)
			(layer "B.Fab")
		)
		(pad "1" smd custom
			(at 0 -0.2794 90)
			(size 0.0762 0.0762)
			(layers "B.Cu" "B.Mask" "B.Paste")
			(net "GB_VDDA")
			(options
				(clearance outline)
				(anchor circle)
			)
			(primitives
				(gr_poly
					(pts
						(arc
							(start 0.1524 0.127)
							(mid 0.137521 0.162921)
							(end 0.1016 0.1778)
						)
						(arc
							(start -0.1016 0.1778)
							(mid -0.137521 0.162921)
							(end -0.1524 0.127)
						)
						(arc
							(start -0.1524 -0.127)
							(mid -0.137521 -0.162921)
							(end -0.1016 -0.1778)
						)
						(arc
							(start 0.1016 -0.1778)
							(mid 0.137521 -0.162921)
							(end 0.1524 -0.127)
						)
					)
					(width 0)
					(fill yes)
				)
			)
		)
		(pad "2" smd custom
			(at 0 0.2794 90)
			(size 0.0762 0.0762)
			(layers "B.Cu" "B.Mask" "B.Paste")
			(net "GND")
			(options
				(clearance outline)
				(anchor circle)
			)
			(primitives
				(gr_poly
					(pts
						(arc
							(start 0.1524 0.127)
							(mid 0.137521 0.162921)
							(end 0.1016 0.1778)
						)
						(arc
							(start -0.1016 0.1778)
							(mid -0.137521 0.162921)
							(end -0.1524 0.127)
						)
						(arc
							(start -0.1524 -0.127)
							(mid -0.137521 -0.162921)
							(end -0.1016 -0.1778)
						)
						(arc
							(start 0.1016 -0.1778)
							(mid 0.137521 -0.162921)
							(end 0.1524 -0.127)
						)
					)
					(width 0)
					(fill yes)
				)
			)
		)
	)
	(footprint ""
		(layer "B.Cu")
		(at 125.5014 -73.8378 180)
		(property "Reference" "C274"
			(at 0 0 0)
			(layer "B.SilkS")
			(hide yes)
			(effects
				(font
					(size 1.27 1.27)
				)
				(justify mirror)
			)
		)
		(property "Value" "SC1U6D3V1MX-GP"
			(at -1.9177 2.0193 180)
			(unlocked yes)
			(layer "B.Fab")
			(hide yes)
			(effects
				(font
					(size 1.016 1.016)
					(thickness 0.1524)
				)
				(justify mirror)
			)
		)
		(property "Device Type" "C0201H14"
			(at -1.9177 0.4953 180)
			(unlocked yes)
			(layer "B.Fab")
			(hide yes)
			(effects
				(font
					(size 1.016 1.016)
					(thickness 0.1524)
				)
				(justify mirror)
			)
		)
		(duplicate_pad_numbers_are_jumpers no)
		(fp_rect
			(start 0.1524 0.3048)
			(end -0.1524 -0.3048)
			(stroke
				(width 0)
				(type default)
			)
			(fill no)
			(layer "B.CrtYd")
		)
		(fp_poly
			(pts
				(xy 0.2794 0.6477) (xy 0.2794 -0.6477) (xy -0.2794 -0.6477) (xy -0.2794 -0.1905) (xy -0.1524 -0.1905)
				(xy -0.1524 -0.3048) (xy 0.1524 -0.3048) (xy 0.1524 0.3048) (xy -0.1524 0.3048) (xy -0.1524 -0.1778)
				(xy -0.2794 -0.1778) (xy -0.2794 0.6477)
			)
			(stroke
				(width 0)
				(type default)
			)
			(fill no)
			(layer "B.CrtYd")
		)
		(fp_rect
			(start 0.2794 0.6477)
			(end -0.2794 -0.6477)
			(stroke
				(width 0)
				(type default)
			)
			(fill no)
			(layer "B.Fab")
		)
		(pad "1" smd custom
			(at 0 -0.2794)
			(size 0.0762 0.0762)
			(layers "B.Cu" "B.Mask" "B.Paste")
			(net "GB_VDDA")
			(options
				(clearance outline)
				(anchor circle)
			)
			(primitives
				(gr_poly
					(pts
						(arc
							(start 0.1524 0.127)
							(mid 0.137521 0.162921)
							(end 0.1016 0.1778)
						)
						(arc
							(start -0.1016 0.1778)
							(mid -0.137521 0.162921)
							(end -0.1524 0.127)
						)
						(arc
							(start -0.1524 -0.127)
							(mid -0.137521 -0.162921)
							(end -0.1016 -0.1778)
						)
						(arc
							(start 0.1016 -0.1778)
							(mid 0.137521 -0.162921)
							(end 0.1524 -0.127)
						)
					)
					(width 0)
					(fill yes)
				)
			)
		)
		(pad "2" smd custom
			(at 0 0.2794)
			(size 0.0762 0.0762)
			(layers "B.Cu" "B.Mask" "B.Paste")
			(net "GND")
			(options
				(clearance outline)
				(anchor circle)
			)
			(primitives
				(gr_poly
					(pts
						(arc
							(start 0.1524 0.127)
							(mid 0.137521 0.162921)
							(end 0.1016 0.1778)
						)
						(arc
							(start -0.1016 0.1778)
							(mid -0.137521 0.162921)
							(end -0.1524 0.127)
						)
						(arc
							(start -0.1524 -0.127)
							(mid -0.137521 -0.162921)
							(end -0.1016 -0.1778)
						)
						(arc
							(start 0.1016 -0.1778)
							(mid 0.137521 -0.162921)
							(end 0.1524 -0.127)
						)
					)
					(width 0)
					(fill yes)
				)
			)
		)
	)
	(footprint ""
		(layer "B.Cu")
		(at 70.612 -51.943 90)
		(property "Reference" "R159"
			(at 0 0 90)
			(layer "B.SilkS")
			(hide yes)
			(effects
				(font
					(size 1.27 1.27)
				)
				(justify mirror)
			)
		)
		(property "Value" "D51R3F-2-GP"
			(at 0.0254 -2.5146 90)
			(unlocked yes)
			(layer "B.Fab")
			(hide yes)
			(effects
				(font
					(size 1.016 1.016)
					(thickness 0.1524)
				)
				(justify mirror)
			)
		)
		(property "Device Type" "R603H22"
			(at 0.0254 -4.0386 90)
			(unlocked yes)
			(layer "B.Fab")
			(hide yes)
			(effects
				(font
					(size 1.016 1.016)
					(thickness 0.1524)
				)
				(justify mirror)
			)
		)
		(duplicate_pad_numbers_are_jumpers no)
		(fp_line
			(start 0.4826 0)
			(end 0.2032 0)
			(stroke
				(width 0.2032)
				(type default)
			)
			(layer "B.SilkS")
		)
		(fp_line
			(start -0.2032 0)
			(end -0.4826 0)
			(stroke
				(width 0.2032)
				(type default)
			)
			(layer "B.SilkS")
		)
		(fp_rect
			(start 0.5842 1.3335)
			(end -0.5842 -1.3335)
			(stroke
				(width 0)
				(type default)
			)
			(fill no)
			(layer "B.CrtYd")
		)
		(fp_rect
			(start 0.5842 1.3335)
			(end -0.5842 -1.3335)
			(stroke
				(width 0)
				(type default)
			)
			(fill no)
			(layer "B.Fab")
		)
		(pad "1" smd custom
			(at 0 -0.762 270)
			(size 0.2159 0.2159)
			(layers "B.Cu" "B.Mask" "B.Paste")
			(net "P0V9")
			(options
				(clearance outline)
				(anchor circle)
			)
			(primitives
				(gr_poly
					(pts
						(arc
							(start -0.3302 0.4318)
							(mid -0.402042 0.402042)
							(end -0.4318 0.3302)
						)
						(arc
							(start -0.4318 -0.3302)
							(mid -0.402042 -0.402042)
							(end -0.3302 -0.4318)
						)
						(arc
							(start 0.3302 -0.4318)
							(mid 0.402042 -0.402042)
							(end 0.4318 -0.3302)
						)
						(arc
							(start 0.4318 0.3302)
							(mid 0.402042 0.402042)
							(end 0.3302 0.4318)
						)
					)
					(width 0)
					(fill yes)
				)
			)
		)
		(pad "2" smd custom
			(at 0 0.762 270)
			(size 0.2159 0.2159)
			(layers "B.Cu" "B.Mask" "B.Paste")
			(net "GB_VDDA")
			(options
				(clearance outline)
				(anchor circle)
			)
			(primitives
				(gr_poly
					(pts
						(arc
							(start -0.3302 0.4318)
							(mid -0.402042 0.402042)
							(end -0.4318 0.3302)
						)
						(arc
							(start -0.4318 -0.3302)
							(mid -0.402042 -0.402042)
							(end -0.3302 -0.4318)
						)
						(arc
							(start 0.3302 -0.4318)
							(mid 0.402042 -0.402042)
							(end 0.4318 -0.3302)
						)
						(arc
							(start 0.4318 0.3302)
							(mid 0.402042 0.402042)
							(end 0.3302 0.4318)
						)
					)
					(width 0)
					(fill yes)
				)
			)
		)
	)
	(footprint ""
		(layer "B.Cu")
		(at 126.3777 -82.3341)
		(property "Reference" "TP161"
			(at 0 0 0)
			(layer "B.SilkS")
			(hide yes)
			(effects
				(font
					(size 1.27 1.27)
				)
				(justify mirror)
			)
		)
		(property "Value" "TPAD28-2-GP"
			(at 0.0127 -1.6637 0)
			(unlocked yes)
			(layer "B.Fab")
			(hide yes)
			(effects
				(font
					(size 1.016 1.016)
					(thickness 0.1524)
				)
				(justify mirror)
			)
		)
		(property "Device Type" "TPAD28"
			(at 0.0127 -3.1877 0)
			(unlocked yes)
			(layer "B.Fab")
			(hide yes)
			(effects
				(font
					(size 1.016 1.016)
					(thickness 0.1524)
				)
				(justify mirror)
			)
		)
		(duplicate_pad_numbers_are_jumpers no)
		(fp_poly
			(pts
				(arc
					(start 0.3556 0)
					(mid -0.3556 0)
					(end 0.3556 0)
				)
			)
			(stroke
				(width 0)
				(type default)
			)
			(fill no)
			(layer "B.CrtYd")
		)
		(fp_poly
			(pts
				(arc
					(start 0.6096 0)
					(mid -0.6096 0)
					(end 0.6096 0)
				)
			)
			(stroke
				(width 0)
				(type default)
			)
			(fill no)
			(layer "B.Fab")
		)
		(pad "1" smd circle
			(at 0 0 180)
			(size 0.7112 0.7112)
			(layers "B.Cu" "B.Mask" "B.Paste")
			(net "ICE_TDO")
		)
	)
	(footprint ""
		(layer "B.Cu")
		(at 133.8326 -44.3992 180)
		(property "Reference" "C27"
			(at 0 0 0)
			(layer "B.SilkS")
			(hide yes)
			(effects
				(font
					(size 1.27 1.27)
				)
				(justify mirror)
			)
		)
		(property "Value" "SCD01U16V1KX-GP"
			(at 2.8321 -1.7399 180)
			(unlocked yes)
			(layer "B.Fab")
			(hide yes)
			(effects
				(font
					(size 1.016 1.016)
					(thickness 0.1524)
				)
				(justify mirror)
			)
		)
		(property "Device Type" "C0201H13"
			(at 2.8321 -3.2639 180)
			(unlocked yes)
			(layer "B.Fab")
			(hide yes)
			(effects
				(font
					(size 1.016 1.016)
					(thickness 0.1524)
				)
				(justify mirror)
			)
		)
		(duplicate_pad_numbers_are_jumpers no)
		(fp_rect
			(start 0.2794 0.6477)
			(end -0.2794 -0.6477)
			(stroke
				(width 0)
				(type default)
			)
			(fill no)
			(layer "B.CrtYd")
		)
		(fp_rect
			(start 0.2794 0.6477)
			(end -0.2794 -0.6477)
			(stroke
				(width 0)
				(type default)
			)
			(fill no)
			(layer "B.Fab")
		)
		(pad "1" smd custom
			(at 0 -0.2794)
			(size 0.0762 0.0762)
			(layers "B.Cu" "B.Mask" "B.Paste")
			(net "PHY_DPB_TO_SCC_30_DP")
			(options
				(clearance outline)
				(anchor circle)
			)
			(primitives
				(gr_poly
					(pts
						(arc
							(start 0.1524 0.127)
							(mid 0.137521 0.162921)
							(end 0.1016 0.1778)
						)
						(arc
							(start -0.1016 0.1778)
							(mid -0.137521 0.162921)
							(end -0.1524 0.127)
						)
						(arc
							(start -0.1524 -0.127)
							(mid -0.137521 -0.162921)
							(end -0.1016 -0.1778)
						)
						(arc
							(start 0.1016 -0.1778)
							(mid 0.137521 -0.162921)
							(end 0.1524 -0.127)
						)
					)
					(width 0)
					(fill yes)
				)
			)
		)
		(pad "2" smd custom
			(at 0 0.2794)
			(size 0.0762 0.0762)
			(layers "B.Cu" "B.Mask" "B.Paste")
			(net "PHY_DPB_TO_SCC_C_30_DP")
			(options
				(clearance outline)
				(anchor circle)
			)
			(primitives
				(gr_poly
					(pts
						(arc
							(start 0.1524 0.127)
							(mid 0.137521 0.162921)
							(end 0.1016 0.1778)
						)
						(arc
							(start -0.1016 0.1778)
							(mid -0.137521 0.162921)
							(end -0.1524 0.127)
						)
						(arc
							(start -0.1524 -0.127)
							(mid -0.137521 -0.162921)
							(end -0.1016 -0.1778)
						)
						(arc
							(start 0.1016 -0.1778)
							(mid 0.137521 -0.162921)
							(end 0.1524 -0.127)
						)
					)
					(width 0)
					(fill yes)
				)
			)
		)
	)
	(footprint ""
		(layer "B.Cu")
		(at 137.239248 -115.511834 180)
		(property "Reference" "Q36"
			(at 0 0 0)
			(layer "B.SilkS")
			(hide yes)
			(effects
				(font
					(size 1.27 1.27)
				)
				(justify mirror)
			)
		)
		(property "Value" "FDS8878-G-GP"
			(at 3.707384 -1.5367 180)
			(unlocked yes)
			(layer "B.Fab")
			(hide yes)
			(effects
				(font
					(size 1.016 1.016)
					(thickness 0.1524)
				)
				(justify mirror)
			)
		)
		(property "Device Type" "SOIC8H69"
			(at 3.707384 -3.0607 180)
			(unlocked yes)
			(layer "B.Fab")
			(hide yes)
			(effects
				(font
					(size 1.016 1.016)
					(thickness 0.1524)
				)
				(justify mirror)
			)
		)
		(duplicate_pad_numbers_are_jumpers no)
		(fp_line
			(start 2.7432 1.4224)
			(end 2.6416 1.4224)
			(stroke
				(width 0.1524)
				(type default)
			)
			(layer "B.SilkS")
		)
		(fp_line
			(start 2.7432 1.4224)
			(end -2.1336 1.4224)
			(stroke
				(width 0.1524)
				(type default)
			)
			(layer "B.SilkS")
		)
		(fp_line
			(start 2.7432 -1.4224)
			(end 2.7432 1.4224)
			(stroke
				(width 0.1524)
				(type default)
			)
			(layer "B.SilkS")
		)
		(fp_line
			(start 2.7178 -0.508)
			(end 2.1844 -0.0508)
			(stroke
				(width 0.1524)
				(type default)
			)
			(layer "B.SilkS")
		)
		(fp_line
			(start 2.6289 3.4417)
			(end 2.6289 1.4732)
			(stroke
				(width 0.381)
				(type default)
			)
			(layer "B.SilkS")
		)
		(fp_line
			(start 2.1844 -0.0508)
			(end 2.7178 0.508)
			(stroke
				(width 0.1524)
				(type default)
			)
			(layer "B.SilkS")
		)
		(fp_line
			(start -2.1336 1.4224)
			(end -2.1336 -1.4224)
			(stroke
				(width 0.1524)
				(type default)
			)
			(layer "B.SilkS")
		)
		(fp_line
			(start -2.1336 -1.4224)
			(end 2.7432 -1.4224)
			(stroke
				(width 0.1524)
				(type default)
			)
			(layer "B.SilkS")
		)
		(fp_poly
			(pts
				(xy 2.2098 -1.4224) (xy 2.2098 1.4224) (xy -2.2098 1.4224) (xy -2.2098 -1.4224)
			)
			(stroke
				(width 0)
				(type default)
			)
			(fill yes)
			(layer "B.SilkS")
		)
		(fp_rect
			(start 2.450084 2.999994)
			(end -2.450084 -2.999994)
			(stroke
				(width 0)
				(type default)
			)
			(fill no)
			(layer "B.CrtYd")
		)
		(fp_poly
			(pts
				(xy 2.8194 3.6322) (xy 2.8194 -3.6322) (xy -2.8194 -3.6322) (xy -2.8194 1.18364) (xy -2.450084 1.18364)
				(xy -2.450084 -2.999994) (xy 2.450084 -2.999994) (xy 2.450084 2.999994) (xy -2.450084 2.999994)
				(xy -2.450084 1.18618) (xy -2.8194 1.18618) (xy -2.8194 3.6322)
			)
			(stroke
				(width 0)
				(type default)
			)
			(fill no)
			(layer "B.CrtYd")
		)
		(fp_rect
			(start 2.8194 3.6322)
			(end -2.8194 -3.6322)
			(stroke
				(width 0)
				(type default)
			)
			(fill no)
			(layer "B.Fab")
		)
		(pad "1" smd rect
			(at 1.905 2.54)
			(size 0.635 1.651)
			(layers "B.Cu" "B.Mask" "B.Paste")
			(net "P1V5_C")
		)
		(pad "2" smd rect
			(at 0.635 2.54)
			(size 0.635 1.651)
			(layers "B.Cu" "B.Mask" "B.Paste")
			(net "P1V5_C")
		)
		(pad "3" smd rect
			(at -0.635 2.54)
			(size 0.635 1.651)
			(layers "B.Cu" "B.Mask" "B.Paste")
			(net "P1V5_C")
		)
		(pad "4" smd rect
			(at -1.905 2.54)
			(size 0.635 1.651)
			(layers "B.Cu" "B.Mask" "B.Paste")
			(net "P1V5_C_PG_G")
		)
		(pad "5" smd rect
			(at -1.905 -2.54)
			(size 0.635 1.651)
			(layers "B.Cu" "B.Mask" "B.Paste")
			(net "P1V5_E_OUT")
		)
		(pad "6" smd rect
			(at -0.635 -2.54)
			(size 0.635 1.651)
			(layers "B.Cu" "B.Mask" "B.Paste")
			(net "P1V5_E_OUT")
		)
		(pad "7" smd rect
			(at 0.635 -2.54)
			(size 0.635 1.651)
			(layers "B.Cu" "B.Mask" "B.Paste")
			(net "P1V5_E_OUT")
		)
		(pad "8" smd rect
			(at 1.905 -2.54)
			(size 0.635 1.651)
			(layers "B.Cu" "B.Mask" "B.Paste")
			(net "P1V5_E_OUT")
		)
	)
	(footprint ""
		(layer "B.Cu")
		(at 179.9082 -28.7782 90)
		(property "Reference" "TP55"
			(at 0 0 90)
			(layer "B.SilkS")
			(hide yes)
			(effects
				(font
					(size 1.27 1.27)
				)
				(justify mirror)
			)
		)
		(property "Value" "TPAD28-2-GP"
			(at 0.0127 -1.6637 90)
			(unlocked yes)
			(layer "B.Fab")
			(hide yes)
			(effects
				(font
					(size 1.016 1.016)
					(thickness 0.1524)
				)
				(justify mirror)
			)
		)
		(property "Device Type" "TPAD28"
			(at 0.0127 -3.1877 90)
			(unlocked yes)
			(layer "B.Fab")
			(hide yes)
			(effects
				(font
					(size 1.016 1.016)
					(thickness 0.1524)
				)
				(justify mirror)
			)
		)
		(duplicate_pad_numbers_are_jumpers no)
		(fp_poly
			(pts
				(arc
					(start 0 0.3556)
					(mid 0 -0.3556)
					(end 0 0.3556)
				)
			)
			(stroke
				(width 0)
				(type default)
			)
			(fill no)
			(layer "B.CrtYd")
		)
		(fp_poly
			(pts
				(arc
					(start 0 0.6096)
					(mid 0 -0.6096)
					(end 0 0.6096)
				)
			)
			(stroke
				(width 0)
				(type default)
			)
			(fill no)
			(layer "B.Fab")
		)
		(pad "1" smd circle
			(at 0 0 270)
			(size 0.7112 0.7112)
			(layers "B.Cu" "B.Mask" "B.Paste")
			(net "IOC_GPIO_2")
		)
	)
	(footprint ""
		(layer "B.Cu")
		(at 175.312578 -52.221638)
		(property "Reference" "TP134"
			(at 0 0 0)
			(layer "B.SilkS")
			(hide yes)
			(effects
				(font
					(size 1.27 1.27)
				)
				(justify mirror)
			)
		)
		(property "Value" "TPAD28-2-GP"
			(at 0.0127 -1.6637 0)
			(unlocked yes)
			(layer "B.Fab")
			(hide yes)
			(effects
				(font
					(size 1.016 1.016)
					(thickness 0.1524)
				)
				(justify mirror)
			)
		)
		(property "Device Type" "TPAD28"
			(at 0.0127 -3.1877 0)
			(unlocked yes)
			(layer "B.Fab")
			(hide yes)
			(effects
				(font
					(size 1.016 1.016)
					(thickness 0.1524)
				)
				(justify mirror)
			)
		)
		(duplicate_pad_numbers_are_jumpers no)
		(fp_poly
			(pts
				(arc
					(start 0.3556 0)
					(mid -0.3556 0)
					(end 0.3556 0)
				)
			)
			(stroke
				(width 0)
				(type default)
			)
			(fill no)
			(layer "B.CrtYd")
		)
		(fp_poly
			(pts
				(arc
					(start 0.6096 0)
					(mid -0.6096 0)
					(end 0.6096 0)
				)
			)
			(stroke
				(width 0)
				(type default)
			)
			(fill no)
			(layer "B.Fab")
		)
		(pad "1" smd circle
			(at 0 0 180)
			(size 0.7112 0.7112)
			(layers "B.Cu" "B.Mask" "B.Paste")
			(net "JTAG_IOC_TCK")
		)
	)
	(footprint ""
		(layer "B.Cu")
		(at 134.606538 -84.709)
		(property "Reference" "R63"
			(at 0 0 0)
			(layer "B.SilkS")
			(hide yes)
			(effects
				(font
					(size 1.27 1.27)
				)
				(justify mirror)
			)
		)
		(property "Value" "1KR2F-3-GP"
			(at -0.064008 -3.993896 0)
			(unlocked yes)
			(layer "B.Fab")
			(hide yes)
			(effects
				(font
					(size 1.016 1.016)
					(thickness 0.1524)
				)
				(justify mirror)
			)
		)
		(property "Device Type" "R402H16"
			(at -0.064008 -5.517896 0)
			(unlocked yes)
			(layer "B.Fab")
			(hide yes)
			(effects
				(font
					(size 1.016 1.016)
					(thickness 0.1524)
				)
				(justify mirror)
			)
		)
		(duplicate_pad_numbers_are_jumpers no)
		(fp_line
			(start -0.508 -0.9398)
			(end 0.508 -0.9398)
			(stroke
				(width 0.1524)
				(type default)
			)
			(layer "B.SilkS")
		)
		(fp_line
			(start 0.508 -0.9398)
			(end 0.508 0.9398)
			(stroke
				(width 0.1524)
				(type default)
			)
			(layer "B.SilkS")
		)
		(fp_rect
			(start 0.508 0.9398)
			(end -0.508 -0.9398)
			(stroke
				(width 0)
				(type default)
			)
			(fill no)
			(layer "B.CrtYd")
		)
		(fp_rect
			(start 0.508 0.9398)
			(end -0.508 -0.9398)
			(stroke
				(width 0)
				(type default)
			)
			(fill no)
			(layer "B.Fab")
		)
		(pad "1" smd custom
			(at 0 -0.4445 180)
			(size 0.1397 0.1397)
			(layers "B.Cu" "B.Mask" "B.Paste")
			(net "P1V8_E")
			(options
				(clearance outline)
				(anchor circle)
			)
			(primitives
				(gr_poly
					(pts
						(arc
							(start -0.1778 0.2794)
							(mid -0.249642 0.249642)
							(end -0.2794 0.1778)
						)
						(arc
							(start -0.2794 -0.1778)
							(mid -0.249642 -0.249642)
							(end -0.1778 -0.2794)
						)
						(arc
							(start 0.1778 -0.2794)
							(mid 0.249642 -0.249642)
							(end 0.2794 -0.1778)
						)
						(arc
							(start 0.2794 0.1778)
							(mid 0.249642 0.249642)
							(end 0.1778 0.2794)
						)
					)
					(width 0)
					(fill yes)
				)
			)
		)
		(pad "2" smd custom
			(at 0 0.4445 180)
			(size 0.1397 0.1397)
			(layers "B.Cu" "B.Mask" "B.Paste")
			(net "I2C_EXP_IOC_SDA8")
			(options
				(clearance outline)
				(anchor circle)
			)
			(primitives
				(gr_poly
					(pts
						(arc
							(start -0.1778 0.2794)
							(mid -0.249642 0.249642)
							(end -0.2794 0.1778)
						)
						(arc
							(start -0.2794 -0.1778)
							(mid -0.249642 -0.249642)
							(end -0.1778 -0.2794)
						)
						(arc
							(start 0.1778 -0.2794)
							(mid 0.249642 -0.249642)
							(end 0.2794 -0.1778)
						)
						(arc
							(start 0.2794 0.1778)
							(mid 0.249642 0.249642)
							(end 0.1778 0.2794)
						)
					)
					(width 0)
					(fill yes)
				)
			)
		)
	)
	(footprint ""
		(layer "B.Cu")
		(at 73.66 -36.068)
		(property "Reference" "C227"
			(at 0 0 0)
			(layer "B.SilkS")
			(hide yes)
			(effects
				(font
					(size 1.27 1.27)
				)
				(justify mirror)
			)
		)
		(property "Value" "SC100U6D3V6MX-GP"
			(at 0.0762 -5.1308 0)
			(unlocked yes)
			(layer "B.Fab")
			(hide yes)
			(effects
				(font
					(size 1.016 1.016)
					(thickness 0.1524)
				)
				(justify mirror)
			)
		)
		(property "Device Type" "C1206H71"
			(at 0.127 -6.6548 0)
			(unlocked yes)
			(layer "B.Fab")
			(hide yes)
			(effects
				(font
					(size 1.016 1.016)
					(thickness 0.1524)
				)
				(justify mirror)
			)
		)
		(duplicate_pad_numbers_are_jumpers no)
		(fp_line
			(start -1.016 -2.2352)
			(end -1.016 -0.8382)
			(stroke
				(width 0.1524)
				(type default)
			)
			(layer "B.SilkS")
		)
		(fp_line
			(start -1.016 0.8382)
			(end -1.016 2.2352)
			(stroke
				(width 0.1524)
				(type default)
			)
			(layer "B.SilkS")
		)
		(fp_line
			(start -1.016 2.2352)
			(end 1.016 2.2352)
			(stroke
				(width 0.1524)
				(type default)
			)
			(layer "B.SilkS")
		)
		(fp_line
			(start 1.016 -2.2352)
			(end -1.016 -2.2352)
			(stroke
				(width 0.1524)
				(type default)
			)
			(layer "B.SilkS")
		)
		(fp_line
			(start 1.016 -0.8382)
			(end 1.016 -2.2352)
			(stroke
				(width 0.1524)
				(type default)
			)
			(layer "B.SilkS")
		)
		(fp_line
			(start 1.016 2.2352)
			(end 1.016 0.8382)
			(stroke
				(width 0.1524)
				(type default)
			)
			(layer "B.SilkS")
		)
		(fp_rect
			(start 1.0922 2.3114)
			(end -1.0922 -2.3114)
			(stroke
				(width 0)
				(type default)
			)
			(fill no)
			(layer "B.CrtYd")
		)
		(fp_poly
			(pts
				(xy -1.0922 -2.3114) (xy -1.0922 2.3114) (xy 1.0922 2.3114) (xy 1.0922 -2.3114)
			)
			(stroke
				(width 0)
				(type default)
			)
			(fill no)
			(layer "B.Fab")
		)
		(pad "1" smd rect
			(at 0 -1.397 180)
			(size 1.651 1.27)
			(layers "B.Cu" "B.Mask" "B.Paste")
			(net "GB_VDDA")
		)
		(pad "2" smd rect
			(at 0 1.397 180)
			(size 1.651 1.27)
			(layers "B.Cu" "B.Mask" "B.Paste")
			(net "GND")
		)
	)
	(footprint ""
		(layer "B.Cu")
		(at 137.414 -74.5998 -90)
		(property "Reference" "C9"
			(at 0 0 90)
			(layer "B.SilkS")
			(hide yes)
			(effects
				(font
					(size 1.27 1.27)
				)
				(justify mirror)
			)
		)
		(property "Value" "SCD01U16V1KX-GP"
			(at 2.8321 -1.7399 270)
			(unlocked yes)
			(layer "B.Fab")
			(hide yes)
			(effects
				(font
					(size 1.016 1.016)
					(thickness 0.1524)
				)
				(justify mirror)
			)
		)
		(property "Device Type" "C0201H13"
			(at 2.8321 -3.2639 270)
			(unlocked yes)
			(layer "B.Fab")
			(hide yes)
			(effects
				(font
					(size 1.016 1.016)
					(thickness 0.1524)
				)
				(justify mirror)
			)
		)
		(duplicate_pad_numbers_are_jumpers no)
		(fp_rect
			(start 0.2794 0.6477)
			(end -0.2794 -0.6477)
			(stroke
				(width 0)
				(type default)
			)
			(fill no)
			(layer "B.CrtYd")
		)
		(fp_rect
			(start 0.2794 0.6477)
			(end -0.2794 -0.6477)
			(stroke
				(width 0)
				(type default)
			)
			(fill no)
			(layer "B.Fab")
		)
		(pad "1" smd custom
			(at 0 -0.2794 90)
			(size 0.0762 0.0762)
			(layers "B.Cu" "B.Mask" "B.Paste")
			(net "PHY_DPB_TO_SCC_7_DP")
			(options
				(clearance outline)
				(anchor circle)
			)
			(primitives
				(gr_poly
					(pts
						(arc
							(start 0.1524 0.127)
							(mid 0.137521 0.162921)
							(end 0.1016 0.1778)
						)
						(arc
							(start -0.1016 0.1778)
							(mid -0.137521 0.162921)
							(end -0.1524 0.127)
						)
						(arc
							(start -0.1524 -0.127)
							(mid -0.137521 -0.162921)
							(end -0.1016 -0.1778)
						)
						(arc
							(start 0.1016 -0.1778)
							(mid 0.137521 -0.162921)
							(end 0.1524 -0.127)
						)
					)
					(width 0)
					(fill yes)
				)
			)
		)
		(pad "2" smd custom
			(at 0 0.2794 90)
			(size 0.0762 0.0762)
			(layers "B.Cu" "B.Mask" "B.Paste")
			(net "PHY_DPB_TO_SCC_C_7_DP")
			(options
				(clearance outline)
				(anchor circle)
			)
			(primitives
				(gr_poly
					(pts
						(arc
							(start 0.1524 0.127)
							(mid 0.137521 0.162921)
							(end 0.1016 0.1778)
						)
						(arc
							(start -0.1016 0.1778)
							(mid -0.137521 0.162921)
							(end -0.1524 0.127)
						)
						(arc
							(start -0.1524 -0.127)
							(mid -0.137521 -0.162921)
							(end -0.1016 -0.1778)
						)
						(arc
							(start 0.1016 -0.1778)
							(mid 0.137521 -0.162921)
							(end 0.1524 -0.127)
						)
					)
					(width 0)
					(fill yes)
				)
			)
		)
	)
	(footprint ""
		(layer "B.Cu")
		(at 167.7162 -38.5572 180)
		(property "Reference" "C400"
			(at 0 0 0)
			(layer "B.SilkS")
			(hide yes)
			(effects
				(font
					(size 1.27 1.27)
				)
				(justify mirror)
			)
		)
		(property "Value" "SCD1U16V2KX-3GP"
			(at -1.1811 -2.7051 180)
			(unlocked yes)
			(layer "B.Fab")
			(hide yes)
			(effects
				(font
					(size 1.016 1.016)
					(thickness 0.1524)
				)
				(justify mirror)
			)
		)
		(property "Device Type" "C402H22"
			(at -1.1811 -4.2291 180)
			(unlocked yes)
			(layer "B.Fab")
			(hide yes)
			(effects
				(font
					(size 1.016 1.016)
					(thickness 0.1524)
				)
				(justify mirror)
			)
		)
		(duplicate_pad_numbers_are_jumpers no)
		(fp_rect
			(start 0.4318 0.9525)
			(end -0.4318 -0.9525)
			(stroke
				(width 0)
				(type default)
			)
			(fill no)
			(layer "B.CrtYd")
		)
		(fp_rect
			(start 0.4318 0.9525)
			(end -0.4318 -0.9525)
			(stroke
				(width 0)
				(type default)
			)
			(fill no)
			(layer "B.Fab")
		)
		(pad "1" smd custom
			(at 0 -0.4445)
			(size 0.1524 0.1524)
			(layers "B.Cu" "B.Mask" "B.Paste")
			(net "SAS0_AVDD")
			(options
				(clearance outline)
				(anchor circle)
			)
			(primitives
				(gr_poly
					(pts
						(arc
							(start 0.3048 0.2032)
							(mid 0.275042 0.275042)
							(end 0.2032 0.3048)
						)
						(arc
							(start -0.2032 0.3048)
							(mid -0.275042 0.275042)
							(end -0.3048 0.2032)
						)
						(arc
							(start -0.3048 -0.2032)
							(mid -0.275042 -0.275042)
							(end -0.2032 -0.3048)
						)
						(arc
							(start 0.2032 -0.3048)
							(mid 0.275042 -0.275042)
							(end 0.3048 -0.2032)
						)
					)
					(width 0)
					(fill yes)
				)
			)
		)
		(pad "2" smd custom
			(at 0 0.4445)
			(size 0.1524 0.1524)
			(layers "B.Cu" "B.Mask" "B.Paste")
			(net "GND")
			(options
				(clearance outline)
				(anchor circle)
			)
			(primitives
				(gr_poly
					(pts
						(arc
							(start 0.3048 0.2032)
							(mid 0.275042 0.275042)
							(end 0.2032 0.3048)
						)
						(arc
							(start -0.2032 0.3048)
							(mid -0.275042 0.275042)
							(end -0.3048 0.2032)
						)
						(arc
							(start -0.3048 -0.2032)
							(mid -0.275042 -0.275042)
							(end -0.2032 -0.3048)
						)
						(arc
							(start 0.2032 -0.3048)
							(mid 0.275042 -0.275042)
							(end 0.3048 -0.2032)
						)
					)
					(width 0)
					(fill yes)
				)
			)
		)
	)
	(footprint ""
		(layer "B.Cu")
		(at 123.5075 -72.7329 180)
		(property "Reference" "C243"
			(at 0 0 0)
			(layer "B.SilkS")
			(hide yes)
			(effects
				(font
					(size 1.27 1.27)
				)
				(justify mirror)
			)
		)
		(property "Value" "SC1U6D3V1MX-GP"
			(at -1.9177 2.0193 180)
			(unlocked yes)
			(layer "B.Fab")
			(hide yes)
			(effects
				(font
					(size 1.016 1.016)
					(thickness 0.1524)
				)
				(justify mirror)
			)
		)
		(property "Device Type" "C0201H14"
			(at -1.9177 0.4953 180)
			(unlocked yes)
			(layer "B.Fab")
			(hide yes)
			(effects
				(font
					(size 1.016 1.016)
					(thickness 0.1524)
				)
				(justify mirror)
			)
		)
		(duplicate_pad_numbers_are_jumpers no)
		(fp_rect
			(start 0.1524 0.3048)
			(end -0.1524 -0.3048)
			(stroke
				(width 0)
				(type default)
			)
			(fill no)
			(layer "B.CrtYd")
		)
		(fp_poly
			(pts
				(xy 0.2794 0.6477) (xy 0.2794 -0.6477) (xy -0.2794 -0.6477) (xy -0.2794 -0.1905) (xy -0.1524 -0.1905)
				(xy -0.1524 -0.3048) (xy 0.1524 -0.3048) (xy 0.1524 0.3048) (xy -0.1524 0.3048) (xy -0.1524 -0.1778)
				(xy -0.2794 -0.1778) (xy -0.2794 0.6477)
			)
			(stroke
				(width 0)
				(type default)
			)
			(fill no)
			(layer "B.CrtYd")
		)
		(fp_rect
			(start 0.2794 0.6477)
			(end -0.2794 -0.6477)
			(stroke
				(width 0)
				(type default)
			)
			(fill no)
			(layer "B.Fab")
		)
		(pad "1" smd custom
			(at 0 -0.2794)
			(size 0.0762 0.0762)
			(layers "B.Cu" "B.Mask" "B.Paste")
			(net "GB_VDDA")
			(options
				(clearance outline)
				(anchor circle)
			)
			(primitives
				(gr_poly
					(pts
						(arc
							(start 0.1524 0.127)
							(mid 0.137521 0.162921)
							(end 0.1016 0.1778)
						)
						(arc
							(start -0.1016 0.1778)
							(mid -0.137521 0.162921)
							(end -0.1524 0.127)
						)
						(arc
							(start -0.1524 -0.127)
							(mid -0.137521 -0.162921)
							(end -0.1016 -0.1778)
						)
						(arc
							(start 0.1016 -0.1778)
							(mid 0.137521 -0.162921)
							(end 0.1524 -0.127)
						)
					)
					(width 0)
					(fill yes)
				)
			)
		)
		(pad "2" smd custom
			(at 0 0.2794)
			(size 0.0762 0.0762)
			(layers "B.Cu" "B.Mask" "B.Paste")
			(net "GND")
			(options
				(clearance outline)
				(anchor circle)
			)
			(primitives
				(gr_poly
					(pts
						(arc
							(start 0.1524 0.127)
							(mid 0.137521 0.162921)
							(end 0.1016 0.1778)
						)
						(arc
							(start -0.1016 0.1778)
							(mid -0.137521 0.162921)
							(end -0.1524 0.127)
						)
						(arc
							(start -0.1524 -0.127)
							(mid -0.137521 -0.162921)
							(end -0.1016 -0.1778)
						)
						(arc
							(start 0.1016 -0.1778)
							(mid 0.137521 -0.162921)
							(end 0.1524 -0.127)
						)
					)
					(width 0)
					(fill yes)
				)
			)
		)
	)
	(footprint ""
		(layer "B.Cu")
		(at 120.0658 -44.2214 180)
		(property "Reference" "C57"
			(at 0 0 0)
			(layer "B.SilkS")
			(hide yes)
			(effects
				(font
					(size 1.27 1.27)
				)
				(justify mirror)
			)
		)
		(property "Value" "SCD01U16V1KX-GP"
			(at 2.8321 -1.7399 180)
			(unlocked yes)
			(layer "B.Fab")
			(hide yes)
			(effects
				(font
					(size 1.016 1.016)
					(thickness 0.1524)
				)
				(justify mirror)
			)
		)
		(property "Device Type" "C0201H13"
			(at 2.8321 -3.2639 180)
			(unlocked yes)
			(layer "B.Fab")
			(hide yes)
			(effects
				(font
					(size 1.016 1.016)
					(thickness 0.1524)
				)
				(justify mirror)
			)
		)
		(duplicate_pad_numbers_are_jumpers no)
		(fp_rect
			(start 0.2794 0.6477)
			(end -0.2794 -0.6477)
			(stroke
				(width 0)
				(type default)
			)
			(fill no)
			(layer "B.CrtYd")
		)
		(fp_rect
			(start 0.2794 0.6477)
			(end -0.2794 -0.6477)
			(stroke
				(width 0)
				(type default)
			)
			(fill no)
			(layer "B.Fab")
		)
		(pad "1" smd custom
			(at 0 -0.2794)
			(size 0.0762 0.0762)
			(layers "B.Cu" "B.Mask" "B.Paste")
			(net "PHY_DPB_TO_SCC_35_DP")
			(options
				(clearance outline)
				(anchor circle)
			)
			(primitives
				(gr_poly
					(pts
						(arc
							(start 0.1524 0.127)
							(mid 0.137521 0.162921)
							(end 0.1016 0.1778)
						)
						(arc
							(start -0.1016 0.1778)
							(mid -0.137521 0.162921)
							(end -0.1524 0.127)
						)
						(arc
							(start -0.1524 -0.127)
							(mid -0.137521 -0.162921)
							(end -0.1016 -0.1778)
						)
						(arc
							(start 0.1016 -0.1778)
							(mid 0.137521 -0.162921)
							(end 0.1524 -0.127)
						)
					)
					(width 0)
					(fill yes)
				)
			)
		)
		(pad "2" smd custom
			(at 0 0.2794)
			(size 0.0762 0.0762)
			(layers "B.Cu" "B.Mask" "B.Paste")
			(net "PHY_DPB_TO_SCC_C_35_DP")
			(options
				(clearance outline)
				(anchor circle)
			)
			(primitives
				(gr_poly
					(pts
						(arc
							(start 0.1524 0.127)
							(mid 0.137521 0.162921)
							(end 0.1016 0.1778)
						)
						(arc
							(start -0.1016 0.1778)
							(mid -0.137521 0.162921)
							(end -0.1524 0.127)
						)
						(arc
							(start -0.1524 -0.127)
							(mid -0.137521 -0.162921)
							(end -0.1016 -0.1778)
						)
						(arc
							(start 0.1016 -0.1778)
							(mid 0.137521 -0.162921)
							(end 0.1524 -0.127)
						)
					)
					(width 0)
					(fill yes)
				)
			)
		)
	)
	(footprint ""
		(layer "B.Cu")
		(at 108.585 -86.9442)
		(property "Reference" "R114"
			(at 0 0 0)
			(layer "B.SilkS")
			(hide yes)
			(effects
				(font
					(size 1.27 1.27)
				)
				(justify mirror)
			)
		)
		(property "Value" "4K75R2F-1-GP"
			(at -0.064008 -3.993896 0)
			(unlocked yes)
			(layer "B.Fab")
			(hide yes)
			(effects
				(font
					(size 1.016 1.016)
					(thickness 0.1524)
				)
				(justify mirror)
			)
		)
		(property "Device Type" "R402H16"
			(at -0.064008 -5.517896 0)
			(unlocked yes)
			(layer "B.Fab")
			(hide yes)
			(effects
				(font
					(size 1.016 1.016)
					(thickness 0.1524)
				)
				(justify mirror)
			)
		)
		(duplicate_pad_numbers_are_jumpers no)
		(fp_line
			(start -0.508 -0.9398)
			(end 0.508 -0.9398)
			(stroke
				(width 0.1524)
				(type default)
			)
			(layer "B.SilkS")
		)
		(fp_line
			(start 0.508 -0.9398)
			(end 0.508 0.9398)
			(stroke
				(width 0.1524)
				(type default)
			)
			(layer "B.SilkS")
		)
		(fp_rect
			(start 0.508 0.9398)
			(end -0.508 -0.9398)
			(stroke
				(width 0)
				(type default)
			)
			(fill no)
			(layer "B.CrtYd")
		)
		(fp_rect
			(start 0.508 0.9398)
			(end -0.508 -0.9398)
			(stroke
				(width 0)
				(type default)
			)
			(fill no)
			(layer "B.Fab")
		)
		(pad "1" smd custom
			(at 0 -0.4445 180)
			(size 0.1397 0.1397)
			(layers "B.Cu" "B.Mask" "B.Paste")
			(net "TMUX_EN")
			(options
				(clearance outline)
				(anchor circle)
			)
			(primitives
				(gr_poly
					(pts
						(arc
							(start -0.1778 0.2794)
							(mid -0.249642 0.249642)
							(end -0.2794 0.1778)
						)
						(arc
							(start -0.2794 -0.1778)
							(mid -0.249642 -0.249642)
							(end -0.1778 -0.2794)
						)
						(arc
							(start 0.1778 -0.2794)
							(mid 0.249642 -0.249642)
							(end 0.2794 -0.1778)
						)
						(arc
							(start 0.2794 0.1778)
							(mid 0.249642 0.249642)
							(end 0.1778 0.2794)
						)
					)
					(width 0)
					(fill yes)
				)
			)
		)
		(pad "2" smd custom
			(at 0 0.4445 180)
			(size 0.1397 0.1397)
			(layers "B.Cu" "B.Mask" "B.Paste")
			(net "GND")
			(options
				(clearance outline)
				(anchor circle)
			)
			(primitives
				(gr_poly
					(pts
						(arc
							(start -0.1778 0.2794)
							(mid -0.249642 0.249642)
							(end -0.2794 0.1778)
						)
						(arc
							(start -0.2794 -0.1778)
							(mid -0.249642 -0.249642)
							(end -0.1778 -0.2794)
						)
						(arc
							(start 0.1778 -0.2794)
							(mid 0.249642 -0.249642)
							(end 0.2794 -0.1778)
						)
						(arc
							(start 0.2794 0.1778)
							(mid 0.249642 0.249642)
							(end 0.1778 0.2794)
						)
					)
					(width 0)
					(fill yes)
				)
			)
		)
	)
	(footprint ""
		(layer "B.Cu")
		(at 107.106466 -67.01409 -90)
		(property "Reference" "R475"
			(at 0 0 90)
			(layer "B.SilkS")
			(hide yes)
			(effects
				(font
					(size 1.27 1.27)
				)
				(justify mirror)
			)
		)
		(property "Value" "0R2F-1-GP"
			(at -0.064008 -3.993896 270)
			(unlocked yes)
			(layer "B.Fab")
			(hide yes)
			(effects
				(font
					(size 1.016 1.016)
					(thickness 0.1524)
				)
				(justify mirror)
			)
		)
		(property "Device Type" "R402H16"
			(at -0.064008 -5.517896 270)
			(unlocked yes)
			(layer "B.Fab")
			(hide yes)
			(effects
				(font
					(size 1.016 1.016)
					(thickness 0.1524)
				)
				(justify mirror)
			)
		)
		(duplicate_pad_numbers_are_jumpers no)
		(fp_line
			(start -0.508 -0.9398)
			(end 0.508 -0.9398)
			(stroke
				(width 0.1524)
				(type default)
			)
			(layer "B.SilkS")
		)
		(fp_line
			(start 0.508 -0.9398)
			(end 0.508 0.9398)
			(stroke
				(width 0.1524)
				(type default)
			)
			(layer "B.SilkS")
		)
		(fp_rect
			(start 0.508 0.9398)
			(end -0.508 -0.9398)
			(stroke
				(width 0)
				(type default)
			)
			(fill no)
			(layer "B.CrtYd")
		)
		(fp_rect
			(start 0.508 0.9398)
			(end -0.508 -0.9398)
			(stroke
				(width 0)
				(type default)
			)
			(fill no)
			(layer "B.Fab")
		)
		(pad "1" smd custom
			(at 0 -0.4445 90)
			(size 0.1397 0.1397)
			(layers "B.Cu" "B.Mask" "B.Paste")
			(net "P0V9_GSNS")
			(options
				(clearance outline)
				(anchor circle)
			)
			(primitives
				(gr_poly
					(pts
						(arc
							(start -0.1778 0.2794)
							(mid -0.249642 0.249642)
							(end -0.2794 0.1778)
						)
						(arc
							(start -0.2794 -0.1778)
							(mid -0.249642 -0.249642)
							(end -0.1778 -0.2794)
						)
						(arc
							(start 0.1778 -0.2794)
							(mid 0.249642 -0.249642)
							(end 0.2794 -0.1778)
						)
						(arc
							(start 0.2794 0.1778)
							(mid 0.249642 0.249642)
							(end 0.1778 0.2794)
						)
					)
					(width 0)
					(fill yes)
				)
			)
		)
		(pad "2" smd custom
			(at 0 0.4445 90)
			(size 0.1397 0.1397)
			(layers "B.Cu" "B.Mask" "B.Paste")
			(net "GND")
			(options
				(clearance outline)
				(anchor circle)
			)
			(primitives
				(gr_poly
					(pts
						(arc
							(start -0.1778 0.2794)
							(mid -0.249642 0.249642)
							(end -0.2794 0.1778)
						)
						(arc
							(start -0.2794 -0.1778)
							(mid -0.249642 -0.249642)
							(end -0.1778 -0.2794)
						)
						(arc
							(start 0.1778 -0.2794)
							(mid 0.249642 -0.249642)
							(end 0.2794 -0.1778)
						)
						(arc
							(start 0.2794 0.1778)
							(mid 0.249642 0.249642)
							(end 0.1778 0.2794)
						)
					)
					(width 0)
					(fill yes)
				)
			)
		)
	)
	(footprint ""
		(layer "B.Cu")
		(at 173.625002 -20.88642)
		(property "Reference" "C320"
			(at 0 0 0)
			(layer "B.SilkS")
			(hide yes)
			(effects
				(font
					(size 1.27 1.27)
				)
				(justify mirror)
			)
		)
		(property "Value" "SCD22U10V1KX-GP"
			(at 2.8321 -1.7399 0)
			(unlocked yes)
			(layer "B.Fab")
			(hide yes)
			(effects
				(font
					(size 1.016 1.016)
					(thickness 0.1524)
				)
				(justify mirror)
			)
		)
		(property "Device Type" "C0201H13"
			(at 2.8321 -3.2639 0)
			(unlocked yes)
			(layer "B.Fab")
			(hide yes)
			(effects
				(font
					(size 1.016 1.016)
					(thickness 0.1524)
				)
				(justify mirror)
			)
		)
		(duplicate_pad_numbers_are_jumpers no)
		(fp_rect
			(start 0.2794 0.6477)
			(end -0.2794 -0.6477)
			(stroke
				(width 0)
				(type default)
			)
			(fill no)
			(layer "B.CrtYd")
		)
		(fp_rect
			(start 0.2794 0.6477)
			(end -0.2794 -0.6477)
			(stroke
				(width 0)
				(type default)
			)
			(fill no)
			(layer "B.Fab")
		)
		(pad "1" smd custom
			(at 0 -0.2794 180)
			(size 0.0762 0.0762)
			(layers "B.Cu" "B.Mask" "B.Paste")
			(net "PCIE_SCC_TO_COMP_C_4_DN")
			(options
				(clearance outline)
				(anchor circle)
			)
			(primitives
				(gr_poly
					(pts
						(arc
							(start 0.1524 0.127)
							(mid 0.137521 0.162921)
							(end 0.1016 0.1778)
						)
						(arc
							(start -0.1016 0.1778)
							(mid -0.137521 0.162921)
							(end -0.1524 0.127)
						)
						(arc
							(start -0.1524 -0.127)
							(mid -0.137521 -0.162921)
							(end -0.1016 -0.1778)
						)
						(arc
							(start 0.1016 -0.1778)
							(mid 0.137521 -0.162921)
							(end 0.1524 -0.127)
						)
					)
					(width 0)
					(fill yes)
				)
			)
		)
		(pad "2" smd custom
			(at 0 0.2794 180)
			(size 0.0762 0.0762)
			(layers "B.Cu" "B.Mask" "B.Paste")
			(net "PCIE_SCC_TO_COMP_4_DN")
			(options
				(clearance outline)
				(anchor circle)
			)
			(primitives
				(gr_poly
					(pts
						(arc
							(start 0.1524 0.127)
							(mid 0.137521 0.162921)
							(end 0.1016 0.1778)
						)
						(arc
							(start -0.1016 0.1778)
							(mid -0.137521 0.162921)
							(end -0.1524 0.127)
						)
						(arc
							(start -0.1524 -0.127)
							(mid -0.137521 -0.162921)
							(end -0.1016 -0.1778)
						)
						(arc
							(start 0.1016 -0.1778)
							(mid 0.137521 -0.162921)
							(end 0.1524 -0.127)
						)
					)
					(width 0)
					(fill yes)
				)
			)
		)
	)
	(footprint ""
		(layer "B.Cu")
		(at 157.867604 -64.122808 90)
		(property "Reference" "C359"
			(at 0 0 90)
			(layer "B.SilkS")
			(hide yes)
			(effects
				(font
					(size 1.27 1.27)
				)
				(justify mirror)
			)
		)
		(property "Value" "SC22U6D3V3MX-9-GP-U"
			(at 0 -2.8194 90)
			(unlocked yes)
			(layer "B.Fab")
			(hide yes)
			(effects
				(font
					(size 1.016 1.016)
					(thickness 0.1524)
				)
				(justify mirror)
			)
		)
		(property "Device Type" "C603H40"
			(at 0 -4.3434 90)
			(unlocked yes)
			(layer "B.Fab")
			(hide yes)
			(effects
				(font
					(size 1.016 1.016)
					(thickness 0.1524)
				)
				(justify mirror)
			)
		)
		(duplicate_pad_numbers_are_jumpers no)
		(fp_line
			(start -0.508 0)
			(end 0.508 0)
			(stroke
				(width 0.2032)
				(type default)
			)
			(layer "B.SilkS")
		)
		(fp_rect
			(start 0.5842 1.3335)
			(end -0.5842 -1.3335)
			(stroke
				(width 0)
				(type default)
			)
			(fill no)
			(layer "B.CrtYd")
		)
		(fp_rect
			(start 0.5842 1.3335)
			(end -0.5842 -1.3335)
			(stroke
				(width 0)
				(type default)
			)
			(fill no)
			(layer "B.Fab")
		)
		(pad "1" smd custom
			(at 0 -0.762 270)
			(size 0.2159 0.2159)
			(layers "B.Cu" "B.Mask" "B.Paste")
			(net "SHELL_PLL_VDD")
			(options
				(clearance outline)
				(anchor circle)
			)
			(primitives
				(gr_poly
					(pts
						(arc
							(start -0.3302 0.4318)
							(mid -0.402042 0.402042)
							(end -0.4318 0.3302)
						)
						(arc
							(start -0.4318 -0.3302)
							(mid -0.402042 -0.402042)
							(end -0.3302 -0.4318)
						)
						(arc
							(start 0.3302 -0.4318)
							(mid 0.402042 -0.402042)
							(end 0.4318 -0.3302)
						)
						(arc
							(start 0.4318 0.3302)
							(mid 0.402042 0.402042)
							(end 0.3302 0.4318)
						)
					)
					(width 0)
					(fill yes)
				)
			)
		)
		(pad "2" smd custom
			(at 0 0.762 270)
			(size 0.2159 0.2159)
			(layers "B.Cu" "B.Mask" "B.Paste")
			(net "GND")
			(options
				(clearance outline)
				(anchor circle)
			)
			(primitives
				(gr_poly
					(pts
						(arc
							(start -0.3302 0.4318)
							(mid -0.402042 0.402042)
							(end -0.4318 0.3302)
						)
						(arc
							(start -0.4318 -0.3302)
							(mid -0.402042 -0.402042)
							(end -0.3302 -0.4318)
						)
						(arc
							(start 0.3302 -0.4318)
							(mid 0.402042 -0.402042)
							(end 0.4318 -0.3302)
						)
						(arc
							(start 0.4318 0.3302)
							(mid 0.402042 0.402042)
							(end 0.3302 0.4318)
						)
					)
					(width 0)
					(fill yes)
				)
			)
		)
	)
	(footprint ""
		(layer "B.Cu")
		(at 118.6307 -57.4802)
		(property "Reference" "C238"
			(at 0 0 0)
			(layer "B.SilkS")
			(hide yes)
			(effects
				(font
					(size 1.27 1.27)
				)
				(justify mirror)
			)
		)
		(property "Value" "SCD1U6D3V1KX-GP"
			(at 2.8321 -1.7399 0)
			(unlocked yes)
			(layer "B.Fab")
			(hide yes)
			(effects
				(font
					(size 1.016 1.016)
					(thickness 0.1524)
				)
				(justify mirror)
			)
		)
		(property "Device Type" "C0201H13"
			(at 2.8321 -3.2639 0)
			(unlocked yes)
			(layer "B.Fab")
			(hide yes)
			(effects
				(font
					(size 1.016 1.016)
					(thickness 0.1524)
				)
				(justify mirror)
			)
		)
		(duplicate_pad_numbers_are_jumpers no)
		(fp_rect
			(start 0.2794 0.6477)
			(end -0.2794 -0.6477)
			(stroke
				(width 0)
				(type default)
			)
			(fill no)
			(layer "B.CrtYd")
		)
		(fp_rect
			(start 0.2794 0.6477)
			(end -0.2794 -0.6477)
			(stroke
				(width 0)
				(type default)
			)
			(fill no)
			(layer "B.Fab")
		)
		(pad "1" smd custom
			(at 0 -0.2794 180)
			(size 0.0762 0.0762)
			(layers "B.Cu" "B.Mask" "B.Paste")
			(net "GB_VDDA")
			(options
				(clearance outline)
				(anchor circle)
			)
			(primitives
				(gr_poly
					(pts
						(arc
							(start 0.1524 0.127)
							(mid 0.137521 0.162921)
							(end 0.1016 0.1778)
						)
						(arc
							(start -0.1016 0.1778)
							(mid -0.137521 0.162921)
							(end -0.1524 0.127)
						)
						(arc
							(start -0.1524 -0.127)
							(mid -0.137521 -0.162921)
							(end -0.1016 -0.1778)
						)
						(arc
							(start 0.1016 -0.1778)
							(mid 0.137521 -0.162921)
							(end 0.1524 -0.127)
						)
					)
					(width 0)
					(fill yes)
				)
			)
		)
		(pad "2" smd custom
			(at 0 0.2794 180)
			(size 0.0762 0.0762)
			(layers "B.Cu" "B.Mask" "B.Paste")
			(net "GND")
			(options
				(clearance outline)
				(anchor circle)
			)
			(primitives
				(gr_poly
					(pts
						(arc
							(start 0.1524 0.127)
							(mid 0.137521 0.162921)
							(end 0.1016 0.1778)
						)
						(arc
							(start -0.1016 0.1778)
							(mid -0.137521 0.162921)
							(end -0.1524 0.127)
						)
						(arc
							(start -0.1524 -0.127)
							(mid -0.137521 -0.162921)
							(end -0.1016 -0.1778)
						)
						(arc
							(start 0.1016 -0.1778)
							(mid 0.137521 -0.162921)
							(end 0.1524 -0.127)
						)
					)
					(width 0)
					(fill yes)
				)
			)
		)
	)
	(footprint ""
		(layer "B.Cu")
		(at 124.2822 -65.5066 -90)
		(property "Reference" "C578"
			(at 0 0 90)
			(layer "B.SilkS")
			(hide yes)
			(effects
				(font
					(size 1.27 1.27)
				)
				(justify mirror)
			)
		)
		(property "Value" "SCD1U6D3V1KX-GP"
			(at 2.8321 -1.7399 270)
			(unlocked yes)
			(layer "B.Fab")
			(hide yes)
			(effects
				(font
					(size 1.016 1.016)
					(thickness 0.1524)
				)
				(justify mirror)
			)
		)
		(property "Device Type" "C0201H13"
			(at 2.8321 -3.2639 270)
			(unlocked yes)
			(layer "B.Fab")
			(hide yes)
			(effects
				(font
					(size 1.016 1.016)
					(thickness 0.1524)
				)
				(justify mirror)
			)
		)
		(duplicate_pad_numbers_are_jumpers no)
		(fp_rect
			(start 0.2794 0.6477)
			(end -0.2794 -0.6477)
			(stroke
				(width 0)
				(type default)
			)
			(fill no)
			(layer "B.CrtYd")
		)
		(fp_rect
			(start 0.2794 0.6477)
			(end -0.2794 -0.6477)
			(stroke
				(width 0)
				(type default)
			)
			(fill no)
			(layer "B.Fab")
		)
		(pad "1" smd custom
			(at 0 -0.2794 90)
			(size 0.0762 0.0762)
			(layers "B.Cu" "B.Mask" "B.Paste")
			(net "GB_VDDA")
			(options
				(clearance outline)
				(anchor circle)
			)
			(primitives
				(gr_poly
					(pts
						(arc
							(start 0.1524 0.127)
							(mid 0.137521 0.162921)
							(end 0.1016 0.1778)
						)
						(arc
							(start -0.1016 0.1778)
							(mid -0.137521 0.162921)
							(end -0.1524 0.127)
						)
						(arc
							(start -0.1524 -0.127)
							(mid -0.137521 -0.162921)
							(end -0.1016 -0.1778)
						)
						(arc
							(start 0.1016 -0.1778)
							(mid 0.137521 -0.162921)
							(end 0.1524 -0.127)
						)
					)
					(width 0)
					(fill yes)
				)
			)
		)
		(pad "2" smd custom
			(at 0 0.2794 90)
			(size 0.0762 0.0762)
			(layers "B.Cu" "B.Mask" "B.Paste")
			(net "GND")
			(options
				(clearance outline)
				(anchor circle)
			)
			(primitives
				(gr_poly
					(pts
						(arc
							(start 0.1524 0.127)
							(mid 0.137521 0.162921)
							(end 0.1016 0.1778)
						)
						(arc
							(start -0.1016 0.1778)
							(mid -0.137521 0.162921)
							(end -0.1524 0.127)
						)
						(arc
							(start -0.1524 -0.127)
							(mid -0.137521 -0.162921)
							(end -0.1016 -0.1778)
						)
						(arc
							(start 0.1016 -0.1778)
							(mid 0.137521 -0.162921)
							(end 0.1524 -0.127)
						)
					)
					(width 0)
					(fill yes)
				)
			)
		)
	)
	(footprint ""
		(layer "B.Cu")
		(at 93.951806 -74.788014 180)
		(property "Reference" "C205"
			(at 0 0 0)
			(layer "B.SilkS")
			(hide yes)
			(effects
				(font
					(size 1.27 1.27)
				)
				(justify mirror)
			)
		)
		(property "Value" "SC10U6D3V2MX-GP-U"
			(at 1.524 -1.905 180)
			(unlocked yes)
			(layer "B.Fab")
			(hide yes)
			(effects
				(font
					(size 1.016 1.016)
					(thickness 0.1524)
				)
				(justify mirror)
			)
		)
		(property "Device Type" "C402-TO0D2H28"
			(at 1.524 -3.429 180)
			(unlocked yes)
			(layer "B.Fab")
			(hide yes)
			(effects
				(font
					(size 1.016 1.016)
					(thickness 0.1524)
				)
				(justify mirror)
			)
		)
		(duplicate_pad_numbers_are_jumpers no)
		(fp_rect
			(start 0.4826 0.889)
			(end -0.4826 -0.889)
			(stroke
				(width 0)
				(type default)
			)
			(fill no)
			(layer "B.CrtYd")
		)
		(fp_rect
			(start 0.4826 0.889)
			(end -0.4826 -0.889)
			(stroke
				(width 0)
				(type default)
			)
			(fill no)
			(layer "B.Fab")
		)
		(pad "1" smd custom
			(at 0 -0.4572)
			(size 0.1524 0.1524)
			(layers "B.Cu" "B.Mask" "B.Paste")
			(net "XTAL_VDDA09")
			(options
				(clearance outline)
				(anchor circle)
			)
			(primitives
				(gr_poly
					(pts
						(arc
							(start -0.254 -0.3048)
							(mid -0.325842 -0.275042)
							(end -0.3556 -0.2032)
						)
						(arc
							(start -0.3556 0.2032)
							(mid -0.325842 0.275042)
							(end -0.254 0.3048)
						)
						(arc
							(start 0.254 0.3048)
							(mid 0.325842 0.275042)
							(end 0.3556 0.2032)
						)
						(arc
							(start 0.3556 -0.2032)
							(mid 0.325842 -0.275042)
							(end 0.254 -0.3048)
						)
					)
					(width 0)
					(fill yes)
				)
			)
		)
		(pad "2" smd custom
			(at 0 0.4572)
			(size 0.1524 0.1524)
			(layers "B.Cu" "B.Mask" "B.Paste")
			(net "GND")
			(options
				(clearance outline)
				(anchor circle)
			)
			(primitives
				(gr_poly
					(pts
						(arc
							(start -0.254 -0.3048)
							(mid -0.325842 -0.275042)
							(end -0.3556 -0.2032)
						)
						(arc
							(start -0.3556 0.2032)
							(mid -0.325842 0.275042)
							(end -0.254 0.3048)
						)
						(arc
							(start 0.254 0.3048)
							(mid 0.325842 0.275042)
							(end 0.3556 0.2032)
						)
						(arc
							(start 0.3556 -0.2032)
							(mid 0.325842 -0.275042)
							(end 0.254 -0.3048)
						)
					)
					(width 0)
					(fill yes)
				)
			)
		)
	)
	(footprint ""
		(layer "B.Cu")
		(at 196.953378 -31.926022)
		(property "Reference" "C365"
			(at 0 0 0)
			(layer "B.SilkS")
			(hide yes)
			(effects
				(font
					(size 1.27 1.27)
				)
				(justify mirror)
			)
		)
		(property "Value" "SC1U16V2KX-7-GP"
			(at -1.7526 -1.6002 0)
			(unlocked yes)
			(layer "B.Fab")
			(hide yes)
			(effects
				(font
					(size 1.016 1.016)
					(thickness 0.1524)
				)
				(justify mirror)
			)
		)
		(property "Device Type" "C402-TO0D2H24"
			(at -1.7526 -3.1242 0)
			(unlocked yes)
			(layer "B.Fab")
			(hide yes)
			(effects
				(font
					(size 1.016 1.016)
					(thickness 0.1524)
				)
				(justify mirror)
			)
		)
		(duplicate_pad_numbers_are_jumpers no)
		(fp_rect
			(start 0.4826 0.889)
			(end -0.4826 -0.889)
			(stroke
				(width 0)
				(type default)
			)
			(fill no)
			(layer "B.CrtYd")
		)
		(fp_rect
			(start 0.4826 0.889)
			(end -0.4826 -0.889)
			(stroke
				(width 0)
				(type default)
			)
			(fill no)
			(layer "B.Fab")
		)
		(pad "1" smd custom
			(at 0 -0.4572 180)
			(size 0.1524 0.1524)
			(layers "B.Cu" "B.Mask" "B.Paste")
			(net "PLL_VDD")
			(options
				(clearance outline)
				(anchor circle)
			)
			(primitives
				(gr_poly
					(pts
						(arc
							(start -0.254 -0.3048)
							(mid -0.325842 -0.275042)
							(end -0.3556 -0.2032)
						)
						(arc
							(start -0.3556 0.2032)
							(mid -0.325842 0.275042)
							(end -0.254 0.3048)
						)
						(arc
							(start 0.254 0.3048)
							(mid 0.325842 0.275042)
							(end 0.3556 0.2032)
						)
						(arc
							(start 0.3556 -0.2032)
							(mid 0.325842 -0.275042)
							(end 0.254 -0.3048)
						)
					)
					(width 0)
					(fill yes)
				)
			)
		)
		(pad "2" smd custom
			(at 0 0.4572 180)
			(size 0.1524 0.1524)
			(layers "B.Cu" "B.Mask" "B.Paste")
			(net "GND")
			(options
				(clearance outline)
				(anchor circle)
			)
			(primitives
				(gr_poly
					(pts
						(arc
							(start -0.254 -0.3048)
							(mid -0.325842 -0.275042)
							(end -0.3556 -0.2032)
						)
						(arc
							(start -0.3556 0.2032)
							(mid -0.325842 0.275042)
							(end -0.254 0.3048)
						)
						(arc
							(start 0.254 0.3048)
							(mid 0.325842 0.275042)
							(end 0.3556 0.2032)
						)
						(arc
							(start 0.3556 -0.2032)
							(mid 0.325842 -0.275042)
							(end 0.254 -0.3048)
						)
					)
					(width 0)
					(fill yes)
				)
			)
		)
	)
	(footprint ""
		(layer "B.Cu")
		(at 124.2822 -62.484 -90)
		(property "Reference" "C514"
			(at 0 0 90)
			(layer "B.SilkS")
			(hide yes)
			(effects
				(font
					(size 1.27 1.27)
				)
				(justify mirror)
			)
		)
		(property "Value" "SCD1U6D3V1KX-GP"
			(at 2.8321 -1.7399 270)
			(unlocked yes)
			(layer "B.Fab")
			(hide yes)
			(effects
				(font
					(size 1.016 1.016)
					(thickness 0.1524)
				)
				(justify mirror)
			)
		)
		(property "Device Type" "C0201H13"
			(at 2.8321 -3.2639 270)
			(unlocked yes)
			(layer "B.Fab")
			(hide yes)
			(effects
				(font
					(size 1.016 1.016)
					(thickness 0.1524)
				)
				(justify mirror)
			)
		)
		(duplicate_pad_numbers_are_jumpers no)
		(fp_rect
			(start 0.2794 0.6477)
			(end -0.2794 -0.6477)
			(stroke
				(width 0)
				(type default)
			)
			(fill no)
			(layer "B.CrtYd")
		)
		(fp_rect
			(start 0.2794 0.6477)
			(end -0.2794 -0.6477)
			(stroke
				(width 0)
				(type default)
			)
			(fill no)
			(layer "B.Fab")
		)
		(pad "1" smd custom
			(at 0 -0.2794 90)
			(size 0.0762 0.0762)
			(layers "B.Cu" "B.Mask" "B.Paste")
			(net "GB_VDDA")
			(options
				(clearance outline)
				(anchor circle)
			)
			(primitives
				(gr_poly
					(pts
						(arc
							(start 0.1524 0.127)
							(mid 0.137521 0.162921)
							(end 0.1016 0.1778)
						)
						(arc
							(start -0.1016 0.1778)
							(mid -0.137521 0.162921)
							(end -0.1524 0.127)
						)
						(arc
							(start -0.1524 -0.127)
							(mid -0.137521 -0.162921)
							(end -0.1016 -0.1778)
						)
						(arc
							(start 0.1016 -0.1778)
							(mid 0.137521 -0.162921)
							(end 0.1524 -0.127)
						)
					)
					(width 0)
					(fill yes)
				)
			)
		)
		(pad "2" smd custom
			(at 0 0.2794 90)
			(size 0.0762 0.0762)
			(layers "B.Cu" "B.Mask" "B.Paste")
			(net "GND")
			(options
				(clearance outline)
				(anchor circle)
			)
			(primitives
				(gr_poly
					(pts
						(arc
							(start 0.1524 0.127)
							(mid 0.137521 0.162921)
							(end 0.1016 0.1778)
						)
						(arc
							(start -0.1016 0.1778)
							(mid -0.137521 0.162921)
							(end -0.1524 0.127)
						)
						(arc
							(start -0.1524 -0.127)
							(mid -0.137521 -0.162921)
							(end -0.1016 -0.1778)
						)
						(arc
							(start 0.1016 -0.1778)
							(mid 0.137521 -0.162921)
							(end 0.1524 -0.127)
						)
					)
					(width 0)
					(fill yes)
				)
			)
		)
	)
	(footprint ""
		(layer "B.Cu")
		(at 170.548808 -51.26101 180)
		(property "Reference" "C465"
			(at 0 0 0)
			(layer "B.SilkS")
			(hide yes)
			(effects
				(font
					(size 1.27 1.27)
				)
				(justify mirror)
			)
		)
		(property "Value" "SCD1U6D3V1KX-GP"
			(at 2.8321 -1.7399 180)
			(unlocked yes)
			(layer "B.Fab")
			(hide yes)
			(effects
				(font
					(size 1.016 1.016)
					(thickness 0.1524)
				)
				(justify mirror)
			)
		)
		(property "Device Type" "C0201H13"
			(at 2.8321 -3.2639 180)
			(unlocked yes)
			(layer "B.Fab")
			(hide yes)
			(effects
				(font
					(size 1.016 1.016)
					(thickness 0.1524)
				)
				(justify mirror)
			)
		)
		(duplicate_pad_numbers_are_jumpers no)
		(fp_rect
			(start 0.2794 0.6477)
			(end -0.2794 -0.6477)
			(stroke
				(width 0)
				(type default)
			)
			(fill no)
			(layer "B.CrtYd")
		)
		(fp_rect
			(start 0.2794 0.6477)
			(end -0.2794 -0.6477)
			(stroke
				(width 0)
				(type default)
			)
			(fill no)
			(layer "B.Fab")
		)
		(pad "1" smd custom
			(at 0 -0.2794)
			(size 0.0762 0.0762)
			(layers "B.Cu" "B.Mask" "B.Paste")
			(net "P1V8_C")
			(options
				(clearance outline)
				(anchor circle)
			)
			(primitives
				(gr_poly
					(pts
						(arc
							(start 0.1524 0.127)
							(mid 0.137521 0.162921)
							(end 0.1016 0.1778)
						)
						(arc
							(start -0.1016 0.1778)
							(mid -0.137521 0.162921)
							(end -0.1524 0.127)
						)
						(arc
							(start -0.1524 -0.127)
							(mid -0.137521 -0.162921)
							(end -0.1016 -0.1778)
						)
						(arc
							(start 0.1016 -0.1778)
							(mid 0.137521 -0.162921)
							(end 0.1524 -0.127)
						)
					)
					(width 0)
					(fill yes)
				)
			)
		)
		(pad "2" smd custom
			(at 0 0.2794)
			(size 0.0762 0.0762)
			(layers "B.Cu" "B.Mask" "B.Paste")
			(net "GND")
			(options
				(clearance outline)
				(anchor circle)
			)
			(primitives
				(gr_poly
					(pts
						(arc
							(start 0.1524 0.127)
							(mid 0.137521 0.162921)
							(end 0.1016 0.1778)
						)
						(arc
							(start -0.1016 0.1778)
							(mid -0.137521 0.162921)
							(end -0.1524 0.127)
						)
						(arc
							(start -0.1524 -0.127)
							(mid -0.137521 -0.162921)
							(end -0.1016 -0.1778)
						)
						(arc
							(start 0.1016 -0.1778)
							(mid 0.137521 -0.162921)
							(end 0.1524 -0.127)
						)
					)
					(width 0)
					(fill yes)
				)
			)
		)
	)
	(footprint ""
		(layer "B.Cu")
		(at 127.325374 -87.251794)
		(property "Reference" "R236"
			(at 0 0 0)
			(layer "B.SilkS")
			(hide yes)
			(effects
				(font
					(size 1.27 1.27)
				)
				(justify mirror)
			)
		)
		(property "Value" "4K75R2F-1-GP"
			(at -0.064008 -3.993896 0)
			(unlocked yes)
			(layer "B.Fab")
			(hide yes)
			(effects
				(font
					(size 1.016 1.016)
					(thickness 0.1524)
				)
				(justify mirror)
			)
		)
		(property "Device Type" "R402H16"
			(at -0.064008 -5.517896 0)
			(unlocked yes)
			(layer "B.Fab")
			(hide yes)
			(effects
				(font
					(size 1.016 1.016)
					(thickness 0.1524)
				)
				(justify mirror)
			)
		)
		(duplicate_pad_numbers_are_jumpers no)
		(fp_line
			(start -0.508 -0.9398)
			(end 0.508 -0.9398)
			(stroke
				(width 0.1524)
				(type default)
			)
			(layer "B.SilkS")
		)
		(fp_line
			(start 0.508 -0.9398)
			(end 0.508 0.9398)
			(stroke
				(width 0.1524)
				(type default)
			)
			(layer "B.SilkS")
		)
		(fp_rect
			(start 0.508 0.9398)
			(end -0.508 -0.9398)
			(stroke
				(width 0)
				(type default)
			)
			(fill no)
			(layer "B.CrtYd")
		)
		(fp_rect
			(start 0.508 0.9398)
			(end -0.508 -0.9398)
			(stroke
				(width 0)
				(type default)
			)
			(fill no)
			(layer "B.Fab")
		)
		(pad "1" smd custom
			(at 0 -0.4445 180)
			(size 0.1397 0.1397)
			(layers "B.Cu" "B.Mask" "B.Paste")
			(net "P1V8_E")
			(options
				(clearance outline)
				(anchor circle)
			)
			(primitives
				(gr_poly
					(pts
						(arc
							(start -0.1778 0.2794)
							(mid -0.249642 0.249642)
							(end -0.2794 0.1778)
						)
						(arc
							(start -0.2794 -0.1778)
							(mid -0.249642 -0.249642)
							(end -0.1778 -0.2794)
						)
						(arc
							(start 0.1778 -0.2794)
							(mid 0.249642 -0.249642)
							(end 0.2794 -0.1778)
						)
						(arc
							(start 0.2794 0.1778)
							(mid 0.249642 0.249642)
							(end 0.1778 0.2794)
						)
					)
					(width 0)
					(fill yes)
				)
			)
		)
		(pad "2" smd custom
			(at 0 0.4445 180)
			(size 0.1397 0.1397)
			(layers "B.Cu" "B.Mask" "B.Paste")
			(net "ICE_TRST_N")
			(options
				(clearance outline)
				(anchor circle)
			)
			(primitives
				(gr_poly
					(pts
						(arc
							(start -0.1778 0.2794)
							(mid -0.249642 0.249642)
							(end -0.2794 0.1778)
						)
						(arc
							(start -0.2794 -0.1778)
							(mid -0.249642 -0.249642)
							(end -0.1778 -0.2794)
						)
						(arc
							(start 0.1778 -0.2794)
							(mid 0.249642 -0.249642)
							(end 0.2794 -0.1778)
						)
						(arc
							(start 0.2794 0.1778)
							(mid 0.249642 0.249642)
							(end 0.1778 0.2794)
						)
					)
					(width 0)
					(fill yes)
				)
			)
		)
	)
	(footprint ""
		(layer "B.Cu")
		(at 100.33 -57.4802 -90)
		(property "Reference" "C195"
			(at 0 0 90)
			(layer "B.SilkS")
			(hide yes)
			(effects
				(font
					(size 1.27 1.27)
				)
				(justify mirror)
			)
		)
		(property "Value" "SCD1U6D3V1KX-GP"
			(at 2.8321 -1.7399 270)
			(unlocked yes)
			(layer "B.Fab")
			(hide yes)
			(effects
				(font
					(size 1.016 1.016)
					(thickness 0.1524)
				)
				(justify mirror)
			)
		)
		(property "Device Type" "C0201H13"
			(at 2.8321 -3.2639 270)
			(unlocked yes)
			(layer "B.Fab")
			(hide yes)
			(effects
				(font
					(size 1.016 1.016)
					(thickness 0.1524)
				)
				(justify mirror)
			)
		)
		(duplicate_pad_numbers_are_jumpers no)
		(fp_rect
			(start 0.2794 0.6477)
			(end -0.2794 -0.6477)
			(stroke
				(width 0)
				(type default)
			)
			(fill no)
			(layer "B.CrtYd")
		)
		(fp_rect
			(start 0.2794 0.6477)
			(end -0.2794 -0.6477)
			(stroke
				(width 0)
				(type default)
			)
			(fill no)
			(layer "B.Fab")
		)
		(pad "1" smd custom
			(at 0 -0.2794 90)
			(size 0.0762 0.0762)
			(layers "B.Cu" "B.Mask" "B.Paste")
			(net "XTAL_VDDA18")
			(options
				(clearance outline)
				(anchor circle)
			)
			(primitives
				(gr_poly
					(pts
						(arc
							(start 0.1524 0.127)
							(mid 0.137521 0.162921)
							(end 0.1016 0.1778)
						)
						(arc
							(start -0.1016 0.1778)
							(mid -0.137521 0.162921)
							(end -0.1524 0.127)
						)
						(arc
							(start -0.1524 -0.127)
							(mid -0.137521 -0.162921)
							(end -0.1016 -0.1778)
						)
						(arc
							(start 0.1016 -0.1778)
							(mid 0.137521 -0.162921)
							(end 0.1524 -0.127)
						)
					)
					(width 0)
					(fill yes)
				)
			)
		)
		(pad "2" smd custom
			(at 0 0.2794 90)
			(size 0.0762 0.0762)
			(layers "B.Cu" "B.Mask" "B.Paste")
			(net "GND")
			(options
				(clearance outline)
				(anchor circle)
			)
			(primitives
				(gr_poly
					(pts
						(arc
							(start 0.1524 0.127)
							(mid 0.137521 0.162921)
							(end 0.1016 0.1778)
						)
						(arc
							(start -0.1016 0.1778)
							(mid -0.137521 0.162921)
							(end -0.1524 0.127)
						)
						(arc
							(start -0.1524 -0.127)
							(mid -0.137521 -0.162921)
							(end -0.1016 -0.1778)
						)
						(arc
							(start 0.1016 -0.1778)
							(mid 0.137521 -0.162921)
							(end 0.1524 -0.127)
						)
					)
					(width 0)
					(fill yes)
				)
			)
		)
	)
	(footprint ""
		(layer "B.Cu")
		(at 137.603738 -84.70011)
		(property "Reference" "R51"
			(at 0 0 0)
			(layer "B.SilkS")
			(hide yes)
			(effects
				(font
					(size 1.27 1.27)
				)
				(justify mirror)
			)
		)
		(property "Value" "4K7R2F-GP"
			(at -0.064008 -3.993896 0)
			(unlocked yes)
			(layer "B.Fab")
			(hide yes)
			(effects
				(font
					(size 1.016 1.016)
					(thickness 0.1524)
				)
				(justify mirror)
			)
		)
		(property "Device Type" "R402H16"
			(at -0.064008 -5.517896 0)
			(unlocked yes)
			(layer "B.Fab")
			(hide yes)
			(effects
				(font
					(size 1.016 1.016)
					(thickness 0.1524)
				)
				(justify mirror)
			)
		)
		(duplicate_pad_numbers_are_jumpers no)
		(fp_line
			(start -0.508 -0.9398)
			(end 0.508 -0.9398)
			(stroke
				(width 0.1524)
				(type default)
			)
			(layer "B.SilkS")
		)
		(fp_line
			(start 0.508 -0.9398)
			(end 0.508 0.9398)
			(stroke
				(width 0.1524)
				(type default)
			)
			(layer "B.SilkS")
		)
		(fp_rect
			(start 0.508 0.9398)
			(end -0.508 -0.9398)
			(stroke
				(width 0)
				(type default)
			)
			(fill no)
			(layer "B.CrtYd")
		)
		(fp_rect
			(start 0.508 0.9398)
			(end -0.508 -0.9398)
			(stroke
				(width 0)
				(type default)
			)
			(fill no)
			(layer "B.Fab")
		)
		(pad "1" smd custom
			(at 0 -0.4445 180)
			(size 0.1397 0.1397)
			(layers "B.Cu" "B.Mask" "B.Paste")
			(net "P1V8_E")
			(options
				(clearance outline)
				(anchor circle)
			)
			(primitives
				(gr_poly
					(pts
						(arc
							(start -0.1778 0.2794)
							(mid -0.249642 0.249642)
							(end -0.2794 0.1778)
						)
						(arc
							(start -0.2794 -0.1778)
							(mid -0.249642 -0.249642)
							(end -0.1778 -0.2794)
						)
						(arc
							(start 0.1778 -0.2794)
							(mid 0.249642 -0.249642)
							(end 0.2794 -0.1778)
						)
						(arc
							(start 0.2794 0.1778)
							(mid 0.249642 0.249642)
							(end 0.1778 0.2794)
						)
					)
					(width 0)
					(fill yes)
				)
			)
		)
		(pad "2" smd custom
			(at 0 0.4445 180)
			(size 0.1397 0.1397)
			(layers "B.Cu" "B.Mask" "B.Paste")
			(net "I2C_BMC_RMT_SDA1_LS")
			(options
				(clearance outline)
				(anchor circle)
			)
			(primitives
				(gr_poly
					(pts
						(arc
							(start -0.1778 0.2794)
							(mid -0.249642 0.249642)
							(end -0.2794 0.1778)
						)
						(arc
							(start -0.2794 -0.1778)
							(mid -0.249642 -0.249642)
							(end -0.1778 -0.2794)
						)
						(arc
							(start 0.1778 -0.2794)
							(mid 0.249642 -0.249642)
							(end 0.2794 -0.1778)
						)
						(arc
							(start 0.2794 0.1778)
							(mid 0.249642 0.249642)
							(end 0.1778 0.2794)
						)
					)
					(width 0)
					(fill yes)
				)
			)
		)
	)
	(footprint ""
		(layer "B.Cu")
		(at 108.2802 -62.865 180)
		(property "Reference" "C221"
			(at 0 0 0)
			(layer "B.SilkS")
			(hide yes)
			(effects
				(font
					(size 1.27 1.27)
				)
				(justify mirror)
			)
		)
		(property "Value" "SCD1U16V2KX-3GP"
			(at -1.1811 -2.7051 180)
			(unlocked yes)
			(layer "B.Fab")
			(hide yes)
			(effects
				(font
					(size 1.016 1.016)
					(thickness 0.1524)
				)
				(justify mirror)
			)
		)
		(property "Device Type" "C402H22"
			(at -1.1811 -4.2291 180)
			(unlocked yes)
			(layer "B.Fab")
			(hide yes)
			(effects
				(font
					(size 1.016 1.016)
					(thickness 0.1524)
				)
				(justify mirror)
			)
		)
		(duplicate_pad_numbers_are_jumpers no)
		(fp_rect
			(start 0.4318 0.9525)
			(end -0.4318 -0.9525)
			(stroke
				(width 0)
				(type default)
			)
			(fill no)
			(layer "B.CrtYd")
		)
		(fp_rect
			(start 0.4318 0.9525)
			(end -0.4318 -0.9525)
			(stroke
				(width 0)
				(type default)
			)
			(fill no)
			(layer "B.Fab")
		)
		(pad "1" smd custom
			(at 0 -0.4445)
			(size 0.1524 0.1524)
			(layers "B.Cu" "B.Mask" "B.Paste")
			(net "GB_VDDH")
			(options
				(clearance outline)
				(anchor circle)
			)
			(primitives
				(gr_poly
					(pts
						(arc
							(start 0.3048 0.2032)
							(mid 0.275042 0.275042)
							(end 0.2032 0.3048)
						)
						(arc
							(start -0.2032 0.3048)
							(mid -0.275042 0.275042)
							(end -0.3048 0.2032)
						)
						(arc
							(start -0.3048 -0.2032)
							(mid -0.275042 -0.275042)
							(end -0.2032 -0.3048)
						)
						(arc
							(start 0.2032 -0.3048)
							(mid 0.275042 -0.275042)
							(end 0.3048 -0.2032)
						)
					)
					(width 0)
					(fill yes)
				)
			)
		)
		(pad "2" smd custom
			(at 0 0.4445)
			(size 0.1524 0.1524)
			(layers "B.Cu" "B.Mask" "B.Paste")
			(net "GND")
			(options
				(clearance outline)
				(anchor circle)
			)
			(primitives
				(gr_poly
					(pts
						(arc
							(start 0.3048 0.2032)
							(mid 0.275042 0.275042)
							(end 0.2032 0.3048)
						)
						(arc
							(start -0.2032 0.3048)
							(mid -0.275042 0.275042)
							(end -0.3048 0.2032)
						)
						(arc
							(start -0.3048 -0.2032)
							(mid -0.275042 -0.275042)
							(end -0.2032 -0.3048)
						)
						(arc
							(start 0.2032 -0.3048)
							(mid 0.275042 -0.275042)
							(end 0.3048 -0.2032)
						)
					)
					(width 0)
					(fill yes)
				)
			)
		)
	)
	(footprint ""
		(layer "B.Cu")
		(at 189.397386 -46.682152 -90)
		(property "Reference" "TP108"
			(at 0 0 90)
			(layer "B.SilkS")
			(hide yes)
			(effects
				(font
					(size 1.27 1.27)
				)
				(justify mirror)
			)
		)
		(property "Value" "TPAD28-2-GP"
			(at 0.0127 -1.6637 270)
			(unlocked yes)
			(layer "B.Fab")
			(hide yes)
			(effects
				(font
					(size 1.016 1.016)
					(thickness 0.1524)
				)
				(justify mirror)
			)
		)
		(property "Device Type" "TPAD28"
			(at 0.0127 -3.1877 270)
			(unlocked yes)
			(layer "B.Fab")
			(hide yes)
			(effects
				(font
					(size 1.016 1.016)
					(thickness 0.1524)
				)
				(justify mirror)
			)
		)
		(duplicate_pad_numbers_are_jumpers no)
		(fp_poly
			(pts
				(arc
					(start 0 -0.3556)
					(mid 0 0.3556)
					(end 0 -0.3556)
				)
			)
			(stroke
				(width 0)
				(type default)
			)
			(fill no)
			(layer "B.CrtYd")
		)
		(fp_poly
			(pts
				(arc
					(start 0 -0.6096)
					(mid 0 0.6096)
					(end 0 -0.6096)
				)
			)
			(stroke
				(width 0)
				(type default)
			)
			(fill no)
			(layer "B.Fab")
		)
		(pad "1" smd circle
			(at 0 0 90)
			(size 0.7112 0.7112)
			(layers "B.Cu" "B.Mask" "B.Paste")
			(net "XM_ADDR_21")
		)
	)
	(footprint ""
		(layer "B.Cu")
		(at 176.22139 -39.709344 90)
		(property "Reference" "C412"
			(at 0 0 90)
			(layer "B.SilkS")
			(hide yes)
			(effects
				(font
					(size 1.27 1.27)
				)
				(justify mirror)
			)
		)
		(property "Value" "SC1U6D3V1MX-GP"
			(at -1.9177 2.0193 90)
			(unlocked yes)
			(layer "B.Fab")
			(hide yes)
			(effects
				(font
					(size 1.016 1.016)
					(thickness 0.1524)
				)
				(justify mirror)
			)
		)
		(property "Device Type" "C0201H14"
			(at -1.9177 0.4953 90)
			(unlocked yes)
			(layer "B.Fab")
			(hide yes)
			(effects
				(font
					(size 1.016 1.016)
					(thickness 0.1524)
				)
				(justify mirror)
			)
		)
		(duplicate_pad_numbers_are_jumpers no)
		(fp_rect
			(start 0.1524 0.3048)
			(end -0.1524 -0.3048)
			(stroke
				(width 0)
				(type default)
			)
			(fill no)
			(layer "B.CrtYd")
		)
		(fp_poly
			(pts
				(xy 0.2794 0.6477) (xy 0.2794 -0.6477) (xy -0.2794 -0.6477) (xy -0.2794 -0.1905) (xy -0.1524 -0.1905)
				(xy -0.1524 -0.3048) (xy 0.1524 -0.3048) (xy 0.1524 0.3048) (xy -0.1524 0.3048) (xy -0.1524 -0.1778)
				(xy -0.2794 -0.1778) (xy -0.2794 0.6477)
			)
			(stroke
				(width 0)
				(type default)
			)
			(fill no)
			(layer "B.CrtYd")
		)
		(fp_rect
			(start 0.2794 0.6477)
			(end -0.2794 -0.6477)
			(stroke
				(width 0)
				(type default)
			)
			(fill no)
			(layer "B.Fab")
		)
		(pad "1" smd custom
			(at 0 -0.2794 270)
			(size 0.0762 0.0762)
			(layers "B.Cu" "B.Mask" "B.Paste")
			(net "P0V975")
			(options
				(clearance outline)
				(anchor circle)
			)
			(primitives
				(gr_poly
					(pts
						(arc
							(start 0.1524 0.127)
							(mid 0.137521 0.162921)
							(end 0.1016 0.1778)
						)
						(arc
							(start -0.1016 0.1778)
							(mid -0.137521 0.162921)
							(end -0.1524 0.127)
						)
						(arc
							(start -0.1524 -0.127)
							(mid -0.137521 -0.162921)
							(end -0.1016 -0.1778)
						)
						(arc
							(start 0.1016 -0.1778)
							(mid 0.137521 -0.162921)
							(end 0.1524 -0.127)
						)
					)
					(width 0)
					(fill yes)
				)
			)
		)
		(pad "2" smd custom
			(at 0 0.2794 270)
			(size 0.0762 0.0762)
			(layers "B.Cu" "B.Mask" "B.Paste")
			(net "GND")
			(options
				(clearance outline)
				(anchor circle)
			)
			(primitives
				(gr_poly
					(pts
						(arc
							(start 0.1524 0.127)
							(mid 0.137521 0.162921)
							(end 0.1016 0.1778)
						)
						(arc
							(start -0.1016 0.1778)
							(mid -0.137521 0.162921)
							(end -0.1524 0.127)
						)
						(arc
							(start -0.1524 -0.127)
							(mid -0.137521 -0.162921)
							(end -0.1016 -0.1778)
						)
						(arc
							(start 0.1016 -0.1778)
							(mid 0.137521 -0.162921)
							(end 0.1524 -0.127)
						)
					)
					(width 0)
					(fill yes)
				)
			)
		)
	)
	(footprint ""
		(layer "B.Cu")
		(at 172.844206 -66.764916 -90)
		(property "Reference" "R547"
			(at 0 0 90)
			(layer "B.SilkS")
			(hide yes)
			(effects
				(font
					(size 1.27 1.27)
				)
				(justify mirror)
			)
		)
		(property "Value" "4K7R2F-GP"
			(at -0.064008 -3.993896 270)
			(unlocked yes)
			(layer "B.Fab")
			(hide yes)
			(effects
				(font
					(size 1.016 1.016)
					(thickness 0.1524)
				)
				(justify mirror)
			)
		)
		(property "Device Type" "R402H16"
			(at -0.064008 -5.517896 270)
			(unlocked yes)
			(layer "B.Fab")
			(hide yes)
			(effects
				(font
					(size 1.016 1.016)
					(thickness 0.1524)
				)
				(justify mirror)
			)
		)
		(duplicate_pad_numbers_are_jumpers no)
		(fp_line
			(start -0.508 -0.9398)
			(end 0.508 -0.9398)
			(stroke
				(width 0.1524)
				(type default)
			)
			(layer "B.SilkS")
		)
		(fp_line
			(start 0.508 -0.9398)
			(end 0.508 0.9398)
			(stroke
				(width 0.1524)
				(type default)
			)
			(layer "B.SilkS")
		)
		(fp_rect
			(start 0.508 0.9398)
			(end -0.508 -0.9398)
			(stroke
				(width 0)
				(type default)
			)
			(fill no)
			(layer "B.CrtYd")
		)
		(fp_rect
			(start 0.508 0.9398)
			(end -0.508 -0.9398)
			(stroke
				(width 0)
				(type default)
			)
			(fill no)
			(layer "B.Fab")
		)
		(pad "1" smd custom
			(at 0 -0.4445 90)
			(size 0.1397 0.1397)
			(layers "B.Cu" "B.Mask" "B.Paste")
			(net "IOC_VREF_SET_LS")
			(options
				(clearance outline)
				(anchor circle)
			)
			(primitives
				(gr_poly
					(pts
						(arc
							(start -0.1778 0.2794)
							(mid -0.249642 0.249642)
							(end -0.2794 0.1778)
						)
						(arc
							(start -0.2794 -0.1778)
							(mid -0.249642 -0.249642)
							(end -0.1778 -0.2794)
						)
						(arc
							(start 0.1778 -0.2794)
							(mid 0.249642 -0.249642)
							(end 0.2794 -0.1778)
						)
						(arc
							(start 0.2794 0.1778)
							(mid 0.249642 0.249642)
							(end 0.1778 0.2794)
						)
					)
					(width 0)
					(fill yes)
				)
			)
		)
		(pad "2" smd custom
			(at 0 0.4445 90)
			(size 0.1397 0.1397)
			(layers "B.Cu" "B.Mask" "B.Paste")
			(net "GND")
			(options
				(clearance outline)
				(anchor circle)
			)
			(primitives
				(gr_poly
					(pts
						(arc
							(start -0.1778 0.2794)
							(mid -0.249642 0.249642)
							(end -0.2794 0.1778)
						)
						(arc
							(start -0.2794 -0.1778)
							(mid -0.249642 -0.249642)
							(end -0.1778 -0.2794)
						)
						(arc
							(start 0.1778 -0.2794)
							(mid 0.249642 -0.249642)
							(end 0.2794 -0.1778)
						)
						(arc
							(start 0.2794 0.1778)
							(mid 0.249642 0.249642)
							(end 0.1778 0.2794)
						)
					)
					(width 0)
					(fill yes)
				)
			)
		)
	)
	(footprint ""
		(layer "B.Cu")
		(at 164.961316 -35.202114 -90)
		(property "Reference" "C397"
			(at 0 0 90)
			(layer "B.SilkS")
			(hide yes)
			(effects
				(font
					(size 1.27 1.27)
				)
				(justify mirror)
			)
		)
		(property "Value" "SCD1U16V2KX-3GP"
			(at -1.1811 -2.7051 270)
			(unlocked yes)
			(layer "B.Fab")
			(hide yes)
			(effects
				(font
					(size 1.016 1.016)
					(thickness 0.1524)
				)
				(justify mirror)
			)
		)
		(property "Device Type" "C402H22"
			(at -1.1811 -4.2291 270)
			(unlocked yes)
			(layer "B.Fab")
			(hide yes)
			(effects
				(font
					(size 1.016 1.016)
					(thickness 0.1524)
				)
				(justify mirror)
			)
		)
		(duplicate_pad_numbers_are_jumpers no)
		(fp_rect
			(start 0.4318 0.9525)
			(end -0.4318 -0.9525)
			(stroke
				(width 0)
				(type default)
			)
			(fill no)
			(layer "B.CrtYd")
		)
		(fp_rect
			(start 0.4318 0.9525)
			(end -0.4318 -0.9525)
			(stroke
				(width 0)
				(type default)
			)
			(fill no)
			(layer "B.Fab")
		)
		(pad "1" smd custom
			(at 0 -0.4445 90)
			(size 0.1524 0.1524)
			(layers "B.Cu" "B.Mask" "B.Paste")
			(net "SAS0_AVDD")
			(options
				(clearance outline)
				(anchor circle)
			)
			(primitives
				(gr_poly
					(pts
						(arc
							(start 0.3048 0.2032)
							(mid 0.275042 0.275042)
							(end 0.2032 0.3048)
						)
						(arc
							(start -0.2032 0.3048)
							(mid -0.275042 0.275042)
							(end -0.3048 0.2032)
						)
						(arc
							(start -0.3048 -0.2032)
							(mid -0.275042 -0.275042)
							(end -0.2032 -0.3048)
						)
						(arc
							(start 0.2032 -0.3048)
							(mid 0.275042 -0.275042)
							(end 0.3048 -0.2032)
						)
					)
					(width 0)
					(fill yes)
				)
			)
		)
		(pad "2" smd custom
			(at 0 0.4445 90)
			(size 0.1524 0.1524)
			(layers "B.Cu" "B.Mask" "B.Paste")
			(net "GND")
			(options
				(clearance outline)
				(anchor circle)
			)
			(primitives
				(gr_poly
					(pts
						(arc
							(start 0.3048 0.2032)
							(mid 0.275042 0.275042)
							(end 0.2032 0.3048)
						)
						(arc
							(start -0.2032 0.3048)
							(mid -0.275042 0.275042)
							(end -0.3048 0.2032)
						)
						(arc
							(start -0.3048 -0.2032)
							(mid -0.275042 -0.275042)
							(end -0.2032 -0.3048)
						)
						(arc
							(start 0.2032 -0.3048)
							(mid 0.275042 -0.275042)
							(end 0.3048 -0.2032)
						)
					)
					(width 0)
					(fill yes)
				)
			)
		)
	)
	(footprint ""
		(layer "B.Cu")
		(at 109.4867 -59.4487)
		(property "Reference" "C537"
			(at 0 0 0)
			(layer "B.SilkS")
			(hide yes)
			(effects
				(font
					(size 1.27 1.27)
				)
				(justify mirror)
			)
		)
		(property "Value" "SCD1U6D3V1KX-GP"
			(at 2.8321 -1.7399 0)
			(unlocked yes)
			(layer "B.Fab")
			(hide yes)
			(effects
				(font
					(size 1.016 1.016)
					(thickness 0.1524)
				)
				(justify mirror)
			)
		)
		(property "Device Type" "C0201H13"
			(at 2.8321 -3.2639 0)
			(unlocked yes)
			(layer "B.Fab")
			(hide yes)
			(effects
				(font
					(size 1.016 1.016)
					(thickness 0.1524)
				)
				(justify mirror)
			)
		)
		(duplicate_pad_numbers_are_jumpers no)
		(fp_rect
			(start 0.2794 0.6477)
			(end -0.2794 -0.6477)
			(stroke
				(width 0)
				(type default)
			)
			(fill no)
			(layer "B.CrtYd")
		)
		(fp_rect
			(start 0.2794 0.6477)
			(end -0.2794 -0.6477)
			(stroke
				(width 0)
				(type default)
			)
			(fill no)
			(layer "B.Fab")
		)
		(pad "1" smd custom
			(at 0 -0.2794 180)
			(size 0.0762 0.0762)
			(layers "B.Cu" "B.Mask" "B.Paste")
			(net "GB_VDDA")
			(options
				(clearance outline)
				(anchor circle)
			)
			(primitives
				(gr_poly
					(pts
						(arc
							(start 0.1524 0.127)
							(mid 0.137521 0.162921)
							(end 0.1016 0.1778)
						)
						(arc
							(start -0.1016 0.1778)
							(mid -0.137521 0.162921)
							(end -0.1524 0.127)
						)
						(arc
							(start -0.1524 -0.127)
							(mid -0.137521 -0.162921)
							(end -0.1016 -0.1778)
						)
						(arc
							(start 0.1016 -0.1778)
							(mid 0.137521 -0.162921)
							(end 0.1524 -0.127)
						)
					)
					(width 0)
					(fill yes)
				)
			)
		)
		(pad "2" smd custom
			(at 0 0.2794 180)
			(size 0.0762 0.0762)
			(layers "B.Cu" "B.Mask" "B.Paste")
			(net "GND")
			(options
				(clearance outline)
				(anchor circle)
			)
			(primitives
				(gr_poly
					(pts
						(arc
							(start 0.1524 0.127)
							(mid 0.137521 0.162921)
							(end 0.1016 0.1778)
						)
						(arc
							(start -0.1016 0.1778)
							(mid -0.137521 0.162921)
							(end -0.1524 0.127)
						)
						(arc
							(start -0.1524 -0.127)
							(mid -0.137521 -0.162921)
							(end -0.1016 -0.1778)
						)
						(arc
							(start 0.1016 -0.1778)
							(mid 0.137521 -0.162921)
							(end 0.1524 -0.127)
						)
					)
					(width 0)
					(fill yes)
				)
			)
		)
	)
	(footprint ""
		(layer "B.Cu")
		(at 93.311472 -67.625214 180)
		(property "Reference" "C201"
			(at 0 0 0)
			(layer "B.SilkS")
			(hide yes)
			(effects
				(font
					(size 1.27 1.27)
				)
				(justify mirror)
			)
		)
		(property "Value" "SC10U6D3V2MX-GP-U"
			(at 1.524 -1.905 180)
			(unlocked yes)
			(layer "B.Fab")
			(hide yes)
			(effects
				(font
					(size 1.016 1.016)
					(thickness 0.1524)
				)
				(justify mirror)
			)
		)
		(property "Device Type" "C402-TO0D2H28"
			(at 1.524 -3.429 180)
			(unlocked yes)
			(layer "B.Fab")
			(hide yes)
			(effects
				(font
					(size 1.016 1.016)
					(thickness 0.1524)
				)
				(justify mirror)
			)
		)
		(duplicate_pad_numbers_are_jumpers no)
		(fp_rect
			(start 0.4826 0.889)
			(end -0.4826 -0.889)
			(stroke
				(width 0)
				(type default)
			)
			(fill no)
			(layer "B.CrtYd")
		)
		(fp_rect
			(start 0.4826 0.889)
			(end -0.4826 -0.889)
			(stroke
				(width 0)
				(type default)
			)
			(fill no)
			(layer "B.Fab")
		)
		(pad "1" smd custom
			(at 0 -0.4572)
			(size 0.1524 0.1524)
			(layers "B.Cu" "B.Mask" "B.Paste")
			(net "PLLDDR_VDDA18")
			(options
				(clearance outline)
				(anchor circle)
			)
			(primitives
				(gr_poly
					(pts
						(arc
							(start -0.254 -0.3048)
							(mid -0.325842 -0.275042)
							(end -0.3556 -0.2032)
						)
						(arc
							(start -0.3556 0.2032)
							(mid -0.325842 0.275042)
							(end -0.254 0.3048)
						)
						(arc
							(start 0.254 0.3048)
							(mid 0.325842 0.275042)
							(end 0.3556 0.2032)
						)
						(arc
							(start 0.3556 -0.2032)
							(mid 0.325842 -0.275042)
							(end 0.254 -0.3048)
						)
					)
					(width 0)
					(fill yes)
				)
			)
		)
		(pad "2" smd custom
			(at 0 0.4572)
			(size 0.1524 0.1524)
			(layers "B.Cu" "B.Mask" "B.Paste")
			(net "GND")
			(options
				(clearance outline)
				(anchor circle)
			)
			(primitives
				(gr_poly
					(pts
						(arc
							(start -0.254 -0.3048)
							(mid -0.325842 -0.275042)
							(end -0.3556 -0.2032)
						)
						(arc
							(start -0.3556 0.2032)
							(mid -0.325842 0.275042)
							(end -0.254 0.3048)
						)
						(arc
							(start 0.254 0.3048)
							(mid 0.325842 0.275042)
							(end 0.3556 0.2032)
						)
						(arc
							(start 0.3556 -0.2032)
							(mid 0.325842 -0.275042)
							(end 0.254 -0.3048)
						)
					)
					(width 0)
					(fill yes)
				)
			)
		)
	)
	(footprint ""
		(layer "B.Cu")
		(at 121.4374 -39.4716 180)
		(property "Reference" "C56"
			(at 0 0 0)
			(layer "B.SilkS")
			(hide yes)
			(effects
				(font
					(size 1.27 1.27)
				)
				(justify mirror)
			)
		)
		(property "Value" "SCD01U16V1KX-GP"
			(at 2.8321 -1.7399 180)
			(unlocked yes)
			(layer "B.Fab")
			(hide yes)
			(effects
				(font
					(size 1.016 1.016)
					(thickness 0.1524)
				)
				(justify mirror)
			)
		)
		(property "Device Type" "C0201H13"
			(at 2.8321 -3.2639 180)
			(unlocked yes)
			(layer "B.Fab")
			(hide yes)
			(effects
				(font
					(size 1.016 1.016)
					(thickness 0.1524)
				)
				(justify mirror)
			)
		)
		(duplicate_pad_numbers_are_jumpers no)
		(fp_rect
			(start 0.2794 0.6477)
			(end -0.2794 -0.6477)
			(stroke
				(width 0)
				(type default)
			)
			(fill no)
			(layer "B.CrtYd")
		)
		(fp_rect
			(start 0.2794 0.6477)
			(end -0.2794 -0.6477)
			(stroke
				(width 0)
				(type default)
			)
			(fill no)
			(layer "B.Fab")
		)
		(pad "1" smd custom
			(at 0 -0.2794)
			(size 0.0762 0.0762)
			(layers "B.Cu" "B.Mask" "B.Paste")
			(net "PHY_DPB_TO_SCC_36_DN")
			(options
				(clearance outline)
				(anchor circle)
			)
			(primitives
				(gr_poly
					(pts
						(arc
							(start 0.1524 0.127)
							(mid 0.137521 0.162921)
							(end 0.1016 0.1778)
						)
						(arc
							(start -0.1016 0.1778)
							(mid -0.137521 0.162921)
							(end -0.1524 0.127)
						)
						(arc
							(start -0.1524 -0.127)
							(mid -0.137521 -0.162921)
							(end -0.1016 -0.1778)
						)
						(arc
							(start 0.1016 -0.1778)
							(mid 0.137521 -0.162921)
							(end 0.1524 -0.127)
						)
					)
					(width 0)
					(fill yes)
				)
			)
		)
		(pad "2" smd custom
			(at 0 0.2794)
			(size 0.0762 0.0762)
			(layers "B.Cu" "B.Mask" "B.Paste")
			(net "PHY_DPB_TO_SCC_C_36_DN")
			(options
				(clearance outline)
				(anchor circle)
			)
			(primitives
				(gr_poly
					(pts
						(arc
							(start 0.1524 0.127)
							(mid 0.137521 0.162921)
							(end 0.1016 0.1778)
						)
						(arc
							(start -0.1016 0.1778)
							(mid -0.137521 0.162921)
							(end -0.1524 0.127)
						)
						(arc
							(start -0.1524 -0.127)
							(mid -0.137521 -0.162921)
							(end -0.1016 -0.1778)
						)
						(arc
							(start 0.1016 -0.1778)
							(mid 0.137521 -0.162921)
							(end 0.1524 -0.127)
						)
					)
					(width 0)
					(fill yes)
				)
			)
		)
	)
	(footprint ""
		(layer "B.Cu")
		(at 179.767738 -35.155124 -90)
		(property "Reference" "R273"
			(at 0 0 90)
			(layer "B.SilkS")
			(hide yes)
			(effects
				(font
					(size 1.27 1.27)
				)
				(justify mirror)
			)
		)
		(property "Value" "10KR2F-2-GP"
			(at -0.064008 -3.993896 270)
			(unlocked yes)
			(layer "B.Fab")
			(hide yes)
			(effects
				(font
					(size 1.016 1.016)
					(thickness 0.1524)
				)
				(justify mirror)
			)
		)
		(property "Device Type" "R402H16"
			(at -0.064008 -5.517896 270)
			(unlocked yes)
			(layer "B.Fab")
			(hide yes)
			(effects
				(font
					(size 1.016 1.016)
					(thickness 0.1524)
				)
				(justify mirror)
			)
		)
		(duplicate_pad_numbers_are_jumpers no)
		(fp_line
			(start -0.508 -0.9398)
			(end 0.508 -0.9398)
			(stroke
				(width 0.1524)
				(type default)
			)
			(layer "B.SilkS")
		)
		(fp_line
			(start 0.508 -0.9398)
			(end 0.508 0.9398)
			(stroke
				(width 0.1524)
				(type default)
			)
			(layer "B.SilkS")
		)
		(fp_rect
			(start 0.508 0.9398)
			(end -0.508 -0.9398)
			(stroke
				(width 0)
				(type default)
			)
			(fill no)
			(layer "B.CrtYd")
		)
		(fp_rect
			(start 0.508 0.9398)
			(end -0.508 -0.9398)
			(stroke
				(width 0)
				(type default)
			)
			(fill no)
			(layer "B.Fab")
		)
		(pad "1" smd custom
			(at 0 -0.4445 90)
			(size 0.1397 0.1397)
			(layers "B.Cu" "B.Mask" "B.Paste")
			(net "SYS_DBMODE0")
			(options
				(clearance outline)
				(anchor circle)
			)
			(primitives
				(gr_poly
					(pts
						(arc
							(start -0.1778 0.2794)
							(mid -0.249642 0.249642)
							(end -0.2794 0.1778)
						)
						(arc
							(start -0.2794 -0.1778)
							(mid -0.249642 -0.249642)
							(end -0.1778 -0.2794)
						)
						(arc
							(start 0.1778 -0.2794)
							(mid 0.249642 -0.249642)
							(end 0.2794 -0.1778)
						)
						(arc
							(start 0.2794 0.1778)
							(mid 0.249642 0.249642)
							(end 0.1778 0.2794)
						)
					)
					(width 0)
					(fill yes)
				)
			)
		)
		(pad "2" smd custom
			(at 0 0.4445 90)
			(size 0.1397 0.1397)
			(layers "B.Cu" "B.Mask" "B.Paste")
			(net "GND")
			(options
				(clearance outline)
				(anchor circle)
			)
			(primitives
				(gr_poly
					(pts
						(arc
							(start -0.1778 0.2794)
							(mid -0.249642 0.249642)
							(end -0.2794 0.1778)
						)
						(arc
							(start -0.2794 -0.1778)
							(mid -0.249642 -0.249642)
							(end -0.1778 -0.2794)
						)
						(arc
							(start 0.1778 -0.2794)
							(mid 0.249642 -0.249642)
							(end 0.2794 -0.1778)
						)
						(arc
							(start 0.2794 0.1778)
							(mid 0.249642 0.249642)
							(end 0.1778 0.2794)
						)
					)
					(width 0)
					(fill yes)
				)
			)
		)
	)
	(footprint ""
		(layer "B.Cu")
		(at 127.880872 -82.37855)
		(property "Reference" "TP36"
			(at 0 0 0)
			(layer "B.SilkS")
			(hide yes)
			(effects
				(font
					(size 1.27 1.27)
				)
				(justify mirror)
			)
		)
		(property "Value" "TPAD28-2-GP"
			(at 0.0127 -1.6637 0)
			(unlocked yes)
			(layer "B.Fab")
			(hide yes)
			(effects
				(font
					(size 1.016 1.016)
					(thickness 0.1524)
				)
				(justify mirror)
			)
		)
		(property "Device Type" "TPAD28"
			(at 0.0127 -3.1877 0)
			(unlocked yes)
			(layer "B.Fab")
			(hide yes)
			(effects
				(font
					(size 1.016 1.016)
					(thickness 0.1524)
				)
				(justify mirror)
			)
		)
		(duplicate_pad_numbers_are_jumpers no)
		(fp_poly
			(pts
				(arc
					(start 0.3556 0)
					(mid -0.3556 0)
					(end 0.3556 0)
				)
			)
			(stroke
				(width 0)
				(type default)
			)
			(fill no)
			(layer "B.CrtYd")
		)
		(fp_poly
			(pts
				(arc
					(start 0.6096 0)
					(mid -0.6096 0)
					(end 0.6096 0)
				)
			)
			(stroke
				(width 0)
				(type default)
			)
			(fill no)
			(layer "B.Fab")
		)
		(pad "1" smd circle
			(at 0 0 180)
			(size 0.7112 0.7112)
			(layers "B.Cu" "B.Mask" "B.Paste")
			(net "UART_RTS")
		)
	)
	(footprint ""
		(layer "B.Cu")
		(at 189.7888 -32.3596 90)
		(property "Reference" "TP70"
			(at 0 0 90)
			(layer "B.SilkS")
			(hide yes)
			(effects
				(font
					(size 1.27 1.27)
				)
				(justify mirror)
			)
		)
		(property "Value" "TPAD28-2-GP"
			(at 0.0127 -1.6637 90)
			(unlocked yes)
			(layer "B.Fab")
			(hide yes)
			(effects
				(font
					(size 1.016 1.016)
					(thickness 0.1524)
				)
				(justify mirror)
			)
		)
		(property "Device Type" "TPAD28"
			(at 0.0127 -3.1877 90)
			(unlocked yes)
			(layer "B.Fab")
			(hide yes)
			(effects
				(font
					(size 1.016 1.016)
					(thickness 0.1524)
				)
				(justify mirror)
			)
		)
		(duplicate_pad_numbers_are_jumpers no)
		(fp_poly
			(pts
				(arc
					(start 0 0.3556)
					(mid 0 -0.3556)
					(end 0 0.3556)
				)
			)
			(stroke
				(width 0)
				(type default)
			)
			(fill no)
			(layer "B.CrtYd")
		)
		(fp_poly
			(pts
				(arc
					(start 0 0.6096)
					(mid 0 -0.6096)
					(end 0 0.6096)
				)
			)
			(stroke
				(width 0)
				(type default)
			)
			(fill no)
			(layer "B.Fab")
		)
		(pad "1" smd circle
			(at 0 0 270)
			(size 0.7112 0.7112)
			(layers "B.Cu" "B.Mask" "B.Paste")
			(net "IOC_GPIO_17")
		)
	)
	(footprint ""
		(layer "B.Cu")
		(at 158.496 -52.07)
		(property "Reference" "R194"
			(at 0 0 0)
			(layer "B.SilkS")
			(hide yes)
			(effects
				(font
					(size 1.27 1.27)
				)
				(justify mirror)
			)
		)
		(property "Value" "2K2R2F-GP"
			(at -0.064008 -3.993896 0)
			(unlocked yes)
			(layer "B.Fab")
			(hide yes)
			(effects
				(font
					(size 1.016 1.016)
					(thickness 0.1524)
				)
				(justify mirror)
			)
		)
		(property "Device Type" "R402H16"
			(at -0.064008 -5.517896 0)
			(unlocked yes)
			(layer "B.Fab")
			(hide yes)
			(effects
				(font
					(size 1.016 1.016)
					(thickness 0.1524)
				)
				(justify mirror)
			)
		)
		(duplicate_pad_numbers_are_jumpers no)
		(fp_line
			(start -0.508 -0.9398)
			(end 0.508 -0.9398)
			(stroke
				(width 0.1524)
				(type default)
			)
			(layer "B.SilkS")
		)
		(fp_line
			(start 0.508 -0.9398)
			(end 0.508 0.9398)
			(stroke
				(width 0.1524)
				(type default)
			)
			(layer "B.SilkS")
		)
		(fp_rect
			(start 0.508 0.9398)
			(end -0.508 -0.9398)
			(stroke
				(width 0)
				(type default)
			)
			(fill no)
			(layer "B.CrtYd")
		)
		(fp_rect
			(start 0.508 0.9398)
			(end -0.508 -0.9398)
			(stroke
				(width 0)
				(type default)
			)
			(fill no)
			(layer "B.Fab")
		)
		(pad "1" smd custom
			(at 0 -0.4445 180)
			(size 0.1397 0.1397)
			(layers "B.Cu" "B.Mask" "B.Paste")
			(net "P1V8_C")
			(options
				(clearance outline)
				(anchor circle)
			)
			(primitives
				(gr_poly
					(pts
						(arc
							(start -0.1778 0.2794)
							(mid -0.249642 0.249642)
							(end -0.2794 0.1778)
						)
						(arc
							(start -0.2794 -0.1778)
							(mid -0.249642 -0.249642)
							(end -0.1778 -0.2794)
						)
						(arc
							(start 0.1778 -0.2794)
							(mid 0.249642 -0.249642)
							(end 0.2794 -0.1778)
						)
						(arc
							(start 0.2794 0.1778)
							(mid 0.249642 0.249642)
							(end 0.1778 0.2794)
						)
					)
					(width 0)
					(fill yes)
				)
			)
		)
		(pad "2" smd custom
			(at 0 0.4445 180)
			(size 0.1397 0.1397)
			(layers "B.Cu" "B.Mask" "B.Paste")
			(net "SIO_DIN_0")
			(options
				(clearance outline)
				(anchor circle)
			)
			(primitives
				(gr_poly
					(pts
						(arc
							(start -0.1778 0.2794)
							(mid -0.249642 0.249642)
							(end -0.2794 0.1778)
						)
						(arc
							(start -0.2794 -0.1778)
							(mid -0.249642 -0.249642)
							(end -0.1778 -0.2794)
						)
						(arc
							(start 0.1778 -0.2794)
							(mid 0.249642 -0.249642)
							(end 0.2794 -0.1778)
						)
						(arc
							(start 0.2794 0.1778)
							(mid 0.249642 0.249642)
							(end 0.1778 0.2794)
						)
					)
					(width 0)
					(fill yes)
				)
			)
		)
	)
	(footprint ""
		(layer "B.Cu")
		(at 109.3978 -44.2214 180)
		(property "Reference" "C71"
			(at 0 0 0)
			(layer "B.SilkS")
			(hide yes)
			(effects
				(font
					(size 1.27 1.27)
				)
				(justify mirror)
			)
		)
		(property "Value" "SCD01U16V1KX-GP"
			(at 2.8321 -1.7399 180)
			(unlocked yes)
			(layer "B.Fab")
			(hide yes)
			(effects
				(font
					(size 1.016 1.016)
					(thickness 0.1524)
				)
				(justify mirror)
			)
		)
		(property "Device Type" "C0201H13"
			(at 2.8321 -3.2639 180)
			(unlocked yes)
			(layer "B.Fab")
			(hide yes)
			(effects
				(font
					(size 1.016 1.016)
					(thickness 0.1524)
				)
				(justify mirror)
			)
		)
		(duplicate_pad_numbers_are_jumpers no)
		(fp_rect
			(start 0.2794 0.6477)
			(end -0.2794 -0.6477)
			(stroke
				(width 0)
				(type default)
			)
			(fill no)
			(layer "B.CrtYd")
		)
		(fp_rect
			(start 0.2794 0.6477)
			(end -0.2794 -0.6477)
			(stroke
				(width 0)
				(type default)
			)
			(fill no)
			(layer "B.Fab")
		)
		(pad "1" smd custom
			(at 0 -0.2794)
			(size 0.0762 0.0762)
			(layers "B.Cu" "B.Mask" "B.Paste")
			(net "PHY_DPB_TO_SCC_24_DP")
			(options
				(clearance outline)
				(anchor circle)
			)
			(primitives
				(gr_poly
					(pts
						(arc
							(start 0.1524 0.127)
							(mid 0.137521 0.162921)
							(end 0.1016 0.1778)
						)
						(arc
							(start -0.1016 0.1778)
							(mid -0.137521 0.162921)
							(end -0.1524 0.127)
						)
						(arc
							(start -0.1524 -0.127)
							(mid -0.137521 -0.162921)
							(end -0.1016 -0.1778)
						)
						(arc
							(start 0.1016 -0.1778)
							(mid 0.137521 -0.162921)
							(end 0.1524 -0.127)
						)
					)
					(width 0)
					(fill yes)
				)
			)
		)
		(pad "2" smd custom
			(at 0 0.2794)
			(size 0.0762 0.0762)
			(layers "B.Cu" "B.Mask" "B.Paste")
			(net "PHY_DPB_TO_SCC_C_24_DP")
			(options
				(clearance outline)
				(anchor circle)
			)
			(primitives
				(gr_poly
					(pts
						(arc
							(start 0.1524 0.127)
							(mid 0.137521 0.162921)
							(end 0.1016 0.1778)
						)
						(arc
							(start -0.1016 0.1778)
							(mid -0.137521 0.162921)
							(end -0.1524 0.127)
						)
						(arc
							(start -0.1524 -0.127)
							(mid -0.137521 -0.162921)
							(end -0.1016 -0.1778)
						)
						(arc
							(start 0.1016 -0.1778)
							(mid 0.137521 -0.162921)
							(end 0.1524 -0.127)
						)
					)
					(width 0)
					(fill yes)
				)
			)
		)
	)
	(footprint ""
		(layer "B.Cu")
		(at 126.873 -39.4716 180)
		(property "Reference" "C50"
			(at 0 0 0)
			(layer "B.SilkS")
			(hide yes)
			(effects
				(font
					(size 1.27 1.27)
				)
				(justify mirror)
			)
		)
		(property "Value" "SCD01U16V1KX-GP"
			(at 2.8321 -1.7399 180)
			(unlocked yes)
			(layer "B.Fab")
			(hide yes)
			(effects
				(font
					(size 1.016 1.016)
					(thickness 0.1524)
				)
				(justify mirror)
			)
		)
		(property "Device Type" "C0201H13"
			(at 2.8321 -3.2639 180)
			(unlocked yes)
			(layer "B.Fab")
			(hide yes)
			(effects
				(font
					(size 1.016 1.016)
					(thickness 0.1524)
				)
				(justify mirror)
			)
		)
		(duplicate_pad_numbers_are_jumpers no)
		(fp_rect
			(start 0.2794 0.6477)
			(end -0.2794 -0.6477)
			(stroke
				(width 0)
				(type default)
			)
			(fill no)
			(layer "B.CrtYd")
		)
		(fp_rect
			(start 0.2794 0.6477)
			(end -0.2794 -0.6477)
			(stroke
				(width 0)
				(type default)
			)
			(fill no)
			(layer "B.Fab")
		)
		(pad "1" smd custom
			(at 0 -0.2794)
			(size 0.0762 0.0762)
			(layers "B.Cu" "B.Mask" "B.Paste")
			(net "PHY_DPB_TO_SCC_39_DN")
			(options
				(clearance outline)
				(anchor circle)
			)
			(primitives
				(gr_poly
					(pts
						(arc
							(start 0.1524 0.127)
							(mid 0.137521 0.162921)
							(end 0.1016 0.1778)
						)
						(arc
							(start -0.1016 0.1778)
							(mid -0.137521 0.162921)
							(end -0.1524 0.127)
						)
						(arc
							(start -0.1524 -0.127)
							(mid -0.137521 -0.162921)
							(end -0.1016 -0.1778)
						)
						(arc
							(start 0.1016 -0.1778)
							(mid 0.137521 -0.162921)
							(end 0.1524 -0.127)
						)
					)
					(width 0)
					(fill yes)
				)
			)
		)
		(pad "2" smd custom
			(at 0 0.2794)
			(size 0.0762 0.0762)
			(layers "B.Cu" "B.Mask" "B.Paste")
			(net "PHY_DPB_TO_SCC_C_39_DN")
			(options
				(clearance outline)
				(anchor circle)
			)
			(primitives
				(gr_poly
					(pts
						(arc
							(start 0.1524 0.127)
							(mid 0.137521 0.162921)
							(end 0.1016 0.1778)
						)
						(arc
							(start -0.1016 0.1778)
							(mid -0.137521 0.162921)
							(end -0.1524 0.127)
						)
						(arc
							(start -0.1524 -0.127)
							(mid -0.137521 -0.162921)
							(end -0.1016 -0.1778)
						)
						(arc
							(start 0.1016 -0.1778)
							(mid 0.137521 -0.162921)
							(end 0.1524 -0.127)
						)
					)
					(width 0)
					(fill yes)
				)
			)
		)
	)
	(footprint ""
		(layer "B.Cu")
		(at 184.0484 -24.6634)
		(property "Reference" "TP145"
			(at 0 0 0)
			(layer "B.SilkS")
			(hide yes)
			(effects
				(font
					(size 1.27 1.27)
				)
				(justify mirror)
			)
		)
		(property "Value" "TPAD28-2-GP"
			(at 0.0127 -1.6637 0)
			(unlocked yes)
			(layer "B.Fab")
			(hide yes)
			(effects
				(font
					(size 1.016 1.016)
					(thickness 0.1524)
				)
				(justify mirror)
			)
		)
		(property "Device Type" "TPAD28"
			(at 0.0127 -3.1877 0)
			(unlocked yes)
			(layer "B.Fab")
			(hide yes)
			(effects
				(font
					(size 1.016 1.016)
					(thickness 0.1524)
				)
				(justify mirror)
			)
		)
		(duplicate_pad_numbers_are_jumpers no)
		(fp_poly
			(pts
				(arc
					(start 0.3556 0)
					(mid -0.3556 0)
					(end 0.3556 0)
				)
			)
			(stroke
				(width 0)
				(type default)
			)
			(fill no)
			(layer "B.CrtYd")
		)
		(fp_poly
			(pts
				(arc
					(start 0.6096 0)
					(mid -0.6096 0)
					(end 0.6096 0)
				)
			)
			(stroke
				(width 0)
				(type default)
			)
			(fill no)
			(layer "B.Fab")
		)
		(pad "1" smd circle
			(at 0 0 180)
			(size 0.7112 0.7112)
			(layers "B.Cu" "B.Mask" "B.Paste")
			(net "SPARE1")
		)
	)
	(footprint ""
		(layer "B.Cu")
		(at 113.453672 -75.47737 90)
		(property "Reference" "C141"
			(at 0 0 90)
			(layer "B.SilkS")
			(hide yes)
			(effects
				(font
					(size 1.27 1.27)
				)
				(justify mirror)
			)
		)
		(property "Value" "SCD1U6D3V1KX-GP"
			(at 2.8321 -1.7399 90)
			(unlocked yes)
			(layer "B.Fab")
			(hide yes)
			(effects
				(font
					(size 1.016 1.016)
					(thickness 0.1524)
				)
				(justify mirror)
			)
		)
		(property "Device Type" "C0201H13"
			(at 2.8321 -3.2639 90)
			(unlocked yes)
			(layer "B.Fab")
			(hide yes)
			(effects
				(font
					(size 1.016 1.016)
					(thickness 0.1524)
				)
				(justify mirror)
			)
		)
		(duplicate_pad_numbers_are_jumpers no)
		(fp_rect
			(start 0.2794 0.6477)
			(end -0.2794 -0.6477)
			(stroke
				(width 0)
				(type default)
			)
			(fill no)
			(layer "B.CrtYd")
		)
		(fp_rect
			(start 0.2794 0.6477)
			(end -0.2794 -0.6477)
			(stroke
				(width 0)
				(type default)
			)
			(fill no)
			(layer "B.Fab")
		)
		(pad "1" smd custom
			(at 0 -0.2794 270)
			(size 0.0762 0.0762)
			(layers "B.Cu" "B.Mask" "B.Paste")
			(net "P1V8_E")
			(options
				(clearance outline)
				(anchor circle)
			)
			(primitives
				(gr_poly
					(pts
						(arc
							(start 0.1524 0.127)
							(mid 0.137521 0.162921)
							(end 0.1016 0.1778)
						)
						(arc
							(start -0.1016 0.1778)
							(mid -0.137521 0.162921)
							(end -0.1524 0.127)
						)
						(arc
							(start -0.1524 -0.127)
							(mid -0.137521 -0.162921)
							(end -0.1016 -0.1778)
						)
						(arc
							(start 0.1016 -0.1778)
							(mid 0.137521 -0.162921)
							(end 0.1524 -0.127)
						)
					)
					(width 0)
					(fill yes)
				)
			)
		)
		(pad "2" smd custom
			(at 0 0.2794 270)
			(size 0.0762 0.0762)
			(layers "B.Cu" "B.Mask" "B.Paste")
			(net "GND")
			(options
				(clearance outline)
				(anchor circle)
			)
			(primitives
				(gr_poly
					(pts
						(arc
							(start 0.1524 0.127)
							(mid 0.137521 0.162921)
							(end 0.1016 0.1778)
						)
						(arc
							(start -0.1016 0.1778)
							(mid -0.137521 0.162921)
							(end -0.1524 0.127)
						)
						(arc
							(start -0.1524 -0.127)
							(mid -0.137521 -0.162921)
							(end -0.1016 -0.1778)
						)
						(arc
							(start 0.1016 -0.1778)
							(mid 0.137521 -0.162921)
							(end 0.1524 -0.127)
						)
					)
					(width 0)
					(fill yes)
				)
			)
		)
	)
	(footprint ""
		(layer "B.Cu")
		(at 186.3344 -30.607 90)
		(property "Reference" "TP80"
			(at 0 0 90)
			(layer "B.SilkS")
			(hide yes)
			(effects
				(font
					(size 1.27 1.27)
				)
				(justify mirror)
			)
		)
		(property "Value" "TPAD28-2-GP"
			(at 0.0127 -1.6637 90)
			(unlocked yes)
			(layer "B.Fab")
			(hide yes)
			(effects
				(font
					(size 1.016 1.016)
					(thickness 0.1524)
				)
				(justify mirror)
			)
		)
		(property "Device Type" "TPAD28"
			(at 0.0127 -3.1877 90)
			(unlocked yes)
			(layer "B.Fab")
			(hide yes)
			(effects
				(font
					(size 1.016 1.016)
					(thickness 0.1524)
				)
				(justify mirror)
			)
		)
		(duplicate_pad_numbers_are_jumpers no)
		(fp_poly
			(pts
				(arc
					(start 0 0.3556)
					(mid 0 -0.3556)
					(end 0 0.3556)
				)
			)
			(stroke
				(width 0)
				(type default)
			)
			(fill no)
			(layer "B.CrtYd")
		)
		(fp_poly
			(pts
				(arc
					(start 0 0.6096)
					(mid 0 -0.6096)
					(end 0 0.6096)
				)
			)
			(stroke
				(width 0)
				(type default)
			)
			(fill no)
			(layer "B.Fab")
		)
		(pad "1" smd circle
			(at 0 0 270)
			(size 0.7112 0.7112)
			(layers "B.Cu" "B.Mask" "B.Paste")
			(net "IOC_GPIO_26")
		)
	)
	(footprint ""
		(layer "B.Cu")
		(at 107.8738 -44.2214 180)
		(property "Reference" "C72"
			(at 0 0 0)
			(layer "B.SilkS")
			(hide yes)
			(effects
				(font
					(size 1.27 1.27)
				)
				(justify mirror)
			)
		)
		(property "Value" "SCD01U16V1KX-GP"
			(at 2.8321 -1.7399 180)
			(unlocked yes)
			(layer "B.Fab")
			(hide yes)
			(effects
				(font
					(size 1.016 1.016)
					(thickness 0.1524)
				)
				(justify mirror)
			)
		)
		(property "Device Type" "C0201H13"
			(at 2.8321 -3.2639 180)
			(unlocked yes)
			(layer "B.Fab")
			(hide yes)
			(effects
				(font
					(size 1.016 1.016)
					(thickness 0.1524)
				)
				(justify mirror)
			)
		)
		(duplicate_pad_numbers_are_jumpers no)
		(fp_rect
			(start 0.2794 0.6477)
			(end -0.2794 -0.6477)
			(stroke
				(width 0)
				(type default)
			)
			(fill no)
			(layer "B.CrtYd")
		)
		(fp_rect
			(start 0.2794 0.6477)
			(end -0.2794 -0.6477)
			(stroke
				(width 0)
				(type default)
			)
			(fill no)
			(layer "B.Fab")
		)
		(pad "1" smd custom
			(at 0 -0.2794)
			(size 0.0762 0.0762)
			(layers "B.Cu" "B.Mask" "B.Paste")
			(net "PHY_DPB_TO_SCC_23_DP")
			(options
				(clearance outline)
				(anchor circle)
			)
			(primitives
				(gr_poly
					(pts
						(arc
							(start 0.1524 0.127)
							(mid 0.137521 0.162921)
							(end 0.1016 0.1778)
						)
						(arc
							(start -0.1016 0.1778)
							(mid -0.137521 0.162921)
							(end -0.1524 0.127)
						)
						(arc
							(start -0.1524 -0.127)
							(mid -0.137521 -0.162921)
							(end -0.1016 -0.1778)
						)
						(arc
							(start 0.1016 -0.1778)
							(mid 0.137521 -0.162921)
							(end 0.1524 -0.127)
						)
					)
					(width 0)
					(fill yes)
				)
			)
		)
		(pad "2" smd custom
			(at 0 0.2794)
			(size 0.0762 0.0762)
			(layers "B.Cu" "B.Mask" "B.Paste")
			(net "PHY_DPB_TO_SCC_C_23_DP")
			(options
				(clearance outline)
				(anchor circle)
			)
			(primitives
				(gr_poly
					(pts
						(arc
							(start 0.1524 0.127)
							(mid 0.137521 0.162921)
							(end 0.1016 0.1778)
						)
						(arc
							(start -0.1016 0.1778)
							(mid -0.137521 0.162921)
							(end -0.1524 0.127)
						)
						(arc
							(start -0.1524 -0.127)
							(mid -0.137521 -0.162921)
							(end -0.1016 -0.1778)
						)
						(arc
							(start 0.1016 -0.1778)
							(mid 0.137521 -0.162921)
							(end 0.1524 -0.127)
						)
					)
					(width 0)
					(fill yes)
				)
			)
		)
	)
	(footprint ""
		(layer "B.Cu")
		(at 86.4616 -72.5932 -90)
		(property "Reference" "C116"
			(at 0 0 90)
			(layer "B.SilkS")
			(hide yes)
			(effects
				(font
					(size 1.27 1.27)
				)
				(justify mirror)
			)
		)
		(property "Value" "SCD1U16V2KX-3GP"
			(at -1.1811 -2.7051 270)
			(unlocked yes)
			(layer "B.Fab")
			(hide yes)
			(effects
				(font
					(size 1.016 1.016)
					(thickness 0.1524)
				)
				(justify mirror)
			)
		)
		(property "Device Type" "C402H22"
			(at -1.1811 -4.2291 270)
			(unlocked yes)
			(layer "B.Fab")
			(hide yes)
			(effects
				(font
					(size 1.016 1.016)
					(thickness 0.1524)
				)
				(justify mirror)
			)
		)
		(duplicate_pad_numbers_are_jumpers no)
		(fp_rect
			(start 0.4318 0.9525)
			(end -0.4318 -0.9525)
			(stroke
				(width 0)
				(type default)
			)
			(fill no)
			(layer "B.CrtYd")
		)
		(fp_rect
			(start 0.4318 0.9525)
			(end -0.4318 -0.9525)
			(stroke
				(width 0)
				(type default)
			)
			(fill no)
			(layer "B.Fab")
		)
		(pad "1" smd custom
			(at 0 -0.4445 90)
			(size 0.1524 0.1524)
			(layers "B.Cu" "B.Mask" "B.Paste")
			(net "P1V8_E")
			(options
				(clearance outline)
				(anchor circle)
			)
			(primitives
				(gr_poly
					(pts
						(arc
							(start 0.3048 0.2032)
							(mid 0.275042 0.275042)
							(end 0.2032 0.3048)
						)
						(arc
							(start -0.2032 0.3048)
							(mid -0.275042 0.275042)
							(end -0.3048 0.2032)
						)
						(arc
							(start -0.3048 -0.2032)
							(mid -0.275042 -0.275042)
							(end -0.2032 -0.3048)
						)
						(arc
							(start 0.2032 -0.3048)
							(mid 0.275042 -0.275042)
							(end 0.3048 -0.2032)
						)
					)
					(width 0)
					(fill yes)
				)
			)
		)
		(pad "2" smd custom
			(at 0 0.4445 90)
			(size 0.1524 0.1524)
			(layers "B.Cu" "B.Mask" "B.Paste")
			(net "GND")
			(options
				(clearance outline)
				(anchor circle)
			)
			(primitives
				(gr_poly
					(pts
						(arc
							(start 0.3048 0.2032)
							(mid 0.275042 0.275042)
							(end 0.2032 0.3048)
						)
						(arc
							(start -0.2032 0.3048)
							(mid -0.275042 0.275042)
							(end -0.3048 0.2032)
						)
						(arc
							(start -0.3048 -0.2032)
							(mid -0.275042 -0.275042)
							(end -0.2032 -0.3048)
						)
						(arc
							(start 0.2032 -0.3048)
							(mid 0.275042 -0.275042)
							(end 0.3048 -0.2032)
						)
					)
					(width 0)
					(fill yes)
				)
			)
		)
	)
	(footprint ""
		(layer "B.Cu")
		(at 70.485 -58.674 90)
		(property "Reference" "L10"
			(at 0 0 90)
			(layer "B.SilkS")
			(hide yes)
			(effects
				(font
					(size 1.27 1.27)
				)
				(justify mirror)
			)
		)
		(property "Value" "MPZ2012S300AT-GP"
			(at 0 -4.2418 90)
			(unlocked yes)
			(layer "B.Fab")
			(hide yes)
			(effects
				(font
					(size 1.016 1.016)
					(thickness 0.1524)
				)
				(justify mirror)
			)
		)
		(property "Device Type" "L805H42"
			(at 0 -5.7912 90)
			(unlocked yes)
			(layer "B.Fab")
			(hide yes)
			(effects
				(font
					(size 1.016 1.016)
					(thickness 0.1524)
				)
				(justify mirror)
			)
		)
		(duplicate_pad_numbers_are_jumpers no)
		(fp_line
			(start 0.889 -1.7018)
			(end -0.889 -1.7018)
			(stroke
				(width 0.1524)
				(type default)
			)
			(layer "B.SilkS")
		)
		(fp_line
			(start -0.889 -1.7018)
			(end -0.889 1.7018)
			(stroke
				(width 0.1524)
				(type default)
			)
			(layer "B.SilkS")
		)
		(fp_line
			(start 0.889 1.7018)
			(end 0.889 -1.7018)
			(stroke
				(width 0.1524)
				(type default)
			)
			(layer "B.SilkS")
		)
		(fp_line
			(start -0.889 1.7018)
			(end 0.889 1.7018)
			(stroke
				(width 0.1524)
				(type default)
			)
			(layer "B.SilkS")
		)
		(fp_rect
			(start 0.9652 1.778)
			(end -0.9652 -1.778)
			(stroke
				(width 0)
				(type default)
			)
			(fill no)
			(layer "B.CrtYd")
		)
		(fp_rect
			(start 0.9652 1.778)
			(end -0.9652 -1.778)
			(stroke
				(width 0)
				(type default)
			)
			(fill no)
			(layer "B.Fab")
		)
		(pad "1" smd rect
			(at 0 -0.9652 270)
			(size 1.397 1.143)
			(layers "B.Cu" "B.Mask" "B.Paste")
			(net "P0V9")
		)
		(pad "2" smd rect
			(at 0 0.9652 270)
			(size 1.397 1.143)
			(layers "B.Cu" "B.Mask" "B.Paste")
			(net "GB_VDDA")
		)
	)
	(footprint ""
		(layer "B.Cu")
		(at 164.723318 -30.381956 -90)
		(property "Reference" "C399"
			(at 0 0 90)
			(layer "B.SilkS")
			(hide yes)
			(effects
				(font
					(size 1.27 1.27)
				)
				(justify mirror)
			)
		)
		(property "Value" "SCD1U16V2KX-3GP"
			(at -1.1811 -2.7051 270)
			(unlocked yes)
			(layer "B.Fab")
			(hide yes)
			(effects
				(font
					(size 1.016 1.016)
					(thickness 0.1524)
				)
				(justify mirror)
			)
		)
		(property "Device Type" "C402H22"
			(at -1.1811 -4.2291 270)
			(unlocked yes)
			(layer "B.Fab")
			(hide yes)
			(effects
				(font
					(size 1.016 1.016)
					(thickness 0.1524)
				)
				(justify mirror)
			)
		)
		(duplicate_pad_numbers_are_jumpers no)
		(fp_rect
			(start 0.4318 0.9525)
			(end -0.4318 -0.9525)
			(stroke
				(width 0)
				(type default)
			)
			(fill no)
			(layer "B.CrtYd")
		)
		(fp_rect
			(start 0.4318 0.9525)
			(end -0.4318 -0.9525)
			(stroke
				(width 0)
				(type default)
			)
			(fill no)
			(layer "B.Fab")
		)
		(pad "1" smd custom
			(at 0 -0.4445 90)
			(size 0.1524 0.1524)
			(layers "B.Cu" "B.Mask" "B.Paste")
			(net "SAS0_AVDD")
			(options
				(clearance outline)
				(anchor circle)
			)
			(primitives
				(gr_poly
					(pts
						(arc
							(start 0.3048 0.2032)
							(mid 0.275042 0.275042)
							(end 0.2032 0.3048)
						)
						(arc
							(start -0.2032 0.3048)
							(mid -0.275042 0.275042)
							(end -0.3048 0.2032)
						)
						(arc
							(start -0.3048 -0.2032)
							(mid -0.275042 -0.275042)
							(end -0.2032 -0.3048)
						)
						(arc
							(start 0.2032 -0.3048)
							(mid 0.275042 -0.275042)
							(end 0.3048 -0.2032)
						)
					)
					(width 0)
					(fill yes)
				)
			)
		)
		(pad "2" smd custom
			(at 0 0.4445 90)
			(size 0.1524 0.1524)
			(layers "B.Cu" "B.Mask" "B.Paste")
			(net "GND")
			(options
				(clearance outline)
				(anchor circle)
			)
			(primitives
				(gr_poly
					(pts
						(arc
							(start 0.3048 0.2032)
							(mid 0.275042 0.275042)
							(end 0.2032 0.3048)
						)
						(arc
							(start -0.2032 0.3048)
							(mid -0.275042 0.275042)
							(end -0.3048 0.2032)
						)
						(arc
							(start -0.3048 -0.2032)
							(mid -0.275042 -0.275042)
							(end -0.2032 -0.3048)
						)
						(arc
							(start 0.2032 -0.3048)
							(mid 0.275042 -0.275042)
							(end 0.3048 -0.2032)
						)
					)
					(width 0)
					(fill yes)
				)
			)
		)
	)
	(footprint ""
		(layer "B.Cu")
		(at 71.5518 -14.558772 180)
		(property "Reference" "C98"
			(at 0 0 0)
			(layer "B.SilkS")
			(hide yes)
			(effects
				(font
					(size 1.27 1.27)
				)
				(justify mirror)
			)
		)
		(property "Value" "SCD1U16V2KX-3GP"
			(at -1.1811 -2.7051 180)
			(unlocked yes)
			(layer "B.Fab")
			(hide yes)
			(effects
				(font
					(size 1.016 1.016)
					(thickness 0.1524)
				)
				(justify mirror)
			)
		)
		(property "Device Type" "C402H22"
			(at -1.1811 -4.2291 180)
			(unlocked yes)
			(layer "B.Fab")
			(hide yes)
			(effects
				(font
					(size 1.016 1.016)
					(thickness 0.1524)
				)
				(justify mirror)
			)
		)
		(duplicate_pad_numbers_are_jumpers no)
		(fp_rect
			(start 0.4318 0.9525)
			(end -0.4318 -0.9525)
			(stroke
				(width 0)
				(type default)
			)
			(fill no)
			(layer "B.CrtYd")
		)
		(fp_rect
			(start 0.4318 0.9525)
			(end -0.4318 -0.9525)
			(stroke
				(width 0)
				(type default)
			)
			(fill no)
			(layer "B.Fab")
		)
		(pad "1" smd custom
			(at 0 -0.4445)
			(size 0.1524 0.1524)
			(layers "B.Cu" "B.Mask" "B.Paste")
			(net "P3V3")
			(options
				(clearance outline)
				(anchor circle)
			)
			(primitives
				(gr_poly
					(pts
						(arc
							(start 0.3048 0.2032)
							(mid 0.275042 0.275042)
							(end 0.2032 0.3048)
						)
						(arc
							(start -0.2032 0.3048)
							(mid -0.275042 0.275042)
							(end -0.3048 0.2032)
						)
						(arc
							(start -0.3048 -0.2032)
							(mid -0.275042 -0.275042)
							(end -0.2032 -0.3048)
						)
						(arc
							(start 0.2032 -0.3048)
							(mid 0.275042 -0.275042)
							(end 0.3048 -0.2032)
						)
					)
					(width 0)
					(fill yes)
				)
			)
		)
		(pad "2" smd custom
			(at 0 0.4445)
			(size 0.1524 0.1524)
			(layers "B.Cu" "B.Mask" "B.Paste")
			(net "GND")
			(options
				(clearance outline)
				(anchor circle)
			)
			(primitives
				(gr_poly
					(pts
						(arc
							(start 0.3048 0.2032)
							(mid 0.275042 0.275042)
							(end 0.2032 0.3048)
						)
						(arc
							(start -0.2032 0.3048)
							(mid -0.275042 0.275042)
							(end -0.3048 0.2032)
						)
						(arc
							(start -0.3048 -0.2032)
							(mid -0.275042 -0.275042)
							(end -0.2032 -0.3048)
						)
						(arc
							(start 0.2032 -0.3048)
							(mid 0.275042 -0.275042)
							(end 0.3048 -0.2032)
						)
					)
					(width 0)
					(fill yes)
				)
			)
		)
	)
	(footprint ""
		(layer "B.Cu")
		(at 117.6782 -71.9074)
		(property "Reference" "C140"
			(at 0 0 0)
			(layer "B.SilkS")
			(hide yes)
			(effects
				(font
					(size 1.27 1.27)
				)
				(justify mirror)
			)
		)
		(property "Value" "SCD1U6D3V1KX-GP"
			(at 2.8321 -1.7399 0)
			(unlocked yes)
			(layer "B.Fab")
			(hide yes)
			(effects
				(font
					(size 1.016 1.016)
					(thickness 0.1524)
				)
				(justify mirror)
			)
		)
		(property "Device Type" "C0201H13"
			(at 2.8321 -3.2639 0)
			(unlocked yes)
			(layer "B.Fab")
			(hide yes)
			(effects
				(font
					(size 1.016 1.016)
					(thickness 0.1524)
				)
				(justify mirror)
			)
		)
		(duplicate_pad_numbers_are_jumpers no)
		(fp_rect
			(start 0.2794 0.6477)
			(end -0.2794 -0.6477)
			(stroke
				(width 0)
				(type default)
			)
			(fill no)
			(layer "B.CrtYd")
		)
		(fp_rect
			(start 0.2794 0.6477)
			(end -0.2794 -0.6477)
			(stroke
				(width 0)
				(type default)
			)
			(fill no)
			(layer "B.Fab")
		)
		(pad "1" smd custom
			(at 0 -0.2794 180)
			(size 0.0762 0.0762)
			(layers "B.Cu" "B.Mask" "B.Paste")
			(net "P1V8_E")
			(options
				(clearance outline)
				(anchor circle)
			)
			(primitives
				(gr_poly
					(pts
						(arc
							(start 0.1524 0.127)
							(mid 0.137521 0.162921)
							(end 0.1016 0.1778)
						)
						(arc
							(start -0.1016 0.1778)
							(mid -0.137521 0.162921)
							(end -0.1524 0.127)
						)
						(arc
							(start -0.1524 -0.127)
							(mid -0.137521 -0.162921)
							(end -0.1016 -0.1778)
						)
						(arc
							(start 0.1016 -0.1778)
							(mid 0.137521 -0.162921)
							(end 0.1524 -0.127)
						)
					)
					(width 0)
					(fill yes)
				)
			)
		)
		(pad "2" smd custom
			(at 0 0.2794 180)
			(size 0.0762 0.0762)
			(layers "B.Cu" "B.Mask" "B.Paste")
			(net "GND")
			(options
				(clearance outline)
				(anchor circle)
			)
			(primitives
				(gr_poly
					(pts
						(arc
							(start 0.1524 0.127)
							(mid 0.137521 0.162921)
							(end 0.1016 0.1778)
						)
						(arc
							(start -0.1016 0.1778)
							(mid -0.137521 0.162921)
							(end -0.1524 0.127)
						)
						(arc
							(start -0.1524 -0.127)
							(mid -0.137521 -0.162921)
							(end -0.1016 -0.1778)
						)
						(arc
							(start 0.1016 -0.1778)
							(mid 0.137521 -0.162921)
							(end 0.1524 -0.127)
						)
					)
					(width 0)
					(fill yes)
				)
			)
		)
	)
	(footprint ""
		(layer "B.Cu")
		(at 147.701 -117.348)
		(property "Reference" "R381"
			(at 0 0 0)
			(layer "B.SilkS")
			(hide yes)
			(effects
				(font
					(size 1.27 1.27)
				)
				(justify mirror)
			)
		)
		(property "Value" "2D2R3-1-U-GP"
			(at 0.0254 -2.5146 0)
			(unlocked yes)
			(layer "B.Fab")
			(hide yes)
			(effects
				(font
					(size 1.016 1.016)
					(thickness 0.1524)
				)
				(justify mirror)
			)
		)
		(property "Device Type" "R603H22"
			(at 0.0254 -4.0386 0)
			(unlocked yes)
			(layer "B.Fab")
			(hide yes)
			(effects
				(font
					(size 1.016 1.016)
					(thickness 0.1524)
				)
				(justify mirror)
			)
		)
		(duplicate_pad_numbers_are_jumpers no)
		(fp_line
			(start -0.2032 0)
			(end -0.4826 0)
			(stroke
				(width 0.2032)
				(type default)
			)
			(layer "B.SilkS")
		)
		(fp_line
			(start 0.4826 0)
			(end 0.2032 0)
			(stroke
				(width 0.2032)
				(type default)
			)
			(layer "B.SilkS")
		)
		(fp_rect
			(start 0.5842 1.3335)
			(end -0.5842 -1.3335)
			(stroke
				(width 0)
				(type default)
			)
			(fill no)
			(layer "B.CrtYd")
		)
		(fp_rect
			(start 0.5842 1.3335)
			(end -0.5842 -1.3335)
			(stroke
				(width 0)
				(type default)
			)
			(fill no)
			(layer "B.Fab")
		)
		(pad "1" smd custom
			(at 0 -0.762 180)
			(size 0.2159 0.2159)
			(layers "B.Cu" "B.Mask" "B.Paste")
			(net "P1V5_E_VBST")
			(options
				(clearance outline)
				(anchor circle)
			)
			(primitives
				(gr_poly
					(pts
						(arc
							(start -0.3302 0.4318)
							(mid -0.402042 0.402042)
							(end -0.4318 0.3302)
						)
						(arc
							(start -0.4318 -0.3302)
							(mid -0.402042 -0.402042)
							(end -0.3302 -0.4318)
						)
						(arc
							(start 0.3302 -0.4318)
							(mid 0.402042 -0.402042)
							(end 0.4318 -0.3302)
						)
						(arc
							(start 0.4318 0.3302)
							(mid 0.402042 0.402042)
							(end 0.3302 0.4318)
						)
					)
					(width 0)
					(fill yes)
				)
			)
		)
		(pad "2" smd custom
			(at 0 0.762 180)
			(size 0.2159 0.2159)
			(layers "B.Cu" "B.Mask" "B.Paste")
			(net "P1V5_E_RC")
			(options
				(clearance outline)
				(anchor circle)
			)
			(primitives
				(gr_poly
					(pts
						(arc
							(start -0.3302 0.4318)
							(mid -0.402042 0.402042)
							(end -0.4318 0.3302)
						)
						(arc
							(start -0.4318 -0.3302)
							(mid -0.402042 -0.402042)
							(end -0.3302 -0.4318)
						)
						(arc
							(start 0.3302 -0.4318)
							(mid 0.402042 -0.402042)
							(end 0.4318 -0.3302)
						)
						(arc
							(start 0.4318 0.3302)
							(mid 0.402042 0.402042)
							(end 0.3302 0.4318)
						)
					)
					(width 0)
					(fill yes)
				)
			)
		)
	)
	(footprint ""
		(layer "B.Cu")
		(at 186.309 -37.084 90)
		(property "Reference" "TP100"
			(at 0 0 90)
			(layer "B.SilkS")
			(hide yes)
			(effects
				(font
					(size 1.27 1.27)
				)
				(justify mirror)
			)
		)
		(property "Value" "TPAD28-2-GP"
			(at 0.0127 -1.6637 90)
			(unlocked yes)
			(layer "B.Fab")
			(hide yes)
			(effects
				(font
					(size 1.016 1.016)
					(thickness 0.1524)
				)
				(justify mirror)
			)
		)
		(property "Device Type" "TPAD28"
			(at 0.0127 -3.1877 90)
			(unlocked yes)
			(layer "B.Fab")
			(hide yes)
			(effects
				(font
					(size 1.016 1.016)
					(thickness 0.1524)
				)
				(justify mirror)
			)
		)
		(duplicate_pad_numbers_are_jumpers no)
		(fp_poly
			(pts
				(arc
					(start 0 0.3556)
					(mid 0 -0.3556)
					(end 0 0.3556)
				)
			)
			(stroke
				(width 0)
				(type default)
			)
			(fill no)
			(layer "B.CrtYd")
		)
		(fp_poly
			(pts
				(arc
					(start 0 0.6096)
					(mid 0 -0.6096)
					(end 0 0.6096)
				)
			)
			(stroke
				(width 0)
				(type default)
			)
			(fill no)
			(layer "B.Fab")
		)
		(pad "1" smd circle
			(at 0 0 270)
			(size 0.7112 0.7112)
			(layers "B.Cu" "B.Mask" "B.Paste")
			(net "IOC_GPIO_38")
		)
	)
	(footprint ""
		(layer "B.Cu")
		(at 160.528 -52.07)
		(property "Reference" "R200"
			(at 0 0 0)
			(layer "B.SilkS")
			(hide yes)
			(effects
				(font
					(size 1.27 1.27)
				)
				(justify mirror)
			)
		)
		(property "Value" "2K2R2F-GP"
			(at -0.064008 -3.993896 0)
			(unlocked yes)
			(layer "B.Fab")
			(hide yes)
			(effects
				(font
					(size 1.016 1.016)
					(thickness 0.1524)
				)
				(justify mirror)
			)
		)
		(property "Device Type" "R402H16"
			(at -0.064008 -5.517896 0)
			(unlocked yes)
			(layer "B.Fab")
			(hide yes)
			(effects
				(font
					(size 1.016 1.016)
					(thickness 0.1524)
				)
				(justify mirror)
			)
		)
		(duplicate_pad_numbers_are_jumpers no)
		(fp_line
			(start -0.508 -0.9398)
			(end 0.508 -0.9398)
			(stroke
				(width 0.1524)
				(type default)
			)
			(layer "B.SilkS")
		)
		(fp_line
			(start 0.508 -0.9398)
			(end 0.508 0.9398)
			(stroke
				(width 0.1524)
				(type default)
			)
			(layer "B.SilkS")
		)
		(fp_rect
			(start 0.508 0.9398)
			(end -0.508 -0.9398)
			(stroke
				(width 0)
				(type default)
			)
			(fill no)
			(layer "B.CrtYd")
		)
		(fp_rect
			(start 0.508 0.9398)
			(end -0.508 -0.9398)
			(stroke
				(width 0)
				(type default)
			)
			(fill no)
			(layer "B.Fab")
		)
		(pad "1" smd custom
			(at 0 -0.4445 180)
			(size 0.1397 0.1397)
			(layers "B.Cu" "B.Mask" "B.Paste")
			(net "P1V8_C")
			(options
				(clearance outline)
				(anchor circle)
			)
			(primitives
				(gr_poly
					(pts
						(arc
							(start -0.1778 0.2794)
							(mid -0.249642 0.249642)
							(end -0.2794 0.1778)
						)
						(arc
							(start -0.2794 -0.1778)
							(mid -0.249642 -0.249642)
							(end -0.1778 -0.2794)
						)
						(arc
							(start 0.1778 -0.2794)
							(mid 0.249642 -0.249642)
							(end 0.2794 -0.1778)
						)
						(arc
							(start 0.2794 0.1778)
							(mid 0.249642 0.249642)
							(end 0.1778 0.2794)
						)
					)
					(width 0)
					(fill yes)
				)
			)
		)
		(pad "2" smd custom
			(at 0 0.4445 180)
			(size 0.1397 0.1397)
			(layers "B.Cu" "B.Mask" "B.Paste")
			(net "SIO_CLK_1")
			(options
				(clearance outline)
				(anchor circle)
			)
			(primitives
				(gr_poly
					(pts
						(arc
							(start -0.1778 0.2794)
							(mid -0.249642 0.249642)
							(end -0.2794 0.1778)
						)
						(arc
							(start -0.2794 -0.1778)
							(mid -0.249642 -0.249642)
							(end -0.1778 -0.2794)
						)
						(arc
							(start 0.1778 -0.2794)
							(mid 0.249642 -0.249642)
							(end 0.2794 -0.1778)
						)
						(arc
							(start 0.2794 0.1778)
							(mid 0.249642 0.249642)
							(end 0.1778 0.2794)
						)
					)
					(width 0)
					(fill yes)
				)
			)
		)
	)
	(footprint ""
		(layer "B.Cu")
		(at 182.245 -34.7853)
		(property "Reference" "R257"
			(at 0 0 0)
			(layer "B.SilkS")
			(hide yes)
			(effects
				(font
					(size 1.27 1.27)
				)
				(justify mirror)
			)
		)
		(property "Value" "10KR2F-2-GP"
			(at -0.064008 -3.993896 0)
			(unlocked yes)
			(layer "B.Fab")
			(hide yes)
			(effects
				(font
					(size 1.016 1.016)
					(thickness 0.1524)
				)
				(justify mirror)
			)
		)
		(property "Device Type" "R402H16"
			(at -0.064008 -5.517896 0)
			(unlocked yes)
			(layer "B.Fab")
			(hide yes)
			(effects
				(font
					(size 1.016 1.016)
					(thickness 0.1524)
				)
				(justify mirror)
			)
		)
		(duplicate_pad_numbers_are_jumpers no)
		(fp_line
			(start -0.508 -0.9398)
			(end 0.508 -0.9398)
			(stroke
				(width 0.1524)
				(type default)
			)
			(layer "B.SilkS")
		)
		(fp_line
			(start 0.508 -0.9398)
			(end 0.508 0.9398)
			(stroke
				(width 0.1524)
				(type default)
			)
			(layer "B.SilkS")
		)
		(fp_rect
			(start 0.508 0.9398)
			(end -0.508 -0.9398)
			(stroke
				(width 0)
				(type default)
			)
			(fill no)
			(layer "B.CrtYd")
		)
		(fp_rect
			(start 0.508 0.9398)
			(end -0.508 -0.9398)
			(stroke
				(width 0)
				(type default)
			)
			(fill no)
			(layer "B.Fab")
		)
		(pad "1" smd custom
			(at 0 -0.4445 180)
			(size 0.1397 0.1397)
			(layers "B.Cu" "B.Mask" "B.Paste")
			(net "P1V8_C")
			(options
				(clearance outline)
				(anchor circle)
			)
			(primitives
				(gr_poly
					(pts
						(arc
							(start -0.1778 0.2794)
							(mid -0.249642 0.249642)
							(end -0.2794 0.1778)
						)
						(arc
							(start -0.2794 -0.1778)
							(mid -0.249642 -0.249642)
							(end -0.1778 -0.2794)
						)
						(arc
							(start 0.1778 -0.2794)
							(mid 0.249642 -0.249642)
							(end 0.2794 -0.1778)
						)
						(arc
							(start 0.2794 0.1778)
							(mid 0.249642 0.249642)
							(end 0.1778 0.2794)
						)
					)
					(width 0)
					(fill yes)
				)
			)
		)
		(pad "2" smd custom
			(at 0 0.4445 180)
			(size 0.1397 0.1397)
			(layers "B.Cu" "B.Mask" "B.Paste")
			(net "SYS_RST_N_1")
			(options
				(clearance outline)
				(anchor circle)
			)
			(primitives
				(gr_poly
					(pts
						(arc
							(start -0.1778 0.2794)
							(mid -0.249642 0.249642)
							(end -0.2794 0.1778)
						)
						(arc
							(start -0.2794 -0.1778)
							(mid -0.249642 -0.249642)
							(end -0.1778 -0.2794)
						)
						(arc
							(start 0.1778 -0.2794)
							(mid 0.249642 -0.249642)
							(end 0.2794 -0.1778)
						)
						(arc
							(start 0.2794 0.1778)
							(mid 0.249642 0.249642)
							(end 0.1778 0.2794)
						)
					)
					(width 0)
					(fill yes)
				)
			)
		)
	)
	(footprint ""
		(layer "B.Cu")
		(at 182.245 -31.75 -90)
		(property "Reference" "C468"
			(at 0 0 90)
			(layer "B.SilkS")
			(hide yes)
			(effects
				(font
					(size 1.27 1.27)
				)
				(justify mirror)
			)
		)
		(property "Value" "SCD1U6D3V1KX-GP"
			(at 2.8321 -1.7399 270)
			(unlocked yes)
			(layer "B.Fab")
			(hide yes)
			(effects
				(font
					(size 1.016 1.016)
					(thickness 0.1524)
				)
				(justify mirror)
			)
		)
		(property "Device Type" "C0201H13"
			(at 2.8321 -3.2639 270)
			(unlocked yes)
			(layer "B.Fab")
			(hide yes)
			(effects
				(font
					(size 1.016 1.016)
					(thickness 0.1524)
				)
				(justify mirror)
			)
		)
		(duplicate_pad_numbers_are_jumpers no)
		(fp_rect
			(start 0.2794 0.6477)
			(end -0.2794 -0.6477)
			(stroke
				(width 0)
				(type default)
			)
			(fill no)
			(layer "B.CrtYd")
		)
		(fp_rect
			(start 0.2794 0.6477)
			(end -0.2794 -0.6477)
			(stroke
				(width 0)
				(type default)
			)
			(fill no)
			(layer "B.Fab")
		)
		(pad "1" smd custom
			(at 0 -0.2794 90)
			(size 0.0762 0.0762)
			(layers "B.Cu" "B.Mask" "B.Paste")
			(net "P1V8_C")
			(options
				(clearance outline)
				(anchor circle)
			)
			(primitives
				(gr_poly
					(pts
						(arc
							(start 0.1524 0.127)
							(mid 0.137521 0.162921)
							(end 0.1016 0.1778)
						)
						(arc
							(start -0.1016 0.1778)
							(mid -0.137521 0.162921)
							(end -0.1524 0.127)
						)
						(arc
							(start -0.1524 -0.127)
							(mid -0.137521 -0.162921)
							(end -0.1016 -0.1778)
						)
						(arc
							(start 0.1016 -0.1778)
							(mid 0.137521 -0.162921)
							(end 0.1524 -0.127)
						)
					)
					(width 0)
					(fill yes)
				)
			)
		)
		(pad "2" smd custom
			(at 0 0.2794 90)
			(size 0.0762 0.0762)
			(layers "B.Cu" "B.Mask" "B.Paste")
			(net "GND")
			(options
				(clearance outline)
				(anchor circle)
			)
			(primitives
				(gr_poly
					(pts
						(arc
							(start 0.1524 0.127)
							(mid 0.137521 0.162921)
							(end 0.1016 0.1778)
						)
						(arc
							(start -0.1016 0.1778)
							(mid -0.137521 0.162921)
							(end -0.1524 0.127)
						)
						(arc
							(start -0.1524 -0.127)
							(mid -0.137521 -0.162921)
							(end -0.1016 -0.1778)
						)
						(arc
							(start 0.1016 -0.1778)
							(mid 0.137521 -0.162921)
							(end 0.1524 -0.127)
						)
					)
					(width 0)
					(fill yes)
				)
			)
		)
	)
	(footprint ""
		(layer "B.Cu")
		(at 170.923204 -20.88642)
		(property "Reference" "C317"
			(at 0 0 0)
			(layer "B.SilkS")
			(hide yes)
			(effects
				(font
					(size 1.27 1.27)
				)
				(justify mirror)
			)
		)
		(property "Value" "SCD22U10V1KX-GP"
			(at 2.8321 -1.7399 0)
			(unlocked yes)
			(layer "B.Fab")
			(hide yes)
			(effects
				(font
					(size 1.016 1.016)
					(thickness 0.1524)
				)
				(justify mirror)
			)
		)
		(property "Device Type" "C0201H13"
			(at 2.8321 -3.2639 0)
			(unlocked yes)
			(layer "B.Fab")
			(hide yes)
			(effects
				(font
					(size 1.016 1.016)
					(thickness 0.1524)
				)
				(justify mirror)
			)
		)
		(duplicate_pad_numbers_are_jumpers no)
		(fp_rect
			(start 0.2794 0.6477)
			(end -0.2794 -0.6477)
			(stroke
				(width 0)
				(type default)
			)
			(fill no)
			(layer "B.CrtYd")
		)
		(fp_rect
			(start 0.2794 0.6477)
			(end -0.2794 -0.6477)
			(stroke
				(width 0)
				(type default)
			)
			(fill no)
			(layer "B.Fab")
		)
		(pad "1" smd custom
			(at 0 -0.2794 180)
			(size 0.0762 0.0762)
			(layers "B.Cu" "B.Mask" "B.Paste")
			(net "PCIE_SCC_TO_COMP_C_3_DP")
			(options
				(clearance outline)
				(anchor circle)
			)
			(primitives
				(gr_poly
					(pts
						(arc
							(start 0.1524 0.127)
							(mid 0.137521 0.162921)
							(end 0.1016 0.1778)
						)
						(arc
							(start -0.1016 0.1778)
							(mid -0.137521 0.162921)
							(end -0.1524 0.127)
						)
						(arc
							(start -0.1524 -0.127)
							(mid -0.137521 -0.162921)
							(end -0.1016 -0.1778)
						)
						(arc
							(start 0.1016 -0.1778)
							(mid 0.137521 -0.162921)
							(end 0.1524 -0.127)
						)
					)
					(width 0)
					(fill yes)
				)
			)
		)
		(pad "2" smd custom
			(at 0 0.2794 180)
			(size 0.0762 0.0762)
			(layers "B.Cu" "B.Mask" "B.Paste")
			(net "PCIE_SCC_TO_COMP_3_DP")
			(options
				(clearance outline)
				(anchor circle)
			)
			(primitives
				(gr_poly
					(pts
						(arc
							(start 0.1524 0.127)
							(mid 0.137521 0.162921)
							(end 0.1016 0.1778)
						)
						(arc
							(start -0.1016 0.1778)
							(mid -0.137521 0.162921)
							(end -0.1524 0.127)
						)
						(arc
							(start -0.1524 -0.127)
							(mid -0.137521 -0.162921)
							(end -0.1016 -0.1778)
						)
						(arc
							(start 0.1016 -0.1778)
							(mid 0.137521 -0.162921)
							(end 0.1524 -0.127)
						)
					)
					(width 0)
					(fill yes)
				)
			)
		)
	)
	(footprint ""
		(layer "B.Cu")
		(at 183.144668 -43.19651 -90)
		(property "Reference" "C478"
			(at 0 0 90)
			(layer "B.SilkS")
			(hide yes)
			(effects
				(font
					(size 1.27 1.27)
				)
				(justify mirror)
			)
		)
		(property "Value" "SCD1U6D3V1KX-GP"
			(at 2.8321 -1.7399 270)
			(unlocked yes)
			(layer "B.Fab")
			(hide yes)
			(effects
				(font
					(size 1.016 1.016)
					(thickness 0.1524)
				)
				(justify mirror)
			)
		)
		(property "Device Type" "C0201H13"
			(at 2.8321 -3.2639 270)
			(unlocked yes)
			(layer "B.Fab")
			(hide yes)
			(effects
				(font
					(size 1.016 1.016)
					(thickness 0.1524)
				)
				(justify mirror)
			)
		)
		(duplicate_pad_numbers_are_jumpers no)
		(fp_rect
			(start 0.2794 0.6477)
			(end -0.2794 -0.6477)
			(stroke
				(width 0)
				(type default)
			)
			(fill no)
			(layer "B.CrtYd")
		)
		(fp_rect
			(start 0.2794 0.6477)
			(end -0.2794 -0.6477)
			(stroke
				(width 0)
				(type default)
			)
			(fill no)
			(layer "B.Fab")
		)
		(pad "1" smd custom
			(at 0 -0.2794 90)
			(size 0.0762 0.0762)
			(layers "B.Cu" "B.Mask" "B.Paste")
			(net "P1V8_C")
			(options
				(clearance outline)
				(anchor circle)
			)
			(primitives
				(gr_poly
					(pts
						(arc
							(start 0.1524 0.127)
							(mid 0.137521 0.162921)
							(end 0.1016 0.1778)
						)
						(arc
							(start -0.1016 0.1778)
							(mid -0.137521 0.162921)
							(end -0.1524 0.127)
						)
						(arc
							(start -0.1524 -0.127)
							(mid -0.137521 -0.162921)
							(end -0.1016 -0.1778)
						)
						(arc
							(start 0.1016 -0.1778)
							(mid 0.137521 -0.162921)
							(end 0.1524 -0.127)
						)
					)
					(width 0)
					(fill yes)
				)
			)
		)
		(pad "2" smd custom
			(at 0 0.2794 90)
			(size 0.0762 0.0762)
			(layers "B.Cu" "B.Mask" "B.Paste")
			(net "GND")
			(options
				(clearance outline)
				(anchor circle)
			)
			(primitives
				(gr_poly
					(pts
						(arc
							(start 0.1524 0.127)
							(mid 0.137521 0.162921)
							(end 0.1016 0.1778)
						)
						(arc
							(start -0.1016 0.1778)
							(mid -0.137521 0.162921)
							(end -0.1524 0.127)
						)
						(arc
							(start -0.1524 -0.127)
							(mid -0.137521 -0.162921)
							(end -0.1016 -0.1778)
						)
						(arc
							(start 0.1016 -0.1778)
							(mid 0.137521 -0.162921)
							(end 0.1524 -0.127)
						)
					)
					(width 0)
					(fill yes)
				)
			)
		)
	)
	(footprint ""
		(layer "B.Cu")
		(at 76.327 -46.609)
		(property "Reference" "C303"
			(at 0 0 0)
			(layer "B.SilkS")
			(hide yes)
			(effects
				(font
					(size 1.27 1.27)
				)
				(justify mirror)
			)
		)
		(property "Value" "SC22U6D3V3MX-9-GP-U"
			(at 0 -2.8194 0)
			(unlocked yes)
			(layer "B.Fab")
			(hide yes)
			(effects
				(font
					(size 1.016 1.016)
					(thickness 0.1524)
				)
				(justify mirror)
			)
		)
		(property "Device Type" "C603H40"
			(at 0 -4.3434 0)
			(unlocked yes)
			(layer "B.Fab")
			(hide yes)
			(effects
				(font
					(size 1.016 1.016)
					(thickness 0.1524)
				)
				(justify mirror)
			)
		)
		(duplicate_pad_numbers_are_jumpers no)
		(fp_line
			(start -0.508 0)
			(end 0.508 0)
			(stroke
				(width 0.2032)
				(type default)
			)
			(layer "B.SilkS")
		)
		(fp_rect
			(start 0.5842 1.3335)
			(end -0.5842 -1.3335)
			(stroke
				(width 0)
				(type default)
			)
			(fill no)
			(layer "B.CrtYd")
		)
		(fp_rect
			(start 0.5842 1.3335)
			(end -0.5842 -1.3335)
			(stroke
				(width 0)
				(type default)
			)
			(fill no)
			(layer "B.Fab")
		)
		(pad "1" smd custom
			(at 0 -0.762 180)
			(size 0.2159 0.2159)
			(layers "B.Cu" "B.Mask" "B.Paste")
			(net "GB_VDDA")
			(options
				(clearance outline)
				(anchor circle)
			)
			(primitives
				(gr_poly
					(pts
						(arc
							(start -0.3302 0.4318)
							(mid -0.402042 0.402042)
							(end -0.4318 0.3302)
						)
						(arc
							(start -0.4318 -0.3302)
							(mid -0.402042 -0.402042)
							(end -0.3302 -0.4318)
						)
						(arc
							(start 0.3302 -0.4318)
							(mid 0.402042 -0.402042)
							(end 0.4318 -0.3302)
						)
						(arc
							(start 0.4318 0.3302)
							(mid 0.402042 0.402042)
							(end 0.3302 0.4318)
						)
					)
					(width 0)
					(fill yes)
				)
			)
		)
		(pad "2" smd custom
			(at 0 0.762 180)
			(size 0.2159 0.2159)
			(layers "B.Cu" "B.Mask" "B.Paste")
			(net "GND")
			(options
				(clearance outline)
				(anchor circle)
			)
			(primitives
				(gr_poly
					(pts
						(arc
							(start -0.3302 0.4318)
							(mid -0.402042 0.402042)
							(end -0.4318 0.3302)
						)
						(arc
							(start -0.4318 -0.3302)
							(mid -0.402042 -0.402042)
							(end -0.3302 -0.4318)
						)
						(arc
							(start 0.3302 -0.4318)
							(mid 0.402042 -0.402042)
							(end 0.4318 -0.3302)
						)
						(arc
							(start 0.4318 0.3302)
							(mid 0.402042 0.402042)
							(end 0.3302 0.4318)
						)
					)
					(width 0)
					(fill yes)
				)
			)
		)
	)
	(footprint ""
		(layer "B.Cu")
		(at 115.4938 -70.3834 180)
		(property "Reference" "C176"
			(at 0 0 0)
			(layer "B.SilkS")
			(hide yes)
			(effects
				(font
					(size 1.27 1.27)
				)
				(justify mirror)
			)
		)
		(property "Value" "SCD1U6D3V1KX-GP"
			(at 2.8321 -1.7399 180)
			(unlocked yes)
			(layer "B.Fab")
			(hide yes)
			(effects
				(font
					(size 1.016 1.016)
					(thickness 0.1524)
				)
				(justify mirror)
			)
		)
		(property "Device Type" "C0201H13"
			(at 2.8321 -3.2639 180)
			(unlocked yes)
			(layer "B.Fab")
			(hide yes)
			(effects
				(font
					(size 1.016 1.016)
					(thickness 0.1524)
				)
				(justify mirror)
			)
		)
		(duplicate_pad_numbers_are_jumpers no)
		(fp_rect
			(start 0.2794 0.6477)
			(end -0.2794 -0.6477)
			(stroke
				(width 0)
				(type default)
			)
			(fill no)
			(layer "B.CrtYd")
		)
		(fp_rect
			(start 0.2794 0.6477)
			(end -0.2794 -0.6477)
			(stroke
				(width 0)
				(type default)
			)
			(fill no)
			(layer "B.Fab")
		)
		(pad "1" smd custom
			(at 0 -0.2794)
			(size 0.0762 0.0762)
			(layers "B.Cu" "B.Mask" "B.Paste")
			(net "P0V9")
			(options
				(clearance outline)
				(anchor circle)
			)
			(primitives
				(gr_poly
					(pts
						(arc
							(start 0.1524 0.127)
							(mid 0.137521 0.162921)
							(end 0.1016 0.1778)
						)
						(arc
							(start -0.1016 0.1778)
							(mid -0.137521 0.162921)
							(end -0.1524 0.127)
						)
						(arc
							(start -0.1524 -0.127)
							(mid -0.137521 -0.162921)
							(end -0.1016 -0.1778)
						)
						(arc
							(start 0.1016 -0.1778)
							(mid 0.137521 -0.162921)
							(end 0.1524 -0.127)
						)
					)
					(width 0)
					(fill yes)
				)
			)
		)
		(pad "2" smd custom
			(at 0 0.2794)
			(size 0.0762 0.0762)
			(layers "B.Cu" "B.Mask" "B.Paste")
			(net "GND")
			(options
				(clearance outline)
				(anchor circle)
			)
			(primitives
				(gr_poly
					(pts
						(arc
							(start 0.1524 0.127)
							(mid 0.137521 0.162921)
							(end 0.1016 0.1778)
						)
						(arc
							(start -0.1016 0.1778)
							(mid -0.137521 0.162921)
							(end -0.1524 0.127)
						)
						(arc
							(start -0.1524 -0.127)
							(mid -0.137521 -0.162921)
							(end -0.1016 -0.1778)
						)
						(arc
							(start 0.1016 -0.1778)
							(mid 0.137521 -0.162921)
							(end 0.1524 -0.127)
						)
					)
					(width 0)
					(fill yes)
				)
			)
		)
	)
	(footprint ""
		(layer "B.Cu")
		(at 122.4788 -68.4911 -90)
		(property "Reference" "C586"
			(at 0 0 90)
			(layer "B.SilkS")
			(hide yes)
			(effects
				(font
					(size 1.27 1.27)
				)
				(justify mirror)
			)
		)
		(property "Value" "SCD1U6D3V1KX-GP"
			(at 2.8321 -1.7399 270)
			(unlocked yes)
			(layer "B.Fab")
			(hide yes)
			(effects
				(font
					(size 1.016 1.016)
					(thickness 0.1524)
				)
				(justify mirror)
			)
		)
		(property "Device Type" "C0201H13"
			(at 2.8321 -3.2639 270)
			(unlocked yes)
			(layer "B.Fab")
			(hide yes)
			(effects
				(font
					(size 1.016 1.016)
					(thickness 0.1524)
				)
				(justify mirror)
			)
		)
		(duplicate_pad_numbers_are_jumpers no)
		(fp_rect
			(start 0.2794 0.6477)
			(end -0.2794 -0.6477)
			(stroke
				(width 0)
				(type default)
			)
			(fill no)
			(layer "B.CrtYd")
		)
		(fp_rect
			(start 0.2794 0.6477)
			(end -0.2794 -0.6477)
			(stroke
				(width 0)
				(type default)
			)
			(fill no)
			(layer "B.Fab")
		)
		(pad "1" smd custom
			(at 0 -0.2794 90)
			(size 0.0762 0.0762)
			(layers "B.Cu" "B.Mask" "B.Paste")
			(net "GB_VDDA")
			(options
				(clearance outline)
				(anchor circle)
			)
			(primitives
				(gr_poly
					(pts
						(arc
							(start 0.1524 0.127)
							(mid 0.137521 0.162921)
							(end 0.1016 0.1778)
						)
						(arc
							(start -0.1016 0.1778)
							(mid -0.137521 0.162921)
							(end -0.1524 0.127)
						)
						(arc
							(start -0.1524 -0.127)
							(mid -0.137521 -0.162921)
							(end -0.1016 -0.1778)
						)
						(arc
							(start 0.1016 -0.1778)
							(mid 0.137521 -0.162921)
							(end 0.1524 -0.127)
						)
					)
					(width 0)
					(fill yes)
				)
			)
		)
		(pad "2" smd custom
			(at 0 0.2794 90)
			(size 0.0762 0.0762)
			(layers "B.Cu" "B.Mask" "B.Paste")
			(net "GND")
			(options
				(clearance outline)
				(anchor circle)
			)
			(primitives
				(gr_poly
					(pts
						(arc
							(start 0.1524 0.127)
							(mid 0.137521 0.162921)
							(end 0.1016 0.1778)
						)
						(arc
							(start -0.1016 0.1778)
							(mid -0.137521 0.162921)
							(end -0.1524 0.127)
						)
						(arc
							(start -0.1524 -0.127)
							(mid -0.137521 -0.162921)
							(end -0.1016 -0.1778)
						)
						(arc
							(start 0.1016 -0.1778)
							(mid 0.137521 -0.162921)
							(end 0.1524 -0.127)
						)
					)
					(width 0)
					(fill yes)
				)
			)
		)
	)
	(footprint ""
		(layer "B.Cu")
		(at 165.46322 -43.798236 180)
		(property "Reference" "C484"
			(at 0 0 0)
			(layer "B.SilkS")
			(hide yes)
			(effects
				(font
					(size 1.27 1.27)
				)
				(justify mirror)
			)
		)
		(property "Value" "SC1U16V2KX-7-GP"
			(at -1.7526 -1.6002 180)
			(unlocked yes)
			(layer "B.Fab")
			(hide yes)
			(effects
				(font
					(size 1.016 1.016)
					(thickness 0.1524)
				)
				(justify mirror)
			)
		)
		(property "Device Type" "C402-TO0D2H24"
			(at -1.7526 -3.1242 180)
			(unlocked yes)
			(layer "B.Fab")
			(hide yes)
			(effects
				(font
					(size 1.016 1.016)
					(thickness 0.1524)
				)
				(justify mirror)
			)
		)
		(duplicate_pad_numbers_are_jumpers no)
		(fp_rect
			(start 0.4826 0.889)
			(end -0.4826 -0.889)
			(stroke
				(width 0)
				(type default)
			)
			(fill no)
			(layer "B.CrtYd")
		)
		(fp_rect
			(start 0.4826 0.889)
			(end -0.4826 -0.889)
			(stroke
				(width 0)
				(type default)
			)
			(fill no)
			(layer "B.Fab")
		)
		(pad "1" smd custom
			(at 0 -0.4572)
			(size 0.1524 0.1524)
			(layers "B.Cu" "B.Mask" "B.Paste")
			(net "P1V8_C")
			(options
				(clearance outline)
				(anchor circle)
			)
			(primitives
				(gr_poly
					(pts
						(arc
							(start -0.254 -0.3048)
							(mid -0.325842 -0.275042)
							(end -0.3556 -0.2032)
						)
						(arc
							(start -0.3556 0.2032)
							(mid -0.325842 0.275042)
							(end -0.254 0.3048)
						)
						(arc
							(start 0.254 0.3048)
							(mid 0.325842 0.275042)
							(end 0.3556 0.2032)
						)
						(arc
							(start 0.3556 -0.2032)
							(mid 0.325842 -0.275042)
							(end 0.254 -0.3048)
						)
					)
					(width 0)
					(fill yes)
				)
			)
		)
		(pad "2" smd custom
			(at 0 0.4572)
			(size 0.1524 0.1524)
			(layers "B.Cu" "B.Mask" "B.Paste")
			(net "GND")
			(options
				(clearance outline)
				(anchor circle)
			)
			(primitives
				(gr_poly
					(pts
						(arc
							(start -0.254 -0.3048)
							(mid -0.325842 -0.275042)
							(end -0.3556 -0.2032)
						)
						(arc
							(start -0.3556 0.2032)
							(mid -0.325842 0.275042)
							(end -0.254 0.3048)
						)
						(arc
							(start 0.254 0.3048)
							(mid 0.325842 0.275042)
							(end 0.3556 0.2032)
						)
						(arc
							(start 0.3556 -0.2032)
							(mid 0.325842 -0.275042)
							(end 0.254 -0.3048)
						)
					)
					(width 0)
					(fill yes)
				)
			)
		)
	)
	(footprint ""
		(layer "B.Cu")
		(at 184.465468 -46.42993 90)
		(property "Reference" "C454"
			(at 0 0 90)
			(layer "B.SilkS")
			(hide yes)
			(effects
				(font
					(size 1.27 1.27)
				)
				(justify mirror)
			)
		)
		(property "Value" "SCD1U6D3V1KX-GP"
			(at 2.8321 -1.7399 90)
			(unlocked yes)
			(layer "B.Fab")
			(hide yes)
			(effects
				(font
					(size 1.016 1.016)
					(thickness 0.1524)
				)
				(justify mirror)
			)
		)
		(property "Device Type" "C0201H13"
			(at 2.8321 -3.2639 90)
			(unlocked yes)
			(layer "B.Fab")
			(hide yes)
			(effects
				(font
					(size 1.016 1.016)
					(thickness 0.1524)
				)
				(justify mirror)
			)
		)
		(duplicate_pad_numbers_are_jumpers no)
		(fp_rect
			(start 0.2794 0.6477)
			(end -0.2794 -0.6477)
			(stroke
				(width 0)
				(type default)
			)
			(fill no)
			(layer "B.CrtYd")
		)
		(fp_rect
			(start 0.2794 0.6477)
			(end -0.2794 -0.6477)
			(stroke
				(width 0)
				(type default)
			)
			(fill no)
			(layer "B.Fab")
		)
		(pad "1" smd custom
			(at 0 -0.2794 270)
			(size 0.0762 0.0762)
			(layers "B.Cu" "B.Mask" "B.Paste")
			(net "P1V8_C")
			(options
				(clearance outline)
				(anchor circle)
			)
			(primitives
				(gr_poly
					(pts
						(arc
							(start 0.1524 0.127)
							(mid 0.137521 0.162921)
							(end 0.1016 0.1778)
						)
						(arc
							(start -0.1016 0.1778)
							(mid -0.137521 0.162921)
							(end -0.1524 0.127)
						)
						(arc
							(start -0.1524 -0.127)
							(mid -0.137521 -0.162921)
							(end -0.1016 -0.1778)
						)
						(arc
							(start 0.1016 -0.1778)
							(mid 0.137521 -0.162921)
							(end 0.1524 -0.127)
						)
					)
					(width 0)
					(fill yes)
				)
			)
		)
		(pad "2" smd custom
			(at 0 0.2794 270)
			(size 0.0762 0.0762)
			(layers "B.Cu" "B.Mask" "B.Paste")
			(net "GND")
			(options
				(clearance outline)
				(anchor circle)
			)
			(primitives
				(gr_poly
					(pts
						(arc
							(start 0.1524 0.127)
							(mid 0.137521 0.162921)
							(end 0.1016 0.1778)
						)
						(arc
							(start -0.1016 0.1778)
							(mid -0.137521 0.162921)
							(end -0.1524 0.127)
						)
						(arc
							(start -0.1524 -0.127)
							(mid -0.137521 -0.162921)
							(end -0.1016 -0.1778)
						)
						(arc
							(start 0.1016 -0.1778)
							(mid 0.137521 -0.162921)
							(end 0.1524 -0.127)
						)
					)
					(width 0)
					(fill yes)
				)
			)
		)
	)
	(footprint ""
		(layer "B.Cu")
		(at 131.699 -89.916 180)
		(property "Reference" "R55"
			(at 0 0 0)
			(layer "B.SilkS")
			(hide yes)
			(effects
				(font
					(size 1.27 1.27)
				)
				(justify mirror)
			)
		)
		(property "Value" "4K7R2F-GP"
			(at -0.064008 -3.993896 180)
			(unlocked yes)
			(layer "B.Fab")
			(hide yes)
			(effects
				(font
					(size 1.016 1.016)
					(thickness 0.1524)
				)
				(justify mirror)
			)
		)
		(property "Device Type" "R402H16"
			(at -0.064008 -5.517896 180)
			(unlocked yes)
			(layer "B.Fab")
			(hide yes)
			(effects
				(font
					(size 1.016 1.016)
					(thickness 0.1524)
				)
				(justify mirror)
			)
		)
		(duplicate_pad_numbers_are_jumpers no)
		(fp_line
			(start 0.508 -0.9398)
			(end 0.508 0.9398)
			(stroke
				(width 0.1524)
				(type default)
			)
			(layer "B.SilkS")
		)
		(fp_line
			(start -0.508 -0.9398)
			(end 0.508 -0.9398)
			(stroke
				(width 0.1524)
				(type default)
			)
			(layer "B.SilkS")
		)
		(fp_rect
			(start 0.508 0.9398)
			(end -0.508 -0.9398)
			(stroke
				(width 0)
				(type default)
			)
			(fill no)
			(layer "B.CrtYd")
		)
		(fp_rect
			(start 0.508 0.9398)
			(end -0.508 -0.9398)
			(stroke
				(width 0)
				(type default)
			)
			(fill no)
			(layer "B.Fab")
		)
		(pad "1" smd custom
			(at 0 -0.4445)
			(size 0.1397 0.1397)
			(layers "B.Cu" "B.Mask" "B.Paste")
			(net "P1V8_E")
			(options
				(clearance outline)
				(anchor circle)
			)
			(primitives
				(gr_poly
					(pts
						(arc
							(start -0.1778 0.2794)
							(mid -0.249642 0.249642)
							(end -0.2794 0.1778)
						)
						(arc
							(start -0.2794 -0.1778)
							(mid -0.249642 -0.249642)
							(end -0.1778 -0.2794)
						)
						(arc
							(start 0.1778 -0.2794)
							(mid 0.249642 -0.249642)
							(end 0.2794 -0.1778)
						)
						(arc
							(start 0.2794 0.1778)
							(mid 0.249642 0.249642)
							(end 0.1778 0.2794)
						)
					)
					(width 0)
					(fill yes)
				)
			)
		)
		(pad "2" smd custom
			(at 0 0.4445)
			(size 0.1397 0.1397)
			(layers "B.Cu" "B.Mask" "B.Paste")
			(net "I2C_DPB_SDA3_LS")
			(options
				(clearance outline)
				(anchor circle)
			)
			(primitives
				(gr_poly
					(pts
						(arc
							(start -0.1778 0.2794)
							(mid -0.249642 0.249642)
							(end -0.2794 0.1778)
						)
						(arc
							(start -0.2794 -0.1778)
							(mid -0.249642 -0.249642)
							(end -0.1778 -0.2794)
						)
						(arc
							(start 0.1778 -0.2794)
							(mid 0.249642 -0.249642)
							(end 0.2794 -0.1778)
						)
						(arc
							(start 0.2794 0.1778)
							(mid 0.249642 0.249642)
							(end 0.1778 0.2794)
						)
					)
					(width 0)
					(fill yes)
				)
			)
		)
	)
	(footprint ""
		(layer "B.Cu")
		(at 102.743 -44.2214 180)
		(property "Reference" "C80"
			(at 0 0 0)
			(layer "B.SilkS")
			(hide yes)
			(effects
				(font
					(size 1.27 1.27)
				)
				(justify mirror)
			)
		)
		(property "Value" "SCD01U16V1KX-GP"
			(at 2.8321 -1.7399 180)
			(unlocked yes)
			(layer "B.Fab")
			(hide yes)
			(effects
				(font
					(size 1.016 1.016)
					(thickness 0.1524)
				)
				(justify mirror)
			)
		)
		(property "Device Type" "C0201H13"
			(at 2.8321 -3.2639 180)
			(unlocked yes)
			(layer "B.Fab")
			(hide yes)
			(effects
				(font
					(size 1.016 1.016)
					(thickness 0.1524)
				)
				(justify mirror)
			)
		)
		(duplicate_pad_numbers_are_jumpers no)
		(fp_rect
			(start 0.2794 0.6477)
			(end -0.2794 -0.6477)
			(stroke
				(width 0)
				(type default)
			)
			(fill no)
			(layer "B.CrtYd")
		)
		(fp_rect
			(start 0.2794 0.6477)
			(end -0.2794 -0.6477)
			(stroke
				(width 0)
				(type default)
			)
			(fill no)
			(layer "B.Fab")
		)
		(pad "1" smd custom
			(at 0 -0.2794)
			(size 0.0762 0.0762)
			(layers "B.Cu" "B.Mask" "B.Paste")
			(net "PHY_DPB_TO_SCC_20_DN")
			(options
				(clearance outline)
				(anchor circle)
			)
			(primitives
				(gr_poly
					(pts
						(arc
							(start 0.1524 0.127)
							(mid 0.137521 0.162921)
							(end 0.1016 0.1778)
						)
						(arc
							(start -0.1016 0.1778)
							(mid -0.137521 0.162921)
							(end -0.1524 0.127)
						)
						(arc
							(start -0.1524 -0.127)
							(mid -0.137521 -0.162921)
							(end -0.1016 -0.1778)
						)
						(arc
							(start 0.1016 -0.1778)
							(mid 0.137521 -0.162921)
							(end 0.1524 -0.127)
						)
					)
					(width 0)
					(fill yes)
				)
			)
		)
		(pad "2" smd custom
			(at 0 0.2794)
			(size 0.0762 0.0762)
			(layers "B.Cu" "B.Mask" "B.Paste")
			(net "PHY_DPB_TO_SCC_C_20_DN")
			(options
				(clearance outline)
				(anchor circle)
			)
			(primitives
				(gr_poly
					(pts
						(arc
							(start 0.1524 0.127)
							(mid 0.137521 0.162921)
							(end 0.1016 0.1778)
						)
						(arc
							(start -0.1016 0.1778)
							(mid -0.137521 0.162921)
							(end -0.1524 0.127)
						)
						(arc
							(start -0.1524 -0.127)
							(mid -0.137521 -0.162921)
							(end -0.1016 -0.1778)
						)
						(arc
							(start 0.1016 -0.1778)
							(mid 0.137521 -0.162921)
							(end 0.1524 -0.127)
						)
					)
					(width 0)
					(fill yes)
				)
			)
		)
	)
	(footprint ""
		(layer "B.Cu")
		(at 198.502778 -31.900622)
		(property "Reference" "C364"
			(at 0 0 0)
			(layer "B.SilkS")
			(hide yes)
			(effects
				(font
					(size 1.27 1.27)
				)
				(justify mirror)
			)
		)
		(property "Value" "SC10U6D3V5KX-4GP"
			(at 0.0762 -6.1214 0)
			(unlocked yes)
			(layer "B.Fab")
			(hide yes)
			(effects
				(font
					(size 1.016 1.016)
					(thickness 0.1524)
				)
				(justify mirror)
			)
		)
		(property "Device Type" "C805H58"
			(at 0.0762 -8.1534 0)
			(unlocked yes)
			(layer "B.Fab")
			(hide yes)
			(effects
				(font
					(size 1.016 1.016)
					(thickness 0.1524)
				)
				(justify mirror)
			)
		)
		(duplicate_pad_numbers_are_jumpers no)
		(fp_line
			(start -0.635 0)
			(end 0.635 0)
			(stroke
				(width 0.508)
				(type default)
			)
			(layer "B.SilkS")
		)
		(fp_rect
			(start 0.9652 1.778)
			(end -0.9652 -1.778)
			(stroke
				(width 0)
				(type default)
			)
			(fill no)
			(layer "B.CrtYd")
		)
		(fp_poly
			(pts
				(xy 0.9652 -1.778) (xy -0.9652 -1.778) (xy -0.9652 1.778) (xy 0.9652 1.778)
			)
			(stroke
				(width 0)
				(type default)
			)
			(fill no)
			(layer "B.Fab")
		)
		(pad "1" smd rect
			(at 0 -0.9652 180)
			(size 1.397 1.143)
			(layers "B.Cu" "B.Mask" "B.Paste")
			(net "PLL_VDD")
		)
		(pad "2" smd rect
			(at 0 0.9652 180)
			(size 1.397 1.143)
			(layers "B.Cu" "B.Mask" "B.Paste")
			(net "GND")
		)
	)
	(footprint ""
		(layer "B.Cu")
		(at 186.963812 -46.168056 -90)
		(property "Reference" "TP110"
			(at 0 0 90)
			(layer "B.SilkS")
			(hide yes)
			(effects
				(font
					(size 1.27 1.27)
				)
				(justify mirror)
			)
		)
		(property "Value" "TPAD28-2-GP"
			(at 0.0127 -1.6637 270)
			(unlocked yes)
			(layer "B.Fab")
			(hide yes)
			(effects
				(font
					(size 1.016 1.016)
					(thickness 0.1524)
				)
				(justify mirror)
			)
		)
		(property "Device Type" "TPAD28"
			(at 0.0127 -3.1877 270)
			(unlocked yes)
			(layer "B.Fab")
			(hide yes)
			(effects
				(font
					(size 1.016 1.016)
					(thickness 0.1524)
				)
				(justify mirror)
			)
		)
		(duplicate_pad_numbers_are_jumpers no)
		(fp_poly
			(pts
				(arc
					(start 0 -0.3556)
					(mid 0 0.3556)
					(end 0 -0.3556)
				)
			)
			(stroke
				(width 0)
				(type default)
			)
			(fill no)
			(layer "B.CrtYd")
		)
		(fp_poly
			(pts
				(arc
					(start 0 -0.6096)
					(mid 0 0.6096)
					(end 0 -0.6096)
				)
			)
			(stroke
				(width 0)
				(type default)
			)
			(fill no)
			(layer "B.Fab")
		)
		(pad "1" smd circle
			(at 0 0 90)
			(size 0.7112 0.7112)
			(layers "B.Cu" "B.Mask" "B.Paste")
			(net "XM_ADDR_25")
		)
	)
	(footprint ""
		(layer "B.Cu")
		(at 185.4708 -24.9428 90)
		(property "Reference" "TP67"
			(at 0 0 90)
			(layer "B.SilkS")
			(hide yes)
			(effects
				(font
					(size 1.27 1.27)
				)
				(justify mirror)
			)
		)
		(property "Value" "TPAD28-2-GP"
			(at 0.0127 -1.6637 90)
			(unlocked yes)
			(layer "B.Fab")
			(hide yes)
			(effects
				(font
					(size 1.016 1.016)
					(thickness 0.1524)
				)
				(justify mirror)
			)
		)
		(property "Device Type" "TPAD28"
			(at 0.0127 -3.1877 90)
			(unlocked yes)
			(layer "B.Fab")
			(hide yes)
			(effects
				(font
					(size 1.016 1.016)
					(thickness 0.1524)
				)
				(justify mirror)
			)
		)
		(duplicate_pad_numbers_are_jumpers no)
		(fp_poly
			(pts
				(arc
					(start 0 0.3556)
					(mid 0 -0.3556)
					(end 0 0.3556)
				)
			)
			(stroke
				(width 0)
				(type default)
			)
			(fill no)
			(layer "B.CrtYd")
		)
		(fp_poly
			(pts
				(arc
					(start 0 0.6096)
					(mid 0 -0.6096)
					(end 0 0.6096)
				)
			)
			(stroke
				(width 0)
				(type default)
			)
			(fill no)
			(layer "B.Fab")
		)
		(pad "1" smd circle
			(at 0 0 270)
			(size 0.7112 0.7112)
			(layers "B.Cu" "B.Mask" "B.Paste")
			(net "IOC_GPIO_14")
		)
	)
	(footprint ""
		(layer "B.Cu")
		(at 118.999 -84.709)
		(property "Reference" "TP157"
			(at 0 0 0)
			(layer "B.SilkS")
			(hide yes)
			(effects
				(font
					(size 1.27 1.27)
				)
				(justify mirror)
			)
		)
		(property "Value" "TPAD28-2-GP"
			(at 0.0127 -1.6637 0)
			(unlocked yes)
			(layer "B.Fab")
			(hide yes)
			(effects
				(font
					(size 1.016 1.016)
					(thickness 0.1524)
				)
				(justify mirror)
			)
		)
		(property "Device Type" "TPAD28"
			(at 0.0127 -3.1877 0)
			(unlocked yes)
			(layer "B.Fab")
			(hide yes)
			(effects
				(font
					(size 1.016 1.016)
					(thickness 0.1524)
				)
				(justify mirror)
			)
		)
		(duplicate_pad_numbers_are_jumpers no)
		(fp_poly
			(pts
				(arc
					(start 0.3556 0)
					(mid -0.3556 0)
					(end 0.3556 0)
				)
			)
			(stroke
				(width 0)
				(type default)
			)
			(fill no)
			(layer "B.CrtYd")
		)
		(fp_poly
			(pts
				(arc
					(start 0.6096 0)
					(mid -0.6096 0)
					(end 0.6096 0)
				)
			)
			(stroke
				(width 0)
				(type default)
			)
			(fill no)
			(layer "B.Fab")
		)
		(pad "1" smd circle
			(at 0 0 180)
			(size 0.7112 0.7112)
			(layers "B.Cu" "B.Mask" "B.Paste")
			(net "ICE_TCK")
		)
	)
	(footprint ""
		(layer "B.Cu")
		(at 108.712 -72.009)
		(property "Reference" "C128"
			(at 0 0 0)
			(layer "B.SilkS")
			(hide yes)
			(effects
				(font
					(size 1.27 1.27)
				)
				(justify mirror)
			)
		)
		(property "Value" "SCD1U6D3V1KX-GP"
			(at 2.8321 -1.7399 0)
			(unlocked yes)
			(layer "B.Fab")
			(hide yes)
			(effects
				(font
					(size 1.016 1.016)
					(thickness 0.1524)
				)
				(justify mirror)
			)
		)
		(property "Device Type" "C0201H13"
			(at 2.8321 -3.2639 0)
			(unlocked yes)
			(layer "B.Fab")
			(hide yes)
			(effects
				(font
					(size 1.016 1.016)
					(thickness 0.1524)
				)
				(justify mirror)
			)
		)
		(duplicate_pad_numbers_are_jumpers no)
		(fp_rect
			(start 0.2794 0.6477)
			(end -0.2794 -0.6477)
			(stroke
				(width 0)
				(type default)
			)
			(fill no)
			(layer "B.CrtYd")
		)
		(fp_rect
			(start 0.2794 0.6477)
			(end -0.2794 -0.6477)
			(stroke
				(width 0)
				(type default)
			)
			(fill no)
			(layer "B.Fab")
		)
		(pad "1" smd custom
			(at 0 -0.2794 180)
			(size 0.0762 0.0762)
			(layers "B.Cu" "B.Mask" "B.Paste")
			(net "P1V8_E")
			(options
				(clearance outline)
				(anchor circle)
			)
			(primitives
				(gr_poly
					(pts
						(arc
							(start 0.1524 0.127)
							(mid 0.137521 0.162921)
							(end 0.1016 0.1778)
						)
						(arc
							(start -0.1016 0.1778)
							(mid -0.137521 0.162921)
							(end -0.1524 0.127)
						)
						(arc
							(start -0.1524 -0.127)
							(mid -0.137521 -0.162921)
							(end -0.1016 -0.1778)
						)
						(arc
							(start 0.1016 -0.1778)
							(mid 0.137521 -0.162921)
							(end 0.1524 -0.127)
						)
					)
					(width 0)
					(fill yes)
				)
			)
		)
		(pad "2" smd custom
			(at 0 0.2794 180)
			(size 0.0762 0.0762)
			(layers "B.Cu" "B.Mask" "B.Paste")
			(net "GND")
			(options
				(clearance outline)
				(anchor circle)
			)
			(primitives
				(gr_poly
					(pts
						(arc
							(start 0.1524 0.127)
							(mid 0.137521 0.162921)
							(end 0.1016 0.1778)
						)
						(arc
							(start -0.1016 0.1778)
							(mid -0.137521 0.162921)
							(end -0.1524 0.127)
						)
						(arc
							(start -0.1524 -0.127)
							(mid -0.137521 -0.162921)
							(end -0.1016 -0.1778)
						)
						(arc
							(start 0.1016 -0.1778)
							(mid 0.137521 -0.162921)
							(end 0.1524 -0.127)
						)
					)
					(width 0)
					(fill yes)
				)
			)
		)
	)
	(footprint ""
		(layer "B.Cu")
		(at 187.1472 -24.8666 -90)
		(property "Reference" "R234"
			(at 0 0 90)
			(layer "B.SilkS")
			(hide yes)
			(effects
				(font
					(size 1.27 1.27)
				)
				(justify mirror)
			)
		)
		(property "Value" "4K7R2F-GP"
			(at -0.064008 -3.993896 270)
			(unlocked yes)
			(layer "B.Fab")
			(hide yes)
			(effects
				(font
					(size 1.016 1.016)
					(thickness 0.1524)
				)
				(justify mirror)
			)
		)
		(property "Device Type" "R402H16"
			(at -0.064008 -5.517896 270)
			(unlocked yes)
			(layer "B.Fab")
			(hide yes)
			(effects
				(font
					(size 1.016 1.016)
					(thickness 0.1524)
				)
				(justify mirror)
			)
		)
		(duplicate_pad_numbers_are_jumpers no)
		(fp_line
			(start -0.508 -0.9398)
			(end 0.508 -0.9398)
			(stroke
				(width 0.1524)
				(type default)
			)
			(layer "B.SilkS")
		)
		(fp_line
			(start 0.508 -0.9398)
			(end 0.508 0.9398)
			(stroke
				(width 0.1524)
				(type default)
			)
			(layer "B.SilkS")
		)
		(fp_rect
			(start 0.508 0.9398)
			(end -0.508 -0.9398)
			(stroke
				(width 0)
				(type default)
			)
			(fill no)
			(layer "B.CrtYd")
		)
		(fp_rect
			(start 0.508 0.9398)
			(end -0.508 -0.9398)
			(stroke
				(width 0)
				(type default)
			)
			(fill no)
			(layer "B.Fab")
		)
		(pad "1" smd custom
			(at 0 -0.4445 90)
			(size 0.1397 0.1397)
			(layers "B.Cu" "B.Mask" "B.Paste")
			(net "P1V8_C")
			(options
				(clearance outline)
				(anchor circle)
			)
			(primitives
				(gr_poly
					(pts
						(arc
							(start -0.1778 0.2794)
							(mid -0.249642 0.249642)
							(end -0.2794 0.1778)
						)
						(arc
							(start -0.2794 -0.1778)
							(mid -0.249642 -0.249642)
							(end -0.1778 -0.2794)
						)
						(arc
							(start 0.1778 -0.2794)
							(mid 0.249642 -0.249642)
							(end 0.2794 -0.1778)
						)
						(arc
							(start 0.2794 0.1778)
							(mid 0.249642 0.249642)
							(end 0.1778 0.2794)
						)
					)
					(width 0)
					(fill yes)
				)
			)
		)
		(pad "2" smd custom
			(at 0 0.4445 90)
			(size 0.1397 0.1397)
			(layers "B.Cu" "B.Mask" "B.Paste")
			(net "IOC_UART_1_RX")
			(options
				(clearance outline)
				(anchor circle)
			)
			(primitives
				(gr_poly
					(pts
						(arc
							(start -0.1778 0.2794)
							(mid -0.249642 0.249642)
							(end -0.2794 0.1778)
						)
						(arc
							(start -0.2794 -0.1778)
							(mid -0.249642 -0.249642)
							(end -0.1778 -0.2794)
						)
						(arc
							(start 0.1778 -0.2794)
							(mid 0.249642 -0.249642)
							(end 0.2794 -0.1778)
						)
						(arc
							(start 0.2794 0.1778)
							(mid 0.249642 0.249642)
							(end 0.1778 0.2794)
						)
					)
					(width 0)
					(fill yes)
				)
			)
		)
	)
	(footprint ""
		(layer "B.Cu")
		(at 109.9566 -87.0204)
		(property "Reference" "R104"
			(at 0 0 0)
			(layer "B.SilkS")
			(hide yes)
			(effects
				(font
					(size 1.27 1.27)
				)
				(justify mirror)
			)
		)
		(property "Value" "4K75R2F-1-GP"
			(at -0.064008 -3.993896 0)
			(unlocked yes)
			(layer "B.Fab")
			(hide yes)
			(effects
				(font
					(size 1.016 1.016)
					(thickness 0.1524)
				)
				(justify mirror)
			)
		)
		(property "Device Type" "R402H16"
			(at -0.064008 -5.517896 0)
			(unlocked yes)
			(layer "B.Fab")
			(hide yes)
			(effects
				(font
					(size 1.016 1.016)
					(thickness 0.1524)
				)
				(justify mirror)
			)
		)
		(duplicate_pad_numbers_are_jumpers no)
		(fp_line
			(start -0.508 -0.9398)
			(end 0.508 -0.9398)
			(stroke
				(width 0.1524)
				(type default)
			)
			(layer "B.SilkS")
		)
		(fp_line
			(start 0.508 -0.9398)
			(end 0.508 0.9398)
			(stroke
				(width 0.1524)
				(type default)
			)
			(layer "B.SilkS")
		)
		(fp_rect
			(start 0.508 0.9398)
			(end -0.508 -0.9398)
			(stroke
				(width 0)
				(type default)
			)
			(fill no)
			(layer "B.CrtYd")
		)
		(fp_rect
			(start 0.508 0.9398)
			(end -0.508 -0.9398)
			(stroke
				(width 0)
				(type default)
			)
			(fill no)
			(layer "B.Fab")
		)
		(pad "1" smd custom
			(at 0 -0.4445 180)
			(size 0.1397 0.1397)
			(layers "B.Cu" "B.Mask" "B.Paste")
			(net "TMUX_EN")
			(options
				(clearance outline)
				(anchor circle)
			)
			(primitives
				(gr_poly
					(pts
						(arc
							(start -0.1778 0.2794)
							(mid -0.249642 0.249642)
							(end -0.2794 0.1778)
						)
						(arc
							(start -0.2794 -0.1778)
							(mid -0.249642 -0.249642)
							(end -0.1778 -0.2794)
						)
						(arc
							(start 0.1778 -0.2794)
							(mid 0.249642 -0.249642)
							(end 0.2794 -0.1778)
						)
						(arc
							(start 0.2794 0.1778)
							(mid 0.249642 0.249642)
							(end 0.1778 0.2794)
						)
					)
					(width 0)
					(fill yes)
				)
			)
		)
		(pad "2" smd custom
			(at 0 0.4445 180)
			(size 0.1397 0.1397)
			(layers "B.Cu" "B.Mask" "B.Paste")
			(net "P1V8_E")
			(options
				(clearance outline)
				(anchor circle)
			)
			(primitives
				(gr_poly
					(pts
						(arc
							(start -0.1778 0.2794)
							(mid -0.249642 0.249642)
							(end -0.2794 0.1778)
						)
						(arc
							(start -0.2794 -0.1778)
							(mid -0.249642 -0.249642)
							(end -0.1778 -0.2794)
						)
						(arc
							(start 0.1778 -0.2794)
							(mid 0.249642 -0.249642)
							(end 0.2794 -0.1778)
						)
						(arc
							(start 0.2794 0.1778)
							(mid 0.249642 0.249642)
							(end 0.1778 0.2794)
						)
					)
					(width 0)
					(fill yes)
				)
			)
		)
	)
	(footprint ""
		(layer "B.Cu")
		(at 70.485 -48.133 90)
		(property "Reference" "L16"
			(at 0 0 90)
			(layer "B.SilkS")
			(hide yes)
			(effects
				(font
					(size 1.27 1.27)
				)
				(justify mirror)
			)
		)
		(property "Value" "MPZ2012S300AT-GP"
			(at 0 -4.2418 90)
			(unlocked yes)
			(layer "B.Fab")
			(hide yes)
			(effects
				(font
					(size 1.016 1.016)
					(thickness 0.1524)
				)
				(justify mirror)
			)
		)
		(property "Device Type" "L805H42"
			(at 0 -5.7912 90)
			(unlocked yes)
			(layer "B.Fab")
			(hide yes)
			(effects
				(font
					(size 1.016 1.016)
					(thickness 0.1524)
				)
				(justify mirror)
			)
		)
		(duplicate_pad_numbers_are_jumpers no)
		(fp_line
			(start 0.889 -1.7018)
			(end -0.889 -1.7018)
			(stroke
				(width 0.1524)
				(type default)
			)
			(layer "B.SilkS")
		)
		(fp_line
			(start -0.889 -1.7018)
			(end -0.889 1.7018)
			(stroke
				(width 0.1524)
				(type default)
			)
			(layer "B.SilkS")
		)
		(fp_line
			(start 0.889 1.7018)
			(end 0.889 -1.7018)
			(stroke
				(width 0.1524)
				(type default)
			)
			(layer "B.SilkS")
		)
		(fp_line
			(start -0.889 1.7018)
			(end 0.889 1.7018)
			(stroke
				(width 0.1524)
				(type default)
			)
			(layer "B.SilkS")
		)
		(fp_rect
			(start 0.9652 1.778)
			(end -0.9652 -1.778)
			(stroke
				(width 0)
				(type default)
			)
			(fill no)
			(layer "B.CrtYd")
		)
		(fp_rect
			(start 0.9652 1.778)
			(end -0.9652 -1.778)
			(stroke
				(width 0)
				(type default)
			)
			(fill no)
			(layer "B.Fab")
		)
		(pad "1" smd rect
			(at 0 -0.9652 270)
			(size 1.397 1.143)
			(layers "B.Cu" "B.Mask" "B.Paste")
			(net "P0V9")
		)
		(pad "2" smd rect
			(at 0 0.9652 270)
			(size 1.397 1.143)
			(layers "B.Cu" "B.Mask" "B.Paste")
			(net "GB_VDDA")
		)
	)
	(footprint ""
		(layer "B.Cu")
		(at 117.5004 -76.0222 180)
		(property "Reference" "C131"
			(at 0 0 0)
			(layer "B.SilkS")
			(hide yes)
			(effects
				(font
					(size 1.27 1.27)
				)
				(justify mirror)
			)
		)
		(property "Value" "SCD1U6D3V1KX-GP"
			(at 2.8321 -1.7399 180)
			(unlocked yes)
			(layer "B.Fab")
			(hide yes)
			(effects
				(font
					(size 1.016 1.016)
					(thickness 0.1524)
				)
				(justify mirror)
			)
		)
		(property "Device Type" "C0201H13"
			(at 2.8321 -3.2639 180)
			(unlocked yes)
			(layer "B.Fab")
			(hide yes)
			(effects
				(font
					(size 1.016 1.016)
					(thickness 0.1524)
				)
				(justify mirror)
			)
		)
		(duplicate_pad_numbers_are_jumpers no)
		(fp_rect
			(start 0.2794 0.6477)
			(end -0.2794 -0.6477)
			(stroke
				(width 0)
				(type default)
			)
			(fill no)
			(layer "B.CrtYd")
		)
		(fp_rect
			(start 0.2794 0.6477)
			(end -0.2794 -0.6477)
			(stroke
				(width 0)
				(type default)
			)
			(fill no)
			(layer "B.Fab")
		)
		(pad "1" smd custom
			(at 0 -0.2794)
			(size 0.0762 0.0762)
			(layers "B.Cu" "B.Mask" "B.Paste")
			(net "P1V8_E")
			(options
				(clearance outline)
				(anchor circle)
			)
			(primitives
				(gr_poly
					(pts
						(arc
							(start 0.1524 0.127)
							(mid 0.137521 0.162921)
							(end 0.1016 0.1778)
						)
						(arc
							(start -0.1016 0.1778)
							(mid -0.137521 0.162921)
							(end -0.1524 0.127)
						)
						(arc
							(start -0.1524 -0.127)
							(mid -0.137521 -0.162921)
							(end -0.1016 -0.1778)
						)
						(arc
							(start 0.1016 -0.1778)
							(mid 0.137521 -0.162921)
							(end 0.1524 -0.127)
						)
					)
					(width 0)
					(fill yes)
				)
			)
		)
		(pad "2" smd custom
			(at 0 0.2794)
			(size 0.0762 0.0762)
			(layers "B.Cu" "B.Mask" "B.Paste")
			(net "GND")
			(options
				(clearance outline)
				(anchor circle)
			)
			(primitives
				(gr_poly
					(pts
						(arc
							(start 0.1524 0.127)
							(mid 0.137521 0.162921)
							(end 0.1016 0.1778)
						)
						(arc
							(start -0.1016 0.1778)
							(mid -0.137521 0.162921)
							(end -0.1524 0.127)
						)
						(arc
							(start -0.1524 -0.127)
							(mid -0.137521 -0.162921)
							(end -0.1016 -0.1778)
						)
						(arc
							(start 0.1016 -0.1778)
							(mid 0.137521 -0.162921)
							(end 0.1524 -0.127)
						)
					)
					(width 0)
					(fill yes)
				)
			)
		)
	)
	(footprint ""
		(layer "B.Cu")
		(at 116.84 -86.995 180)
		(property "Reference" "R143"
			(at 0 0 0)
			(layer "B.SilkS")
			(hide yes)
			(effects
				(font
					(size 1.27 1.27)
				)
				(justify mirror)
			)
		)
		(property "Value" "4K7R2F-GP"
			(at -0.064008 -3.993896 180)
			(unlocked yes)
			(layer "B.Fab")
			(hide yes)
			(effects
				(font
					(size 1.016 1.016)
					(thickness 0.1524)
				)
				(justify mirror)
			)
		)
		(property "Device Type" "R402H16"
			(at -0.064008 -5.517896 180)
			(unlocked yes)
			(layer "B.Fab")
			(hide yes)
			(effects
				(font
					(size 1.016 1.016)
					(thickness 0.1524)
				)
				(justify mirror)
			)
		)
		(duplicate_pad_numbers_are_jumpers no)
		(fp_line
			(start 0.508 -0.9398)
			(end 0.508 0.9398)
			(stroke
				(width 0.1524)
				(type default)
			)
			(layer "B.SilkS")
		)
		(fp_line
			(start -0.508 -0.9398)
			(end 0.508 -0.9398)
			(stroke
				(width 0.1524)
				(type default)
			)
			(layer "B.SilkS")
		)
		(fp_rect
			(start 0.508 0.9398)
			(end -0.508 -0.9398)
			(stroke
				(width 0)
				(type default)
			)
			(fill no)
			(layer "B.CrtYd")
		)
		(fp_rect
			(start 0.508 0.9398)
			(end -0.508 -0.9398)
			(stroke
				(width 0)
				(type default)
			)
			(fill no)
			(layer "B.Fab")
		)
		(pad "1" smd custom
			(at 0 -0.4445)
			(size 0.1397 0.1397)
			(layers "B.Cu" "B.Mask" "B.Paste")
			(net "EXP_XM_ADDR_17")
			(options
				(clearance outline)
				(anchor circle)
			)
			(primitives
				(gr_poly
					(pts
						(arc
							(start -0.1778 0.2794)
							(mid -0.249642 0.249642)
							(end -0.2794 0.1778)
						)
						(arc
							(start -0.2794 -0.1778)
							(mid -0.249642 -0.249642)
							(end -0.1778 -0.2794)
						)
						(arc
							(start 0.1778 -0.2794)
							(mid 0.249642 -0.249642)
							(end 0.2794 -0.1778)
						)
						(arc
							(start 0.2794 0.1778)
							(mid 0.249642 0.249642)
							(end 0.1778 0.2794)
						)
					)
					(width 0)
					(fill yes)
				)
			)
		)
		(pad "2" smd custom
			(at 0 0.4445)
			(size 0.1397 0.1397)
			(layers "B.Cu" "B.Mask" "B.Paste")
			(net "GND")
			(options
				(clearance outline)
				(anchor circle)
			)
			(primitives
				(gr_poly
					(pts
						(arc
							(start -0.1778 0.2794)
							(mid -0.249642 0.249642)
							(end -0.2794 0.1778)
						)
						(arc
							(start -0.2794 -0.1778)
							(mid -0.249642 -0.249642)
							(end -0.1778 -0.2794)
						)
						(arc
							(start 0.1778 -0.2794)
							(mid 0.249642 -0.249642)
							(end 0.2794 -0.1778)
						)
						(arc
							(start 0.2794 0.1778)
							(mid 0.249642 0.249642)
							(end 0.1778 0.2794)
						)
					)
					(width 0)
					(fill yes)
				)
			)
		)
	)
	(footprint ""
		(layer "B.Cu")
		(at 136.1948 -78.0542 -90)
		(property "Reference" "C6"
			(at 0 0 90)
			(layer "B.SilkS")
			(hide yes)
			(effects
				(font
					(size 1.27 1.27)
				)
				(justify mirror)
			)
		)
		(property "Value" "SCD01U16V1KX-GP"
			(at 2.8321 -1.7399 270)
			(unlocked yes)
			(layer "B.Fab")
			(hide yes)
			(effects
				(font
					(size 1.016 1.016)
					(thickness 0.1524)
				)
				(justify mirror)
			)
		)
		(property "Device Type" "C0201H13"
			(at 2.8321 -3.2639 270)
			(unlocked yes)
			(layer "B.Fab")
			(hide yes)
			(effects
				(font
					(size 1.016 1.016)
					(thickness 0.1524)
				)
				(justify mirror)
			)
		)
		(duplicate_pad_numbers_are_jumpers no)
		(fp_rect
			(start 0.2794 0.6477)
			(end -0.2794 -0.6477)
			(stroke
				(width 0)
				(type default)
			)
			(fill no)
			(layer "B.CrtYd")
		)
		(fp_rect
			(start 0.2794 0.6477)
			(end -0.2794 -0.6477)
			(stroke
				(width 0)
				(type default)
			)
			(fill no)
			(layer "B.Fab")
		)
		(pad "1" smd custom
			(at 0 -0.2794 90)
			(size 0.0762 0.0762)
			(layers "B.Cu" "B.Mask" "B.Paste")
			(net "PHY_CONN_TO_EXP_9_DN")
			(options
				(clearance outline)
				(anchor circle)
			)
			(primitives
				(gr_poly
					(pts
						(arc
							(start 0.1524 0.127)
							(mid 0.137521 0.162921)
							(end 0.1016 0.1778)
						)
						(arc
							(start -0.1016 0.1778)
							(mid -0.137521 0.162921)
							(end -0.1524 0.127)
						)
						(arc
							(start -0.1524 -0.127)
							(mid -0.137521 -0.162921)
							(end -0.1016 -0.1778)
						)
						(arc
							(start 0.1016 -0.1778)
							(mid 0.137521 -0.162921)
							(end 0.1524 -0.127)
						)
					)
					(width 0)
					(fill yes)
				)
			)
		)
		(pad "2" smd custom
			(at 0 0.2794 90)
			(size 0.0762 0.0762)
			(layers "B.Cu" "B.Mask" "B.Paste")
			(net "PHY_CONN_TO_EXP_C_9_DN")
			(options
				(clearance outline)
				(anchor circle)
			)
			(primitives
				(gr_poly
					(pts
						(arc
							(start 0.1524 0.127)
							(mid 0.137521 0.162921)
							(end 0.1016 0.1778)
						)
						(arc
							(start -0.1016 0.1778)
							(mid -0.137521 0.162921)
							(end -0.1524 0.127)
						)
						(arc
							(start -0.1524 -0.127)
							(mid -0.137521 -0.162921)
							(end -0.1016 -0.1778)
						)
						(arc
							(start 0.1016 -0.1778)
							(mid 0.137521 -0.162921)
							(end 0.1524 -0.127)
						)
					)
					(width 0)
					(fill yes)
				)
			)
		)
	)
	(footprint ""
		(layer "B.Cu")
		(at 111.2774 -57.4802)
		(property "Reference" "C540"
			(at 0 0 0)
			(layer "B.SilkS")
			(hide yes)
			(effects
				(font
					(size 1.27 1.27)
				)
				(justify mirror)
			)
		)
		(property "Value" "SCD1U6D3V1KX-GP"
			(at 2.8321 -1.7399 0)
			(unlocked yes)
			(layer "B.Fab")
			(hide yes)
			(effects
				(font
					(size 1.016 1.016)
					(thickness 0.1524)
				)
				(justify mirror)
			)
		)
		(property "Device Type" "C0201H13"
			(at 2.8321 -3.2639 0)
			(unlocked yes)
			(layer "B.Fab")
			(hide yes)
			(effects
				(font
					(size 1.016 1.016)
					(thickness 0.1524)
				)
				(justify mirror)
			)
		)
		(duplicate_pad_numbers_are_jumpers no)
		(fp_rect
			(start 0.2794 0.6477)
			(end -0.2794 -0.6477)
			(stroke
				(width 0)
				(type default)
			)
			(fill no)
			(layer "B.CrtYd")
		)
		(fp_rect
			(start 0.2794 0.6477)
			(end -0.2794 -0.6477)
			(stroke
				(width 0)
				(type default)
			)
			(fill no)
			(layer "B.Fab")
		)
		(pad "1" smd custom
			(at 0 -0.2794 180)
			(size 0.0762 0.0762)
			(layers "B.Cu" "B.Mask" "B.Paste")
			(net "GB_VDDA")
			(options
				(clearance outline)
				(anchor circle)
			)
			(primitives
				(gr_poly
					(pts
						(arc
							(start 0.1524 0.127)
							(mid 0.137521 0.162921)
							(end 0.1016 0.1778)
						)
						(arc
							(start -0.1016 0.1778)
							(mid -0.137521 0.162921)
							(end -0.1524 0.127)
						)
						(arc
							(start -0.1524 -0.127)
							(mid -0.137521 -0.162921)
							(end -0.1016 -0.1778)
						)
						(arc
							(start 0.1016 -0.1778)
							(mid 0.137521 -0.162921)
							(end 0.1524 -0.127)
						)
					)
					(width 0)
					(fill yes)
				)
			)
		)
		(pad "2" smd custom
			(at 0 0.2794 180)
			(size 0.0762 0.0762)
			(layers "B.Cu" "B.Mask" "B.Paste")
			(net "GND")
			(options
				(clearance outline)
				(anchor circle)
			)
			(primitives
				(gr_poly
					(pts
						(arc
							(start 0.1524 0.127)
							(mid 0.137521 0.162921)
							(end 0.1016 0.1778)
						)
						(arc
							(start -0.1016 0.1778)
							(mid -0.137521 0.162921)
							(end -0.1524 0.127)
						)
						(arc
							(start -0.1524 -0.127)
							(mid -0.137521 -0.162921)
							(end -0.1016 -0.1778)
						)
						(arc
							(start 0.1016 -0.1778)
							(mid 0.137521 -0.162921)
							(end 0.1524 -0.127)
						)
					)
					(width 0)
					(fill yes)
				)
			)
		)
	)
	(footprint ""
		(layer "B.Cu")
		(at 191.135 -32.385)
		(property "Reference" "TP117"
			(at 0 0 0)
			(layer "B.SilkS")
			(hide yes)
			(effects
				(font
					(size 1.27 1.27)
				)
				(justify mirror)
			)
		)
		(property "Value" "TPAD28-2-GP"
			(at 0.0127 -1.6637 0)
			(unlocked yes)
			(layer "B.Fab")
			(hide yes)
			(effects
				(font
					(size 1.016 1.016)
					(thickness 0.1524)
				)
				(justify mirror)
			)
		)
		(property "Device Type" "TPAD28"
			(at 0.0127 -3.1877 0)
			(unlocked yes)
			(layer "B.Fab")
			(hide yes)
			(effects
				(font
					(size 1.016 1.016)
					(thickness 0.1524)
				)
				(justify mirror)
			)
		)
		(duplicate_pad_numbers_are_jumpers no)
		(fp_poly
			(pts
				(arc
					(start 0.3556 0)
					(mid -0.3556 0)
					(end 0.3556 0)
				)
			)
			(stroke
				(width 0)
				(type default)
			)
			(fill no)
			(layer "B.CrtYd")
		)
		(fp_poly
			(pts
				(arc
					(start 0.6096 0)
					(mid -0.6096 0)
					(end 0.6096 0)
				)
			)
			(stroke
				(width 0)
				(type default)
			)
			(fill no)
			(layer "B.Fab")
		)
		(pad "1" smd circle
			(at 0 0 180)
			(size 0.7112 0.7112)
			(layers "B.Cu" "B.Mask" "B.Paste")
			(net "UART_SERCLK")
		)
	)
	(footprint ""
		(layer "B.Cu")
		(at 124.82703 -88.559132 180)
		(property "Reference" "R127"
			(at 0 0 0)
			(layer "B.SilkS")
			(hide yes)
			(effects
				(font
					(size 1.27 1.27)
				)
				(justify mirror)
			)
		)
		(property "Value" "4K7R2F-GP"
			(at -0.064008 -3.993896 180)
			(unlocked yes)
			(layer "B.Fab")
			(hide yes)
			(effects
				(font
					(size 1.016 1.016)
					(thickness 0.1524)
				)
				(justify mirror)
			)
		)
		(property "Device Type" "R402H16"
			(at -0.064008 -5.517896 180)
			(unlocked yes)
			(layer "B.Fab")
			(hide yes)
			(effects
				(font
					(size 1.016 1.016)
					(thickness 0.1524)
				)
				(justify mirror)
			)
		)
		(duplicate_pad_numbers_are_jumpers no)
		(fp_line
			(start 0.508 -0.9398)
			(end 0.508 0.9398)
			(stroke
				(width 0.1524)
				(type default)
			)
			(layer "B.SilkS")
		)
		(fp_line
			(start -0.508 -0.9398)
			(end 0.508 -0.9398)
			(stroke
				(width 0.1524)
				(type default)
			)
			(layer "B.SilkS")
		)
		(fp_rect
			(start 0.508 0.9398)
			(end -0.508 -0.9398)
			(stroke
				(width 0)
				(type default)
			)
			(fill no)
			(layer "B.CrtYd")
		)
		(fp_rect
			(start 0.508 0.9398)
			(end -0.508 -0.9398)
			(stroke
				(width 0)
				(type default)
			)
			(fill no)
			(layer "B.Fab")
		)
		(pad "1" smd custom
			(at 0 -0.4445)
			(size 0.1397 0.1397)
			(layers "B.Cu" "B.Mask" "B.Paste")
			(net "USB_DIR")
			(options
				(clearance outline)
				(anchor circle)
			)
			(primitives
				(gr_poly
					(pts
						(arc
							(start -0.1778 0.2794)
							(mid -0.249642 0.249642)
							(end -0.2794 0.1778)
						)
						(arc
							(start -0.2794 -0.1778)
							(mid -0.249642 -0.249642)
							(end -0.1778 -0.2794)
						)
						(arc
							(start 0.1778 -0.2794)
							(mid 0.249642 -0.249642)
							(end 0.2794 -0.1778)
						)
						(arc
							(start 0.2794 0.1778)
							(mid 0.249642 0.249642)
							(end 0.1778 0.2794)
						)
					)
					(width 0)
					(fill yes)
				)
			)
		)
		(pad "2" smd custom
			(at 0 0.4445)
			(size 0.1397 0.1397)
			(layers "B.Cu" "B.Mask" "B.Paste")
			(net "GND")
			(options
				(clearance outline)
				(anchor circle)
			)
			(primitives
				(gr_poly
					(pts
						(arc
							(start -0.1778 0.2794)
							(mid -0.249642 0.249642)
							(end -0.2794 0.1778)
						)
						(arc
							(start -0.2794 -0.1778)
							(mid -0.249642 -0.249642)
							(end -0.1778 -0.2794)
						)
						(arc
							(start 0.1778 -0.2794)
							(mid 0.249642 -0.249642)
							(end 0.2794 -0.1778)
						)
						(arc
							(start 0.2794 0.1778)
							(mid 0.249642 0.249642)
							(end 0.1778 0.2794)
						)
					)
					(width 0)
					(fill yes)
				)
			)
		)
	)
	(footprint ""
		(layer "B.Cu")
		(at 116.713 -66.3575)
		(property "Reference" "C167"
			(at 0 0 0)
			(layer "B.SilkS")
			(hide yes)
			(effects
				(font
					(size 1.27 1.27)
				)
				(justify mirror)
			)
		)
		(property "Value" "SCD1U6D3V1KX-GP"
			(at 2.8321 -1.7399 0)
			(unlocked yes)
			(layer "B.Fab")
			(hide yes)
			(effects
				(font
					(size 1.016 1.016)
					(thickness 0.1524)
				)
				(justify mirror)
			)
		)
		(property "Device Type" "C0201H13"
			(at 2.8321 -3.2639 0)
			(unlocked yes)
			(layer "B.Fab")
			(hide yes)
			(effects
				(font
					(size 1.016 1.016)
					(thickness 0.1524)
				)
				(justify mirror)
			)
		)
		(duplicate_pad_numbers_are_jumpers no)
		(fp_rect
			(start 0.2794 0.6477)
			(end -0.2794 -0.6477)
			(stroke
				(width 0)
				(type default)
			)
			(fill no)
			(layer "B.CrtYd")
		)
		(fp_rect
			(start 0.2794 0.6477)
			(end -0.2794 -0.6477)
			(stroke
				(width 0)
				(type default)
			)
			(fill no)
			(layer "B.Fab")
		)
		(pad "1" smd custom
			(at 0 -0.2794 180)
			(size 0.0762 0.0762)
			(layers "B.Cu" "B.Mask" "B.Paste")
			(net "P0V9")
			(options
				(clearance outline)
				(anchor circle)
			)
			(primitives
				(gr_poly
					(pts
						(arc
							(start 0.1524 0.127)
							(mid 0.137521 0.162921)
							(end 0.1016 0.1778)
						)
						(arc
							(start -0.1016 0.1778)
							(mid -0.137521 0.162921)
							(end -0.1524 0.127)
						)
						(arc
							(start -0.1524 -0.127)
							(mid -0.137521 -0.162921)
							(end -0.1016 -0.1778)
						)
						(arc
							(start 0.1016 -0.1778)
							(mid 0.137521 -0.162921)
							(end 0.1524 -0.127)
						)
					)
					(width 0)
					(fill yes)
				)
			)
		)
		(pad "2" smd custom
			(at 0 0.2794 180)
			(size 0.0762 0.0762)
			(layers "B.Cu" "B.Mask" "B.Paste")
			(net "GND")
			(options
				(clearance outline)
				(anchor circle)
			)
			(primitives
				(gr_poly
					(pts
						(arc
							(start 0.1524 0.127)
							(mid 0.137521 0.162921)
							(end 0.1016 0.1778)
						)
						(arc
							(start -0.1016 0.1778)
							(mid -0.137521 0.162921)
							(end -0.1524 0.127)
						)
						(arc
							(start -0.1524 -0.127)
							(mid -0.137521 -0.162921)
							(end -0.1016 -0.1778)
						)
						(arc
							(start 0.1016 -0.1778)
							(mid 0.137521 -0.162921)
							(end 0.1524 -0.127)
						)
					)
					(width 0)
					(fill yes)
				)
			)
		)
	)
	(footprint ""
		(layer "B.Cu")
		(at 181.051454 -49.597818 -90)
		(property "Reference" "C482"
			(at 0 0 90)
			(layer "B.SilkS")
			(hide yes)
			(effects
				(font
					(size 1.27 1.27)
				)
				(justify mirror)
			)
		)
		(property "Value" "SC1U16V2KX-7-GP"
			(at -1.7526 -1.6002 270)
			(unlocked yes)
			(layer "B.Fab")
			(hide yes)
			(effects
				(font
					(size 1.016 1.016)
					(thickness 0.1524)
				)
				(justify mirror)
			)
		)
		(property "Device Type" "C402-TO0D2H24"
			(at -1.7526 -3.1242 270)
			(unlocked yes)
			(layer "B.Fab")
			(hide yes)
			(effects
				(font
					(size 1.016 1.016)
					(thickness 0.1524)
				)
				(justify mirror)
			)
		)
		(duplicate_pad_numbers_are_jumpers no)
		(fp_rect
			(start 0.4826 0.889)
			(end -0.4826 -0.889)
			(stroke
				(width 0)
				(type default)
			)
			(fill no)
			(layer "B.CrtYd")
		)
		(fp_rect
			(start 0.4826 0.889)
			(end -0.4826 -0.889)
			(stroke
				(width 0)
				(type default)
			)
			(fill no)
			(layer "B.Fab")
		)
		(pad "1" smd custom
			(at 0 -0.4572 90)
			(size 0.1524 0.1524)
			(layers "B.Cu" "B.Mask" "B.Paste")
			(net "P1V8_C")
			(options
				(clearance outline)
				(anchor circle)
			)
			(primitives
				(gr_poly
					(pts
						(arc
							(start -0.254 -0.3048)
							(mid -0.325842 -0.275042)
							(end -0.3556 -0.2032)
						)
						(arc
							(start -0.3556 0.2032)
							(mid -0.325842 0.275042)
							(end -0.254 0.3048)
						)
						(arc
							(start 0.254 0.3048)
							(mid 0.325842 0.275042)
							(end 0.3556 0.2032)
						)
						(arc
							(start 0.3556 -0.2032)
							(mid 0.325842 -0.275042)
							(end 0.254 -0.3048)
						)
					)
					(width 0)
					(fill yes)
				)
			)
		)
		(pad "2" smd custom
			(at 0 0.4572 90)
			(size 0.1524 0.1524)
			(layers "B.Cu" "B.Mask" "B.Paste")
			(net "GND")
			(options
				(clearance outline)
				(anchor circle)
			)
			(primitives
				(gr_poly
					(pts
						(arc
							(start -0.254 -0.3048)
							(mid -0.325842 -0.275042)
							(end -0.3556 -0.2032)
						)
						(arc
							(start -0.3556 0.2032)
							(mid -0.325842 0.275042)
							(end -0.254 0.3048)
						)
						(arc
							(start 0.254 0.3048)
							(mid 0.325842 0.275042)
							(end 0.3556 0.2032)
						)
						(arc
							(start 0.3556 -0.2032)
							(mid 0.325842 -0.275042)
							(end 0.254 -0.3048)
						)
					)
					(width 0)
					(fill yes)
				)
			)
		)
	)
	(footprint ""
		(layer "B.Cu")
		(at 175.039528 -50.31613 180)
		(property "Reference" "C496"
			(at 0 0 0)
			(layer "B.SilkS")
			(hide yes)
			(effects
				(font
					(size 1.27 1.27)
				)
				(justify mirror)
			)
		)
		(property "Value" "SC1KP50V2KX-1GP"
			(at -1.1811 -2.7051 180)
			(unlocked yes)
			(layer "B.Fab")
			(hide yes)
			(effects
				(font
					(size 1.016 1.016)
					(thickness 0.1524)
				)
				(justify mirror)
			)
		)
		(property "Device Type" "C402H22"
			(at -1.1811 -4.2291 180)
			(unlocked yes)
			(layer "B.Fab")
			(hide yes)
			(effects
				(font
					(size 1.016 1.016)
					(thickness 0.1524)
				)
				(justify mirror)
			)
		)
		(duplicate_pad_numbers_are_jumpers no)
		(fp_rect
			(start 0.4318 0.9525)
			(end -0.4318 -0.9525)
			(stroke
				(width 0)
				(type default)
			)
			(fill no)
			(layer "B.CrtYd")
		)
		(fp_rect
			(start 0.4318 0.9525)
			(end -0.4318 -0.9525)
			(stroke
				(width 0)
				(type default)
			)
			(fill no)
			(layer "B.Fab")
		)
		(pad "1" smd custom
			(at 0 -0.4445)
			(size 0.1524 0.1524)
			(layers "B.Cu" "B.Mask" "B.Paste")
			(net "P1V8_C")
			(options
				(clearance outline)
				(anchor circle)
			)
			(primitives
				(gr_poly
					(pts
						(arc
							(start 0.3048 0.2032)
							(mid 0.275042 0.275042)
							(end 0.2032 0.3048)
						)
						(arc
							(start -0.2032 0.3048)
							(mid -0.275042 0.275042)
							(end -0.3048 0.2032)
						)
						(arc
							(start -0.3048 -0.2032)
							(mid -0.275042 -0.275042)
							(end -0.2032 -0.3048)
						)
						(arc
							(start 0.2032 -0.3048)
							(mid 0.275042 -0.275042)
							(end 0.3048 -0.2032)
						)
					)
					(width 0)
					(fill yes)
				)
			)
		)
		(pad "2" smd custom
			(at 0 0.4445)
			(size 0.1524 0.1524)
			(layers "B.Cu" "B.Mask" "B.Paste")
			(net "GND")
			(options
				(clearance outline)
				(anchor circle)
			)
			(primitives
				(gr_poly
					(pts
						(arc
							(start 0.3048 0.2032)
							(mid 0.275042 0.275042)
							(end 0.2032 0.3048)
						)
						(arc
							(start -0.2032 0.3048)
							(mid -0.275042 0.275042)
							(end -0.3048 0.2032)
						)
						(arc
							(start -0.3048 -0.2032)
							(mid -0.275042 -0.275042)
							(end -0.2032 -0.3048)
						)
						(arc
							(start 0.2032 -0.3048)
							(mid 0.275042 -0.275042)
							(end 0.3048 -0.2032)
						)
					)
					(width 0)
					(fill yes)
				)
			)
		)
	)
	(footprint ""
		(layer "B.Cu")
		(at 168.13403 -5.947156 90)
		(property "Reference" "C505"
			(at 0 0 90)
			(layer "B.SilkS")
			(hide yes)
			(effects
				(font
					(size 1.27 1.27)
				)
				(justify mirror)
			)
		)
		(property "Value" "SCD1U16V2KX-3GP"
			(at -1.1811 -2.7051 90)
			(unlocked yes)
			(layer "B.Fab")
			(hide yes)
			(effects
				(font
					(size 1.016 1.016)
					(thickness 0.1524)
				)
				(justify mirror)
			)
		)
		(property "Device Type" "C402H22"
			(at -1.1811 -4.2291 90)
			(unlocked yes)
			(layer "B.Fab")
			(hide yes)
			(effects
				(font
					(size 1.016 1.016)
					(thickness 0.1524)
				)
				(justify mirror)
			)
		)
		(duplicate_pad_numbers_are_jumpers no)
		(fp_rect
			(start 0.4318 0.9525)
			(end -0.4318 -0.9525)
			(stroke
				(width 0)
				(type default)
			)
			(fill no)
			(layer "B.CrtYd")
		)
		(fp_rect
			(start 0.4318 0.9525)
			(end -0.4318 -0.9525)
			(stroke
				(width 0)
				(type default)
			)
			(fill no)
			(layer "B.Fab")
		)
		(pad "1" smd custom
			(at 0 -0.4445 270)
			(size 0.1524 0.1524)
			(layers "B.Cu" "B.Mask" "B.Paste")
			(net "P1V8_E")
			(options
				(clearance outline)
				(anchor circle)
			)
			(primitives
				(gr_poly
					(pts
						(arc
							(start 0.3048 0.2032)
							(mid 0.275042 0.275042)
							(end 0.2032 0.3048)
						)
						(arc
							(start -0.2032 0.3048)
							(mid -0.275042 0.275042)
							(end -0.3048 0.2032)
						)
						(arc
							(start -0.3048 -0.2032)
							(mid -0.275042 -0.275042)
							(end -0.2032 -0.3048)
						)
						(arc
							(start 0.2032 -0.3048)
							(mid 0.275042 -0.275042)
							(end 0.3048 -0.2032)
						)
					)
					(width 0)
					(fill yes)
				)
			)
		)
		(pad "2" smd custom
			(at 0 0.4445 270)
			(size 0.1524 0.1524)
			(layers "B.Cu" "B.Mask" "B.Paste")
			(net "GND")
			(options
				(clearance outline)
				(anchor circle)
			)
			(primitives
				(gr_poly
					(pts
						(arc
							(start 0.3048 0.2032)
							(mid 0.275042 0.275042)
							(end 0.2032 0.3048)
						)
						(arc
							(start -0.2032 0.3048)
							(mid -0.275042 0.275042)
							(end -0.3048 0.2032)
						)
						(arc
							(start -0.3048 -0.2032)
							(mid -0.275042 -0.275042)
							(end -0.2032 -0.3048)
						)
						(arc
							(start 0.2032 -0.3048)
							(mid 0.275042 -0.275042)
							(end 0.3048 -0.2032)
						)
					)
					(width 0)
					(fill yes)
				)
			)
		)
	)
	(footprint ""
		(layer "B.Cu")
		(at 177.805842 -41.888156 90)
		(property "Reference" "C415"
			(at 0 0 90)
			(layer "B.SilkS")
			(hide yes)
			(effects
				(font
					(size 1.27 1.27)
				)
				(justify mirror)
			)
		)
		(property "Value" "SC1U6D3V1MX-GP"
			(at -1.9177 2.0193 90)
			(unlocked yes)
			(layer "B.Fab")
			(hide yes)
			(effects
				(font
					(size 1.016 1.016)
					(thickness 0.1524)
				)
				(justify mirror)
			)
		)
		(property "Device Type" "C0201H14"
			(at -1.9177 0.4953 90)
			(unlocked yes)
			(layer "B.Fab")
			(hide yes)
			(effects
				(font
					(size 1.016 1.016)
					(thickness 0.1524)
				)
				(justify mirror)
			)
		)
		(duplicate_pad_numbers_are_jumpers no)
		(fp_rect
			(start 0.1524 0.3048)
			(end -0.1524 -0.3048)
			(stroke
				(width 0)
				(type default)
			)
			(fill no)
			(layer "B.CrtYd")
		)
		(fp_poly
			(pts
				(xy 0.2794 0.6477) (xy 0.2794 -0.6477) (xy -0.2794 -0.6477) (xy -0.2794 -0.1905) (xy -0.1524 -0.1905)
				(xy -0.1524 -0.3048) (xy 0.1524 -0.3048) (xy 0.1524 0.3048) (xy -0.1524 0.3048) (xy -0.1524 -0.1778)
				(xy -0.2794 -0.1778) (xy -0.2794 0.6477)
			)
			(stroke
				(width 0)
				(type default)
			)
			(fill no)
			(layer "B.CrtYd")
		)
		(fp_rect
			(start 0.2794 0.6477)
			(end -0.2794 -0.6477)
			(stroke
				(width 0)
				(type default)
			)
			(fill no)
			(layer "B.Fab")
		)
		(pad "1" smd custom
			(at 0 -0.2794 270)
			(size 0.0762 0.0762)
			(layers "B.Cu" "B.Mask" "B.Paste")
			(net "P0V975")
			(options
				(clearance outline)
				(anchor circle)
			)
			(primitives
				(gr_poly
					(pts
						(arc
							(start 0.1524 0.127)
							(mid 0.137521 0.162921)
							(end 0.1016 0.1778)
						)
						(arc
							(start -0.1016 0.1778)
							(mid -0.137521 0.162921)
							(end -0.1524 0.127)
						)
						(arc
							(start -0.1524 -0.127)
							(mid -0.137521 -0.162921)
							(end -0.1016 -0.1778)
						)
						(arc
							(start 0.1016 -0.1778)
							(mid 0.137521 -0.162921)
							(end 0.1524 -0.127)
						)
					)
					(width 0)
					(fill yes)
				)
			)
		)
		(pad "2" smd custom
			(at 0 0.2794 270)
			(size 0.0762 0.0762)
			(layers "B.Cu" "B.Mask" "B.Paste")
			(net "GND")
			(options
				(clearance outline)
				(anchor circle)
			)
			(primitives
				(gr_poly
					(pts
						(arc
							(start 0.1524 0.127)
							(mid 0.137521 0.162921)
							(end 0.1016 0.1778)
						)
						(arc
							(start -0.1016 0.1778)
							(mid -0.137521 0.162921)
							(end -0.1524 0.127)
						)
						(arc
							(start -0.1524 -0.127)
							(mid -0.137521 -0.162921)
							(end -0.1016 -0.1778)
						)
						(arc
							(start 0.1016 -0.1778)
							(mid 0.137521 -0.162921)
							(end 0.1524 -0.127)
						)
					)
					(width 0)
					(fill yes)
				)
			)
		)
	)
	(footprint ""
		(layer "B.Cu")
		(at 131.449318 -87.260684 180)
		(property "Reference" "R36"
			(at 0 0 0)
			(layer "B.SilkS")
			(hide yes)
			(effects
				(font
					(size 1.27 1.27)
				)
				(justify mirror)
			)
		)
		(property "Value" "4K7R2F-GP"
			(at -0.064008 -3.993896 180)
			(unlocked yes)
			(layer "B.Fab")
			(hide yes)
			(effects
				(font
					(size 1.016 1.016)
					(thickness 0.1524)
				)
				(justify mirror)
			)
		)
		(property "Device Type" "R402H16"
			(at -0.064008 -5.517896 180)
			(unlocked yes)
			(layer "B.Fab")
			(hide yes)
			(effects
				(font
					(size 1.016 1.016)
					(thickness 0.1524)
				)
				(justify mirror)
			)
		)
		(duplicate_pad_numbers_are_jumpers no)
		(fp_line
			(start 0.508 -0.9398)
			(end 0.508 0.9398)
			(stroke
				(width 0.1524)
				(type default)
			)
			(layer "B.SilkS")
		)
		(fp_line
			(start -0.508 -0.9398)
			(end 0.508 -0.9398)
			(stroke
				(width 0.1524)
				(type default)
			)
			(layer "B.SilkS")
		)
		(fp_rect
			(start 0.508 0.9398)
			(end -0.508 -0.9398)
			(stroke
				(width 0)
				(type default)
			)
			(fill no)
			(layer "B.CrtYd")
		)
		(fp_rect
			(start 0.508 0.9398)
			(end -0.508 -0.9398)
			(stroke
				(width 0)
				(type default)
			)
			(fill no)
			(layer "B.Fab")
		)
		(pad "1" smd custom
			(at 0 -0.4445)
			(size 0.1397 0.1397)
			(layers "B.Cu" "B.Mask" "B.Paste")
			(net "EXP_SIO_LOAD_IN")
			(options
				(clearance outline)
				(anchor circle)
			)
			(primitives
				(gr_poly
					(pts
						(arc
							(start -0.1778 0.2794)
							(mid -0.249642 0.249642)
							(end -0.2794 0.1778)
						)
						(arc
							(start -0.2794 -0.1778)
							(mid -0.249642 -0.249642)
							(end -0.1778 -0.2794)
						)
						(arc
							(start 0.1778 -0.2794)
							(mid 0.249642 -0.249642)
							(end 0.2794 -0.1778)
						)
						(arc
							(start 0.2794 0.1778)
							(mid 0.249642 0.249642)
							(end 0.1778 0.2794)
						)
					)
					(width 0)
					(fill yes)
				)
			)
		)
		(pad "2" smd custom
			(at 0 0.4445)
			(size 0.1397 0.1397)
			(layers "B.Cu" "B.Mask" "B.Paste")
			(net "P1V8_E")
			(options
				(clearance outline)
				(anchor circle)
			)
			(primitives
				(gr_poly
					(pts
						(arc
							(start -0.1778 0.2794)
							(mid -0.249642 0.249642)
							(end -0.2794 0.1778)
						)
						(arc
							(start -0.2794 -0.1778)
							(mid -0.249642 -0.249642)
							(end -0.1778 -0.2794)
						)
						(arc
							(start 0.1778 -0.2794)
							(mid 0.249642 -0.249642)
							(end 0.2794 -0.1778)
						)
						(arc
							(start 0.2794 0.1778)
							(mid 0.249642 0.249642)
							(end 0.1778 0.2794)
						)
					)
					(width 0)
					(fill yes)
				)
			)
		)
	)
	(footprint ""
		(layer "B.Cu")
		(at 162.33648 -115.60302 180)
		(property "Reference" "R28"
			(at 0 0 0)
			(layer "B.SilkS")
			(hide yes)
			(effects
				(font
					(size 1.27 1.27)
				)
				(justify mirror)
			)
		)
		(property "Value" "2D2R3J-2-GP"
			(at 0.0254 -2.5146 180)
			(unlocked yes)
			(layer "B.Fab")
			(hide yes)
			(effects
				(font
					(size 1.016 1.016)
					(thickness 0.1524)
				)
				(justify mirror)
			)
		)
		(property "Device Type" "R603H22"
			(at 0.0254 -4.0386 180)
			(unlocked yes)
			(layer "B.Fab")
			(hide yes)
			(effects
				(font
					(size 1.016 1.016)
					(thickness 0.1524)
				)
				(justify mirror)
			)
		)
		(duplicate_pad_numbers_are_jumpers no)
		(fp_line
			(start 0.4826 0)
			(end 0.2032 0)
			(stroke
				(width 0.2032)
				(type default)
			)
			(layer "B.SilkS")
		)
		(fp_line
			(start -0.2032 0)
			(end -0.4826 0)
			(stroke
				(width 0.2032)
				(type default)
			)
			(layer "B.SilkS")
		)
		(fp_rect
			(start 0.5842 1.3335)
			(end -0.5842 -1.3335)
			(stroke
				(width 0)
				(type default)
			)
			(fill no)
			(layer "B.CrtYd")
		)
		(fp_rect
			(start 0.5842 1.3335)
			(end -0.5842 -1.3335)
			(stroke
				(width 0)
				(type default)
			)
			(fill no)
			(layer "B.Fab")
		)
		(pad "1" smd custom
			(at 0 -0.762)
			(size 0.2159 0.2159)
			(layers "B.Cu" "B.Mask" "B.Paste")
			(net "P12V_STBY_VDD_U11")
			(options
				(clearance outline)
				(anchor circle)
			)
			(primitives
				(gr_poly
					(pts
						(arc
							(start -0.3302 0.4318)
							(mid -0.402042 0.402042)
							(end -0.4318 0.3302)
						)
						(arc
							(start -0.4318 -0.3302)
							(mid -0.402042 -0.402042)
							(end -0.3302 -0.4318)
						)
						(arc
							(start 0.3302 -0.4318)
							(mid 0.402042 -0.402042)
							(end 0.4318 -0.3302)
						)
						(arc
							(start 0.4318 0.3302)
							(mid 0.402042 0.402042)
							(end 0.3302 0.4318)
						)
					)
					(width 0)
					(fill yes)
				)
			)
		)
		(pad "2" smd custom
			(at 0 0.762)
			(size 0.2159 0.2159)
			(layers "B.Cu" "B.Mask" "B.Paste")
			(net "P12V_STBY_SCC")
			(options
				(clearance outline)
				(anchor circle)
			)
			(primitives
				(gr_poly
					(pts
						(arc
							(start -0.3302 0.4318)
							(mid -0.402042 0.402042)
							(end -0.4318 0.3302)
						)
						(arc
							(start -0.4318 -0.3302)
							(mid -0.402042 -0.402042)
							(end -0.3302 -0.4318)
						)
						(arc
							(start 0.3302 -0.4318)
							(mid 0.402042 -0.402042)
							(end 0.4318 -0.3302)
						)
						(arc
							(start 0.4318 0.3302)
							(mid 0.402042 0.402042)
							(end 0.3302 0.4318)
						)
					)
					(width 0)
					(fill yes)
				)
			)
		)
	)
	(footprint ""
		(layer "B.Cu")
		(at 117.856 -86.995 180)
		(property "Reference" "R146"
			(at 0 0 0)
			(layer "B.SilkS")
			(hide yes)
			(effects
				(font
					(size 1.27 1.27)
				)
				(justify mirror)
			)
		)
		(property "Value" "4K7R2F-GP"
			(at -0.064008 -3.993896 180)
			(unlocked yes)
			(layer "B.Fab")
			(hide yes)
			(effects
				(font
					(size 1.016 1.016)
					(thickness 0.1524)
				)
				(justify mirror)
			)
		)
		(property "Device Type" "R402H16"
			(at -0.064008 -5.517896 180)
			(unlocked yes)
			(layer "B.Fab")
			(hide yes)
			(effects
				(font
					(size 1.016 1.016)
					(thickness 0.1524)
				)
				(justify mirror)
			)
		)
		(duplicate_pad_numbers_are_jumpers no)
		(fp_line
			(start 0.508 -0.9398)
			(end 0.508 0.9398)
			(stroke
				(width 0.1524)
				(type default)
			)
			(layer "B.SilkS")
		)
		(fp_line
			(start -0.508 -0.9398)
			(end 0.508 -0.9398)
			(stroke
				(width 0.1524)
				(type default)
			)
			(layer "B.SilkS")
		)
		(fp_rect
			(start 0.508 0.9398)
			(end -0.508 -0.9398)
			(stroke
				(width 0)
				(type default)
			)
			(fill no)
			(layer "B.CrtYd")
		)
		(fp_rect
			(start 0.508 0.9398)
			(end -0.508 -0.9398)
			(stroke
				(width 0)
				(type default)
			)
			(fill no)
			(layer "B.Fab")
		)
		(pad "1" smd custom
			(at 0 -0.4445)
			(size 0.1397 0.1397)
			(layers "B.Cu" "B.Mask" "B.Paste")
			(net "EXP_XM_ADDR_23")
			(options
				(clearance outline)
				(anchor circle)
			)
			(primitives
				(gr_poly
					(pts
						(arc
							(start -0.1778 0.2794)
							(mid -0.249642 0.249642)
							(end -0.2794 0.1778)
						)
						(arc
							(start -0.2794 -0.1778)
							(mid -0.249642 -0.249642)
							(end -0.1778 -0.2794)
						)
						(arc
							(start 0.1778 -0.2794)
							(mid 0.249642 -0.249642)
							(end 0.2794 -0.1778)
						)
						(arc
							(start 0.2794 0.1778)
							(mid 0.249642 0.249642)
							(end 0.1778 0.2794)
						)
					)
					(width 0)
					(fill yes)
				)
			)
		)
		(pad "2" smd custom
			(at 0 0.4445)
			(size 0.1397 0.1397)
			(layers "B.Cu" "B.Mask" "B.Paste")
			(net "GND")
			(options
				(clearance outline)
				(anchor circle)
			)
			(primitives
				(gr_poly
					(pts
						(arc
							(start -0.1778 0.2794)
							(mid -0.249642 0.249642)
							(end -0.2794 0.1778)
						)
						(arc
							(start -0.2794 -0.1778)
							(mid -0.249642 -0.249642)
							(end -0.1778 -0.2794)
						)
						(arc
							(start 0.1778 -0.2794)
							(mid 0.249642 -0.249642)
							(end 0.2794 -0.1778)
						)
						(arc
							(start 0.2794 0.1778)
							(mid 0.249642 0.249642)
							(end 0.1778 0.2794)
						)
					)
					(width 0)
					(fill yes)
				)
			)
		)
	)
	(footprint ""
		(layer "B.Cu")
		(at 100.584 -86.9696 180)
		(property "Reference" "R72"
			(at 0 0 0)
			(layer "B.SilkS")
			(hide yes)
			(effects
				(font
					(size 1.27 1.27)
				)
				(justify mirror)
			)
		)
		(property "Value" "4K7R2F-GP"
			(at -0.064008 -3.993896 180)
			(unlocked yes)
			(layer "B.Fab")
			(hide yes)
			(effects
				(font
					(size 1.016 1.016)
					(thickness 0.1524)
				)
				(justify mirror)
			)
		)
		(property "Device Type" "R402H16"
			(at -0.064008 -5.517896 180)
			(unlocked yes)
			(layer "B.Fab")
			(hide yes)
			(effects
				(font
					(size 1.016 1.016)
					(thickness 0.1524)
				)
				(justify mirror)
			)
		)
		(duplicate_pad_numbers_are_jumpers no)
		(fp_line
			(start 0.508 -0.9398)
			(end 0.508 0.9398)
			(stroke
				(width 0.1524)
				(type default)
			)
			(layer "B.SilkS")
		)
		(fp_line
			(start -0.508 -0.9398)
			(end 0.508 -0.9398)
			(stroke
				(width 0.1524)
				(type default)
			)
			(layer "B.SilkS")
		)
		(fp_rect
			(start 0.508 0.9398)
			(end -0.508 -0.9398)
			(stroke
				(width 0)
				(type default)
			)
			(fill no)
			(layer "B.CrtYd")
		)
		(fp_rect
			(start 0.508 0.9398)
			(end -0.508 -0.9398)
			(stroke
				(width 0)
				(type default)
			)
			(fill no)
			(layer "B.Fab")
		)
		(pad "1" smd custom
			(at 0 -0.4445)
			(size 0.1397 0.1397)
			(layers "B.Cu" "B.Mask" "B.Paste")
			(net "P1V8_E")
			(options
				(clearance outline)
				(anchor circle)
			)
			(primitives
				(gr_poly
					(pts
						(arc
							(start -0.1778 0.2794)
							(mid -0.249642 0.249642)
							(end -0.2794 0.1778)
						)
						(arc
							(start -0.2794 -0.1778)
							(mid -0.249642 -0.249642)
							(end -0.1778 -0.2794)
						)
						(arc
							(start 0.1778 -0.2794)
							(mid 0.249642 -0.249642)
							(end 0.2794 -0.1778)
						)
						(arc
							(start 0.2794 0.1778)
							(mid 0.249642 0.249642)
							(end 0.1778 0.2794)
						)
					)
					(width 0)
					(fill yes)
				)
			)
		)
		(pad "2" smd custom
			(at 0 0.4445)
			(size 0.1397 0.1397)
			(layers "B.Cu" "B.Mask" "B.Paste")
			(net "SCC_TYPE_0_LS")
			(options
				(clearance outline)
				(anchor circle)
			)
			(primitives
				(gr_poly
					(pts
						(arc
							(start -0.1778 0.2794)
							(mid -0.249642 0.249642)
							(end -0.2794 0.1778)
						)
						(arc
							(start -0.2794 -0.1778)
							(mid -0.249642 -0.249642)
							(end -0.1778 -0.2794)
						)
						(arc
							(start 0.1778 -0.2794)
							(mid 0.249642 -0.249642)
							(end 0.2794 -0.1778)
						)
						(arc
							(start 0.2794 0.1778)
							(mid 0.249642 0.249642)
							(end 0.1778 0.2794)
						)
					)
					(width 0)
					(fill yes)
				)
			)
		)
	)
	(footprint ""
		(layer "B.Cu")
		(at 179.451 -30.353 -90)
		(property "Reference" "C486"
			(at 0 0 90)
			(layer "B.SilkS")
			(hide yes)
			(effects
				(font
					(size 1.27 1.27)
				)
				(justify mirror)
			)
		)
		(property "Value" "SC1U16V2KX-7-GP"
			(at -1.7526 -1.6002 270)
			(unlocked yes)
			(layer "B.Fab")
			(hide yes)
			(effects
				(font
					(size 1.016 1.016)
					(thickness 0.1524)
				)
				(justify mirror)
			)
		)
		(property "Device Type" "C402-TO0D2H24"
			(at -1.7526 -3.1242 270)
			(unlocked yes)
			(layer "B.Fab")
			(hide yes)
			(effects
				(font
					(size 1.016 1.016)
					(thickness 0.1524)
				)
				(justify mirror)
			)
		)
		(duplicate_pad_numbers_are_jumpers no)
		(fp_rect
			(start 0.4826 0.889)
			(end -0.4826 -0.889)
			(stroke
				(width 0)
				(type default)
			)
			(fill no)
			(layer "B.CrtYd")
		)
		(fp_rect
			(start 0.4826 0.889)
			(end -0.4826 -0.889)
			(stroke
				(width 0)
				(type default)
			)
			(fill no)
			(layer "B.Fab")
		)
		(pad "1" smd custom
			(at 0 -0.4572 90)
			(size 0.1524 0.1524)
			(layers "B.Cu" "B.Mask" "B.Paste")
			(net "P1V8_C")
			(options
				(clearance outline)
				(anchor circle)
			)
			(primitives
				(gr_poly
					(pts
						(arc
							(start -0.254 -0.3048)
							(mid -0.325842 -0.275042)
							(end -0.3556 -0.2032)
						)
						(arc
							(start -0.3556 0.2032)
							(mid -0.325842 0.275042)
							(end -0.254 0.3048)
						)
						(arc
							(start 0.254 0.3048)
							(mid 0.325842 0.275042)
							(end 0.3556 0.2032)
						)
						(arc
							(start 0.3556 -0.2032)
							(mid 0.325842 -0.275042)
							(end 0.254 -0.3048)
						)
					)
					(width 0)
					(fill yes)
				)
			)
		)
		(pad "2" smd custom
			(at 0 0.4572 90)
			(size 0.1524 0.1524)
			(layers "B.Cu" "B.Mask" "B.Paste")
			(net "GND")
			(options
				(clearance outline)
				(anchor circle)
			)
			(primitives
				(gr_poly
					(pts
						(arc
							(start -0.254 -0.3048)
							(mid -0.325842 -0.275042)
							(end -0.3556 -0.2032)
						)
						(arc
							(start -0.3556 0.2032)
							(mid -0.325842 0.275042)
							(end -0.254 0.3048)
						)
						(arc
							(start 0.254 0.3048)
							(mid 0.325842 0.275042)
							(end 0.3556 0.2032)
						)
						(arc
							(start 0.3556 -0.2032)
							(mid 0.325842 -0.275042)
							(end 0.254 -0.3048)
						)
					)
					(width 0)
					(fill yes)
				)
			)
		)
	)
	(footprint ""
		(layer "B.Cu")
		(at 201.168 -58.674 180)
		(property "Reference" "R300"
			(at 0 0 0)
			(layer "B.SilkS")
			(hide yes)
			(effects
				(font
					(size 1.27 1.27)
				)
				(justify mirror)
			)
		)
		(property "Value" "10KR2F-2-GP"
			(at -0.064008 -3.993896 180)
			(unlocked yes)
			(layer "B.Fab")
			(hide yes)
			(effects
				(font
					(size 1.016 1.016)
					(thickness 0.1524)
				)
				(justify mirror)
			)
		)
		(property "Device Type" "R402H16"
			(at -0.064008 -5.517896 180)
			(unlocked yes)
			(layer "B.Fab")
			(hide yes)
			(effects
				(font
					(size 1.016 1.016)
					(thickness 0.1524)
				)
				(justify mirror)
			)
		)
		(duplicate_pad_numbers_are_jumpers no)
		(fp_line
			(start 0.508 -0.9398)
			(end 0.508 0.9398)
			(stroke
				(width 0.1524)
				(type default)
			)
			(layer "B.SilkS")
		)
		(fp_line
			(start -0.508 -0.9398)
			(end 0.508 -0.9398)
			(stroke
				(width 0.1524)
				(type default)
			)
			(layer "B.SilkS")
		)
		(fp_rect
			(start 0.508 0.9398)
			(end -0.508 -0.9398)
			(stroke
				(width 0)
				(type default)
			)
			(fill no)
			(layer "B.CrtYd")
		)
		(fp_rect
			(start 0.508 0.9398)
			(end -0.508 -0.9398)
			(stroke
				(width 0)
				(type default)
			)
			(fill no)
			(layer "B.Fab")
		)
		(pad "1" smd custom
			(at 0 -0.4445)
			(size 0.1397 0.1397)
			(layers "B.Cu" "B.Mask" "B.Paste")
			(net "P1V8_C")
			(options
				(clearance outline)
				(anchor circle)
			)
			(primitives
				(gr_poly
					(pts
						(arc
							(start -0.1778 0.2794)
							(mid -0.249642 0.249642)
							(end -0.2794 0.1778)
						)
						(arc
							(start -0.2794 -0.1778)
							(mid -0.249642 -0.249642)
							(end -0.1778 -0.2794)
						)
						(arc
							(start 0.1778 -0.2794)
							(mid 0.249642 -0.249642)
							(end 0.2794 -0.1778)
						)
						(arc
							(start 0.2794 0.1778)
							(mid 0.249642 0.249642)
							(end 0.1778 0.2794)
						)
					)
					(width 0)
					(fill yes)
				)
			)
		)
		(pad "2" smd custom
			(at 0 0.4445)
			(size 0.1397 0.1397)
			(layers "B.Cu" "B.Mask" "B.Paste")
			(net "IOC_BYTE_N")
			(options
				(clearance outline)
				(anchor circle)
			)
			(primitives
				(gr_poly
					(pts
						(arc
							(start -0.1778 0.2794)
							(mid -0.249642 0.249642)
							(end -0.2794 0.1778)
						)
						(arc
							(start -0.2794 -0.1778)
							(mid -0.249642 -0.249642)
							(end -0.1778 -0.2794)
						)
						(arc
							(start 0.1778 -0.2794)
							(mid 0.249642 -0.249642)
							(end 0.2794 -0.1778)
						)
						(arc
							(start 0.2794 0.1778)
							(mid 0.249642 0.249642)
							(end 0.1778 0.2794)
						)
					)
					(width 0)
					(fill yes)
				)
			)
		)
	)
	(footprint ""
		(layer "B.Cu")
		(at 163.195 -59.6138 -90)
		(property "Reference" "C369"
			(at 0 0 90)
			(layer "B.SilkS")
			(hide yes)
			(effects
				(font
					(size 1.27 1.27)
				)
				(justify mirror)
			)
		)
		(property "Value" "SC1U16V2KX-7-GP"
			(at -1.7526 -1.6002 270)
			(unlocked yes)
			(layer "B.Fab")
			(hide yes)
			(effects
				(font
					(size 1.016 1.016)
					(thickness 0.1524)
				)
				(justify mirror)
			)
		)
		(property "Device Type" "C402-TO0D2H24"
			(at -1.7526 -3.1242 270)
			(unlocked yes)
			(layer "B.Fab")
			(hide yes)
			(effects
				(font
					(size 1.016 1.016)
					(thickness 0.1524)
				)
				(justify mirror)
			)
		)
		(duplicate_pad_numbers_are_jumpers no)
		(fp_rect
			(start 0.4826 0.889)
			(end -0.4826 -0.889)
			(stroke
				(width 0)
				(type default)
			)
			(fill no)
			(layer "B.CrtYd")
		)
		(fp_rect
			(start 0.4826 0.889)
			(end -0.4826 -0.889)
			(stroke
				(width 0)
				(type default)
			)
			(fill no)
			(layer "B.Fab")
		)
		(pad "1" smd custom
			(at 0 -0.4572 90)
			(size 0.1524 0.1524)
			(layers "B.Cu" "B.Mask" "B.Paste")
			(net "VDDA_SAS_REF_CLK")
			(options
				(clearance outline)
				(anchor circle)
			)
			(primitives
				(gr_poly
					(pts
						(arc
							(start -0.254 -0.3048)
							(mid -0.325842 -0.275042)
							(end -0.3556 -0.2032)
						)
						(arc
							(start -0.3556 0.2032)
							(mid -0.325842 0.275042)
							(end -0.254 0.3048)
						)
						(arc
							(start 0.254 0.3048)
							(mid 0.325842 0.275042)
							(end 0.3556 0.2032)
						)
						(arc
							(start 0.3556 -0.2032)
							(mid 0.325842 -0.275042)
							(end 0.254 -0.3048)
						)
					)
					(width 0)
					(fill yes)
				)
			)
		)
		(pad "2" smd custom
			(at 0 0.4572 90)
			(size 0.1524 0.1524)
			(layers "B.Cu" "B.Mask" "B.Paste")
			(net "GND")
			(options
				(clearance outline)
				(anchor circle)
			)
			(primitives
				(gr_poly
					(pts
						(arc
							(start -0.254 -0.3048)
							(mid -0.325842 -0.275042)
							(end -0.3556 -0.2032)
						)
						(arc
							(start -0.3556 0.2032)
							(mid -0.325842 0.275042)
							(end -0.254 0.3048)
						)
						(arc
							(start 0.254 0.3048)
							(mid 0.325842 0.275042)
							(end 0.3556 0.2032)
						)
						(arc
							(start 0.3556 -0.2032)
							(mid 0.325842 -0.275042)
							(end 0.254 -0.3048)
						)
					)
					(width 0)
					(fill yes)
				)
			)
		)
	)
	(footprint ""
		(layer "B.Cu")
		(at 116.3574 -71.882)
		(property "Reference" "C153"
			(at 0 0 0)
			(layer "B.SilkS")
			(hide yes)
			(effects
				(font
					(size 1.27 1.27)
				)
				(justify mirror)
			)
		)
		(property "Value" "SCD1U6D3V1KX-GP"
			(at 2.8321 -1.7399 0)
			(unlocked yes)
			(layer "B.Fab")
			(hide yes)
			(effects
				(font
					(size 1.016 1.016)
					(thickness 0.1524)
				)
				(justify mirror)
			)
		)
		(property "Device Type" "C0201H13"
			(at 2.8321 -3.2639 0)
			(unlocked yes)
			(layer "B.Fab")
			(hide yes)
			(effects
				(font
					(size 1.016 1.016)
					(thickness 0.1524)
				)
				(justify mirror)
			)
		)
		(duplicate_pad_numbers_are_jumpers no)
		(fp_rect
			(start 0.2794 0.6477)
			(end -0.2794 -0.6477)
			(stroke
				(width 0)
				(type default)
			)
			(fill no)
			(layer "B.CrtYd")
		)
		(fp_rect
			(start 0.2794 0.6477)
			(end -0.2794 -0.6477)
			(stroke
				(width 0)
				(type default)
			)
			(fill no)
			(layer "B.Fab")
		)
		(pad "1" smd custom
			(at 0 -0.2794 180)
			(size 0.0762 0.0762)
			(layers "B.Cu" "B.Mask" "B.Paste")
			(net "P1V8_E")
			(options
				(clearance outline)
				(anchor circle)
			)
			(primitives
				(gr_poly
					(pts
						(arc
							(start 0.1524 0.127)
							(mid 0.137521 0.162921)
							(end 0.1016 0.1778)
						)
						(arc
							(start -0.1016 0.1778)
							(mid -0.137521 0.162921)
							(end -0.1524 0.127)
						)
						(arc
							(start -0.1524 -0.127)
							(mid -0.137521 -0.162921)
							(end -0.1016 -0.1778)
						)
						(arc
							(start 0.1016 -0.1778)
							(mid 0.137521 -0.162921)
							(end 0.1524 -0.127)
						)
					)
					(width 0)
					(fill yes)
				)
			)
		)
		(pad "2" smd custom
			(at 0 0.2794 180)
			(size 0.0762 0.0762)
			(layers "B.Cu" "B.Mask" "B.Paste")
			(net "GND")
			(options
				(clearance outline)
				(anchor circle)
			)
			(primitives
				(gr_poly
					(pts
						(arc
							(start 0.1524 0.127)
							(mid 0.137521 0.162921)
							(end 0.1016 0.1778)
						)
						(arc
							(start -0.1016 0.1778)
							(mid -0.137521 0.162921)
							(end -0.1524 0.127)
						)
						(arc
							(start -0.1524 -0.127)
							(mid -0.137521 -0.162921)
							(end -0.1016 -0.1778)
						)
						(arc
							(start 0.1016 -0.1778)
							(mid 0.137521 -0.162921)
							(end 0.1524 -0.127)
						)
					)
					(width 0)
					(fill yes)
				)
			)
		)
	)
	(footprint ""
		(layer "B.Cu")
		(at 100.457 -59.4868)
		(property "Reference" "C132"
			(at 0 0 0)
			(layer "B.SilkS")
			(hide yes)
			(effects
				(font
					(size 1.27 1.27)
				)
				(justify mirror)
			)
		)
		(property "Value" "SCD1U6D3V1KX-GP"
			(at 2.8321 -1.7399 0)
			(unlocked yes)
			(layer "B.Fab")
			(hide yes)
			(effects
				(font
					(size 1.016 1.016)
					(thickness 0.1524)
				)
				(justify mirror)
			)
		)
		(property "Device Type" "C0201H13"
			(at 2.8321 -3.2639 0)
			(unlocked yes)
			(layer "B.Fab")
			(hide yes)
			(effects
				(font
					(size 1.016 1.016)
					(thickness 0.1524)
				)
				(justify mirror)
			)
		)
		(duplicate_pad_numbers_are_jumpers no)
		(fp_rect
			(start 0.2794 0.6477)
			(end -0.2794 -0.6477)
			(stroke
				(width 0)
				(type default)
			)
			(fill no)
			(layer "B.CrtYd")
		)
		(fp_rect
			(start 0.2794 0.6477)
			(end -0.2794 -0.6477)
			(stroke
				(width 0)
				(type default)
			)
			(fill no)
			(layer "B.Fab")
		)
		(pad "1" smd custom
			(at 0 -0.2794 180)
			(size 0.0762 0.0762)
			(layers "B.Cu" "B.Mask" "B.Paste")
			(net "P1V8_E")
			(options
				(clearance outline)
				(anchor circle)
			)
			(primitives
				(gr_poly
					(pts
						(arc
							(start 0.1524 0.127)
							(mid 0.137521 0.162921)
							(end 0.1016 0.1778)
						)
						(arc
							(start -0.1016 0.1778)
							(mid -0.137521 0.162921)
							(end -0.1524 0.127)
						)
						(arc
							(start -0.1524 -0.127)
							(mid -0.137521 -0.162921)
							(end -0.1016 -0.1778)
						)
						(arc
							(start 0.1016 -0.1778)
							(mid 0.137521 -0.162921)
							(end 0.1524 -0.127)
						)
					)
					(width 0)
					(fill yes)
				)
			)
		)
		(pad "2" smd custom
			(at 0 0.2794 180)
			(size 0.0762 0.0762)
			(layers "B.Cu" "B.Mask" "B.Paste")
			(net "GND")
			(options
				(clearance outline)
				(anchor circle)
			)
			(primitives
				(gr_poly
					(pts
						(arc
							(start 0.1524 0.127)
							(mid 0.137521 0.162921)
							(end 0.1016 0.1778)
						)
						(arc
							(start -0.1016 0.1778)
							(mid -0.137521 0.162921)
							(end -0.1524 0.127)
						)
						(arc
							(start -0.1524 -0.127)
							(mid -0.137521 -0.162921)
							(end -0.1016 -0.1778)
						)
						(arc
							(start 0.1016 -0.1778)
							(mid 0.137521 -0.162921)
							(end 0.1524 -0.127)
						)
					)
					(width 0)
					(fill yes)
				)
			)
		)
	)
	(footprint ""
		(layer "B.Cu")
		(at 177.923952 -48.210724 -90)
		(property "Reference" "C462"
			(at 0 0 90)
			(layer "B.SilkS")
			(hide yes)
			(effects
				(font
					(size 1.27 1.27)
				)
				(justify mirror)
			)
		)
		(property "Value" "SCD1U6D3V1KX-GP"
			(at 2.8321 -1.7399 270)
			(unlocked yes)
			(layer "B.Fab")
			(hide yes)
			(effects
				(font
					(size 1.016 1.016)
					(thickness 0.1524)
				)
				(justify mirror)
			)
		)
		(property "Device Type" "C0201H13"
			(at 2.8321 -3.2639 270)
			(unlocked yes)
			(layer "B.Fab")
			(hide yes)
			(effects
				(font
					(size 1.016 1.016)
					(thickness 0.1524)
				)
				(justify mirror)
			)
		)
		(duplicate_pad_numbers_are_jumpers no)
		(fp_rect
			(start 0.2794 0.6477)
			(end -0.2794 -0.6477)
			(stroke
				(width 0)
				(type default)
			)
			(fill no)
			(layer "B.CrtYd")
		)
		(fp_rect
			(start 0.2794 0.6477)
			(end -0.2794 -0.6477)
			(stroke
				(width 0)
				(type default)
			)
			(fill no)
			(layer "B.Fab")
		)
		(pad "1" smd custom
			(at 0 -0.2794 90)
			(size 0.0762 0.0762)
			(layers "B.Cu" "B.Mask" "B.Paste")
			(net "P1V8_C")
			(options
				(clearance outline)
				(anchor circle)
			)
			(primitives
				(gr_poly
					(pts
						(arc
							(start 0.1524 0.127)
							(mid 0.137521 0.162921)
							(end 0.1016 0.1778)
						)
						(arc
							(start -0.1016 0.1778)
							(mid -0.137521 0.162921)
							(end -0.1524 0.127)
						)
						(arc
							(start -0.1524 -0.127)
							(mid -0.137521 -0.162921)
							(end -0.1016 -0.1778)
						)
						(arc
							(start 0.1016 -0.1778)
							(mid 0.137521 -0.162921)
							(end 0.1524 -0.127)
						)
					)
					(width 0)
					(fill yes)
				)
			)
		)
		(pad "2" smd custom
			(at 0 0.2794 90)
			(size 0.0762 0.0762)
			(layers "B.Cu" "B.Mask" "B.Paste")
			(net "GND")
			(options
				(clearance outline)
				(anchor circle)
			)
			(primitives
				(gr_poly
					(pts
						(arc
							(start 0.1524 0.127)
							(mid 0.137521 0.162921)
							(end 0.1016 0.1778)
						)
						(arc
							(start -0.1016 0.1778)
							(mid -0.137521 0.162921)
							(end -0.1524 0.127)
						)
						(arc
							(start -0.1524 -0.127)
							(mid -0.137521 -0.162921)
							(end -0.1016 -0.1778)
						)
						(arc
							(start 0.1016 -0.1778)
							(mid 0.137521 -0.162921)
							(end 0.1524 -0.127)
						)
					)
					(width 0)
					(fill yes)
				)
			)
		)
	)
	(footprint ""
		(layer "B.Cu")
		(at 145.372582 -121.027952 90)
		(property "Reference" "R4"
			(at 0 0 90)
			(layer "B.SilkS")
			(hide yes)
			(effects
				(font
					(size 1.27 1.27)
				)
				(justify mirror)
			)
		)
		(property "Value" "4K53R2F-1-GP"
			(at -0.064008 -3.993896 90)
			(unlocked yes)
			(layer "B.Fab")
			(hide yes)
			(effects
				(font
					(size 1.016 1.016)
					(thickness 0.1524)
				)
				(justify mirror)
			)
		)
		(property "Device Type" "R402H16"
			(at -0.064008 -5.517896 90)
			(unlocked yes)
			(layer "B.Fab")
			(hide yes)
			(effects
				(font
					(size 1.016 1.016)
					(thickness 0.1524)
				)
				(justify mirror)
			)
		)
		(duplicate_pad_numbers_are_jumpers no)
		(fp_line
			(start 0.508 -0.9398)
			(end 0.508 0.9398)
			(stroke
				(width 0.1524)
				(type default)
			)
			(layer "B.SilkS")
		)
		(fp_line
			(start -0.508 -0.9398)
			(end 0.508 -0.9398)
			(stroke
				(width 0.1524)
				(type default)
			)
			(layer "B.SilkS")
		)
		(fp_rect
			(start 0.508 0.9398)
			(end -0.508 -0.9398)
			(stroke
				(width 0)
				(type default)
			)
			(fill no)
			(layer "B.CrtYd")
		)
		(fp_rect
			(start 0.508 0.9398)
			(end -0.508 -0.9398)
			(stroke
				(width 0)
				(type default)
			)
			(fill no)
			(layer "B.Fab")
		)
		(pad "1" smd custom
			(at 0 -0.4445 270)
			(size 0.1397 0.1397)
			(layers "B.Cu" "B.Mask" "B.Paste")
			(net "P1V8_C_PG_G")
			(options
				(clearance outline)
				(anchor circle)
			)
			(primitives
				(gr_poly
					(pts
						(arc
							(start -0.1778 0.2794)
							(mid -0.249642 0.249642)
							(end -0.2794 0.1778)
						)
						(arc
							(start -0.2794 -0.1778)
							(mid -0.249642 -0.249642)
							(end -0.1778 -0.2794)
						)
						(arc
							(start 0.1778 -0.2794)
							(mid 0.249642 -0.249642)
							(end 0.2794 -0.1778)
						)
						(arc
							(start 0.2794 0.1778)
							(mid 0.249642 0.249642)
							(end 0.1778 0.2794)
						)
					)
					(width 0)
					(fill yes)
				)
			)
		)
		(pad "2" smd custom
			(at 0 0.4445 270)
			(size 0.1397 0.1397)
			(layers "B.Cu" "B.Mask" "B.Paste")
			(net "P3V3")
			(options
				(clearance outline)
				(anchor circle)
			)
			(primitives
				(gr_poly
					(pts
						(arc
							(start -0.1778 0.2794)
							(mid -0.249642 0.249642)
							(end -0.2794 0.1778)
						)
						(arc
							(start -0.2794 -0.1778)
							(mid -0.249642 -0.249642)
							(end -0.1778 -0.2794)
						)
						(arc
							(start 0.1778 -0.2794)
							(mid 0.249642 -0.249642)
							(end 0.2794 -0.1778)
						)
						(arc
							(start 0.2794 0.1778)
							(mid 0.249642 0.249642)
							(end 0.1778 0.2794)
						)
					)
					(width 0)
					(fill yes)
				)
			)
		)
	)
	(footprint ""
		(layer "B.Cu")
		(at 111.379 -59.4487)
		(property "Reference" "C539"
			(at 0 0 0)
			(layer "B.SilkS")
			(hide yes)
			(effects
				(font
					(size 1.27 1.27)
				)
				(justify mirror)
			)
		)
		(property "Value" "SCD1U6D3V1KX-GP"
			(at 2.8321 -1.7399 0)
			(unlocked yes)
			(layer "B.Fab")
			(hide yes)
			(effects
				(font
					(size 1.016 1.016)
					(thickness 0.1524)
				)
				(justify mirror)
			)
		)
		(property "Device Type" "C0201H13"
			(at 2.8321 -3.2639 0)
			(unlocked yes)
			(layer "B.Fab")
			(hide yes)
			(effects
				(font
					(size 1.016 1.016)
					(thickness 0.1524)
				)
				(justify mirror)
			)
		)
		(duplicate_pad_numbers_are_jumpers no)
		(fp_rect
			(start 0.2794 0.6477)
			(end -0.2794 -0.6477)
			(stroke
				(width 0)
				(type default)
			)
			(fill no)
			(layer "B.CrtYd")
		)
		(fp_rect
			(start 0.2794 0.6477)
			(end -0.2794 -0.6477)
			(stroke
				(width 0)
				(type default)
			)
			(fill no)
			(layer "B.Fab")
		)
		(pad "1" smd custom
			(at 0 -0.2794 180)
			(size 0.0762 0.0762)
			(layers "B.Cu" "B.Mask" "B.Paste")
			(net "GB_VDDA")
			(options
				(clearance outline)
				(anchor circle)
			)
			(primitives
				(gr_poly
					(pts
						(arc
							(start 0.1524 0.127)
							(mid 0.137521 0.162921)
							(end 0.1016 0.1778)
						)
						(arc
							(start -0.1016 0.1778)
							(mid -0.137521 0.162921)
							(end -0.1524 0.127)
						)
						(arc
							(start -0.1524 -0.127)
							(mid -0.137521 -0.162921)
							(end -0.1016 -0.1778)
						)
						(arc
							(start 0.1016 -0.1778)
							(mid 0.137521 -0.162921)
							(end 0.1524 -0.127)
						)
					)
					(width 0)
					(fill yes)
				)
			)
		)
		(pad "2" smd custom
			(at 0 0.2794 180)
			(size 0.0762 0.0762)
			(layers "B.Cu" "B.Mask" "B.Paste")
			(net "GND")
			(options
				(clearance outline)
				(anchor circle)
			)
			(primitives
				(gr_poly
					(pts
						(arc
							(start 0.1524 0.127)
							(mid 0.137521 0.162921)
							(end 0.1016 0.1778)
						)
						(arc
							(start -0.1016 0.1778)
							(mid -0.137521 0.162921)
							(end -0.1524 0.127)
						)
						(arc
							(start -0.1524 -0.127)
							(mid -0.137521 -0.162921)
							(end -0.1016 -0.1778)
						)
						(arc
							(start 0.1016 -0.1778)
							(mid 0.137521 -0.162921)
							(end 0.1524 -0.127)
						)
					)
					(width 0)
					(fill yes)
				)
			)
		)
	)
	(footprint ""
		(layer "B.Cu")
		(at 127.0508 -49.4792 90)
		(property "Reference" "R115"
			(at 0 0 90)
			(layer "B.SilkS")
			(hide yes)
			(effects
				(font
					(size 1.27 1.27)
				)
				(justify mirror)
			)
		)
		(property "Value" "3K01R2F-3-GP"
			(at -0.064008 -3.993896 90)
			(unlocked yes)
			(layer "B.Fab")
			(hide yes)
			(effects
				(font
					(size 1.016 1.016)
					(thickness 0.1524)
				)
				(justify mirror)
			)
		)
		(property "Device Type" "R402H16"
			(at -0.064008 -5.517896 90)
			(unlocked yes)
			(layer "B.Fab")
			(hide yes)
			(effects
				(font
					(size 1.016 1.016)
					(thickness 0.1524)
				)
				(justify mirror)
			)
		)
		(duplicate_pad_numbers_are_jumpers no)
		(fp_line
			(start 0.508 -0.9398)
			(end 0.508 0.9398)
			(stroke
				(width 0.1524)
				(type default)
			)
			(layer "B.SilkS")
		)
		(fp_line
			(start -0.508 -0.9398)
			(end 0.508 -0.9398)
			(stroke
				(width 0.1524)
				(type default)
			)
			(layer "B.SilkS")
		)
		(fp_rect
			(start 0.508 0.9398)
			(end -0.508 -0.9398)
			(stroke
				(width 0)
				(type default)
			)
			(fill no)
			(layer "B.CrtYd")
		)
		(fp_rect
			(start 0.508 0.9398)
			(end -0.508 -0.9398)
			(stroke
				(width 0)
				(type default)
			)
			(fill no)
			(layer "B.Fab")
		)
		(pad "1" smd custom
			(at 0 -0.4445 270)
			(size 0.1397 0.1397)
			(layers "B.Cu" "B.Mask" "B.Paste")
			(net "RTRIM_A")
			(options
				(clearance outline)
				(anchor circle)
			)
			(primitives
				(gr_poly
					(pts
						(arc
							(start -0.1778 0.2794)
							(mid -0.249642 0.249642)
							(end -0.2794 0.1778)
						)
						(arc
							(start -0.2794 -0.1778)
							(mid -0.249642 -0.249642)
							(end -0.1778 -0.2794)
						)
						(arc
							(start 0.1778 -0.2794)
							(mid 0.249642 -0.249642)
							(end 0.2794 -0.1778)
						)
						(arc
							(start 0.2794 0.1778)
							(mid 0.249642 0.249642)
							(end 0.1778 0.2794)
						)
					)
					(width 0)
					(fill yes)
				)
			)
		)
		(pad "2" smd custom
			(at 0 0.4445 270)
			(size 0.1397 0.1397)
			(layers "B.Cu" "B.Mask" "B.Paste")
			(net "RTRIM_AN")
			(options
				(clearance outline)
				(anchor circle)
			)
			(primitives
				(gr_poly
					(pts
						(arc
							(start -0.1778 0.2794)
							(mid -0.249642 0.249642)
							(end -0.2794 0.1778)
						)
						(arc
							(start -0.2794 -0.1778)
							(mid -0.249642 -0.249642)
							(end -0.1778 -0.2794)
						)
						(arc
							(start 0.1778 -0.2794)
							(mid 0.249642 -0.249642)
							(end 0.2794 -0.1778)
						)
						(arc
							(start 0.2794 0.1778)
							(mid 0.249642 0.249642)
							(end 0.1778 0.2794)
						)
					)
					(width 0)
					(fill yes)
				)
			)
		)
	)
	(footprint ""
		(layer "B.Cu")
		(at 113.665 -70.3834 180)
		(property "Reference" "C163"
			(at 0 0 0)
			(layer "B.SilkS")
			(hide yes)
			(effects
				(font
					(size 1.27 1.27)
				)
				(justify mirror)
			)
		)
		(property "Value" "SCD1U6D3V1KX-GP"
			(at 2.8321 -1.7399 180)
			(unlocked yes)
			(layer "B.Fab")
			(hide yes)
			(effects
				(font
					(size 1.016 1.016)
					(thickness 0.1524)
				)
				(justify mirror)
			)
		)
		(property "Device Type" "C0201H13"
			(at 2.8321 -3.2639 180)
			(unlocked yes)
			(layer "B.Fab")
			(hide yes)
			(effects
				(font
					(size 1.016 1.016)
					(thickness 0.1524)
				)
				(justify mirror)
			)
		)
		(duplicate_pad_numbers_are_jumpers no)
		(fp_rect
			(start 0.2794 0.6477)
			(end -0.2794 -0.6477)
			(stroke
				(width 0)
				(type default)
			)
			(fill no)
			(layer "B.CrtYd")
		)
		(fp_rect
			(start 0.2794 0.6477)
			(end -0.2794 -0.6477)
			(stroke
				(width 0)
				(type default)
			)
			(fill no)
			(layer "B.Fab")
		)
		(pad "1" smd custom
			(at 0 -0.2794)
			(size 0.0762 0.0762)
			(layers "B.Cu" "B.Mask" "B.Paste")
			(net "P0V9")
			(options
				(clearance outline)
				(anchor circle)
			)
			(primitives
				(gr_poly
					(pts
						(arc
							(start 0.1524 0.127)
							(mid 0.137521 0.162921)
							(end 0.1016 0.1778)
						)
						(arc
							(start -0.1016 0.1778)
							(mid -0.137521 0.162921)
							(end -0.1524 0.127)
						)
						(arc
							(start -0.1524 -0.127)
							(mid -0.137521 -0.162921)
							(end -0.1016 -0.1778)
						)
						(arc
							(start 0.1016 -0.1778)
							(mid 0.137521 -0.162921)
							(end 0.1524 -0.127)
						)
					)
					(width 0)
					(fill yes)
				)
			)
		)
		(pad "2" smd custom
			(at 0 0.2794)
			(size 0.0762 0.0762)
			(layers "B.Cu" "B.Mask" "B.Paste")
			(net "GND")
			(options
				(clearance outline)
				(anchor circle)
			)
			(primitives
				(gr_poly
					(pts
						(arc
							(start 0.1524 0.127)
							(mid 0.137521 0.162921)
							(end 0.1016 0.1778)
						)
						(arc
							(start -0.1016 0.1778)
							(mid -0.137521 0.162921)
							(end -0.1524 0.127)
						)
						(arc
							(start -0.1524 -0.127)
							(mid -0.137521 -0.162921)
							(end -0.1016 -0.1778)
						)
						(arc
							(start 0.1016 -0.1778)
							(mid 0.137521 -0.162921)
							(end 0.1524 -0.127)
						)
					)
					(width 0)
					(fill yes)
				)
			)
		)
	)
	(footprint ""
		(layer "B.Cu")
		(at 62.1792 -52.8574 -90)
		(property "Reference" "C684"
			(at 0 0 90)
			(layer "B.SilkS")
			(hide yes)
			(effects
				(font
					(size 1.27 1.27)
				)
				(justify mirror)
			)
		)
		(property "Value" "SC10U6D3V5KX-4GP"
			(at 0.0762 -6.1214 270)
			(unlocked yes)
			(layer "B.Fab")
			(hide yes)
			(effects
				(font
					(size 1.016 1.016)
					(thickness 0.1524)
				)
				(justify mirror)
			)
		)
		(property "Device Type" "C805H58"
			(at 0.0762 -8.1534 270)
			(unlocked yes)
			(layer "B.Fab")
			(hide yes)
			(effects
				(font
					(size 1.016 1.016)
					(thickness 0.1524)
				)
				(justify mirror)
			)
		)
		(duplicate_pad_numbers_are_jumpers no)
		(fp_line
			(start -0.635 0)
			(end 0.635 0)
			(stroke
				(width 0.508)
				(type default)
			)
			(layer "B.SilkS")
		)
		(fp_rect
			(start 0.9652 1.778)
			(end -0.9652 -1.778)
			(stroke
				(width 0)
				(type default)
			)
			(fill no)
			(layer "B.CrtYd")
		)
		(fp_poly
			(pts
				(xy 0.9652 -1.778) (xy -0.9652 -1.778) (xy -0.9652 1.778) (xy 0.9652 1.778)
			)
			(stroke
				(width 0)
				(type default)
			)
			(fill no)
			(layer "B.Fab")
		)
		(pad "1" smd rect
			(at 0 -0.9652 90)
			(size 1.397 1.143)
			(layers "B.Cu" "B.Mask" "B.Paste")
			(net "P0V9")
		)
		(pad "2" smd rect
			(at 0 0.9652 90)
			(size 1.397 1.143)
			(layers "B.Cu" "B.Mask" "B.Paste")
			(net "GND")
		)
	)
	(footprint ""
		(layer "B.Cu")
		(at 174.625 -70.739 180)
		(property "Reference" "Q8"
			(at 0 0 0)
			(layer "B.SilkS")
			(hide yes)
			(effects
				(font
					(size 1.27 1.27)
				)
				(justify mirror)
			)
		)
		(property "Value" "2N7002K-1-GP"
			(at -0.127 -8.9662 180)
			(unlocked yes)
			(layer "B.Fab")
			(hide yes)
			(effects
				(font
					(size 1.016 1.016)
					(thickness 0.1524)
				)
				(justify mirror)
			)
		)
		(property "Device Type" "SOT23DGS2D4H44"
			(at -0.127 -10.4902 180)
			(unlocked yes)
			(layer "B.Fab")
			(hide yes)
			(effects
				(font
					(size 1.016 1.016)
					(thickness 0.1524)
				)
				(justify mirror)
			)
		)
		(duplicate_pad_numbers_are_jumpers no)
		(fp_line
			(start 1.651 1.778)
			(end -1.651 1.778)
			(stroke
				(width 0.1524)
				(type default)
			)
			(layer "B.SilkS")
		)
		(fp_line
			(start 1.651 -1.778)
			(end 1.651 1.778)
			(stroke
				(width 0.1524)
				(type default)
			)
			(layer "B.SilkS")
		)
		(fp_line
			(start -1.651 1.778)
			(end -1.651 -1.778)
			(stroke
				(width 0.1524)
				(type default)
			)
			(layer "B.SilkS")
		)
		(fp_line
			(start -1.651 -1.778)
			(end 1.651 -1.778)
			(stroke
				(width 0.1524)
				(type default)
			)
			(layer "B.SilkS")
		)
		(fp_poly
			(pts
				(xy 1.778 1.8796) (xy 1.778 -1.8796) (xy -1.778 -1.8796) (xy -1.778 1.8796)
			)
			(stroke
				(width 0)
				(type default)
			)
			(fill no)
			(layer "B.CrtYd")
		)
		(fp_poly
			(pts
				(xy 1.778 1.8796) (xy 1.778 -1.8796) (xy -1.778 -1.8796) (xy -1.778 1.8796)
			)
			(stroke
				(width 0)
				(type default)
			)
			(fill no)
			(layer "B.Fab")
		)
		(pad "D" smd custom
			(at 0 -0.9525)
			(size 0.1905 0.1905)
			(layers "B.Cu" "B.Mask" "B.Paste")
			(net "SYS_RST_Q8")
			(options
				(clearance outline)
				(anchor circle)
			)
			(primitives
				(gr_poly
					(pts
						(arc
							(start -0.1778 -0.5715)
							(mid -0.321484 -0.511984)
							(end -0.381 -0.3683)
						)
						(arc
							(start -0.381 0.3683)
							(mid -0.321484 0.511984)
							(end -0.1778 0.5715)
						)
						(arc
							(start 0.1778 0.5715)
							(mid 0.321484 0.511984)
							(end 0.381 0.3683)
						)
						(arc
							(start 0.381 -0.3683)
							(mid 0.321484 -0.511984)
							(end 0.1778 -0.5715)
						)
					)
					(width 0)
					(fill yes)
				)
			)
		)
		(pad "G" smd custom
			(at 0.98425 0.9525)
			(size 0.1905 0.1905)
			(layers "B.Cu" "B.Mask" "B.Paste")
			(net "P3V3_STBY_Q15_R")
			(options
				(clearance outline)
				(anchor circle)
			)
			(primitives
				(gr_poly
					(pts
						(arc
							(start -0.1778 -0.5715)
							(mid -0.321484 -0.511984)
							(end -0.381 -0.3683)
						)
						(arc
							(start -0.381 0.3683)
							(mid -0.321484 0.511984)
							(end -0.1778 0.5715)
						)
						(arc
							(start 0.1778 0.5715)
							(mid 0.321484 0.511984)
							(end 0.381 0.3683)
						)
						(arc
							(start 0.381 -0.3683)
							(mid 0.321484 -0.511984)
							(end 0.1778 -0.5715)
						)
					)
					(width 0)
					(fill yes)
				)
			)
		)
		(pad "S" smd custom
			(at -0.98425 0.9525)
			(size 0.1905 0.1905)
			(layers "B.Cu" "B.Mask" "B.Paste")
			(net "GND")
			(options
				(clearance outline)
				(anchor circle)
			)
			(primitives
				(gr_poly
					(pts
						(arc
							(start -0.1778 -0.5715)
							(mid -0.321484 -0.511984)
							(end -0.381 -0.3683)
						)
						(arc
							(start -0.381 0.3683)
							(mid -0.321484 0.511984)
							(end -0.1778 0.5715)
						)
						(arc
							(start 0.1778 0.5715)
							(mid 0.321484 0.511984)
							(end 0.381 0.3683)
						)
						(arc
							(start 0.381 -0.3683)
							(mid 0.321484 -0.511984)
							(end 0.1778 -0.5715)
						)
					)
					(width 0)
					(fill yes)
				)
			)
		)
	)
	(footprint ""
		(layer "B.Cu")
		(at 172.122338 -42.91965 -90)
		(property "Reference" "C437"
			(at 0 0 90)
			(layer "B.SilkS")
			(hide yes)
			(effects
				(font
					(size 1.27 1.27)
				)
				(justify mirror)
			)
		)
		(property "Value" "SCD1U6D3V1KX-GP"
			(at 2.8321 -1.7399 270)
			(unlocked yes)
			(layer "B.Fab")
			(hide yes)
			(effects
				(font
					(size 1.016 1.016)
					(thickness 0.1524)
				)
				(justify mirror)
			)
		)
		(property "Device Type" "C0201H13"
			(at 2.8321 -3.2639 270)
			(unlocked yes)
			(layer "B.Fab")
			(hide yes)
			(effects
				(font
					(size 1.016 1.016)
					(thickness 0.1524)
				)
				(justify mirror)
			)
		)
		(duplicate_pad_numbers_are_jumpers no)
		(fp_rect
			(start 0.2794 0.6477)
			(end -0.2794 -0.6477)
			(stroke
				(width 0)
				(type default)
			)
			(fill no)
			(layer "B.CrtYd")
		)
		(fp_rect
			(start 0.2794 0.6477)
			(end -0.2794 -0.6477)
			(stroke
				(width 0)
				(type default)
			)
			(fill no)
			(layer "B.Fab")
		)
		(pad "1" smd custom
			(at 0 -0.2794 90)
			(size 0.0762 0.0762)
			(layers "B.Cu" "B.Mask" "B.Paste")
			(net "P0V975")
			(options
				(clearance outline)
				(anchor circle)
			)
			(primitives
				(gr_poly
					(pts
						(arc
							(start 0.1524 0.127)
							(mid 0.137521 0.162921)
							(end 0.1016 0.1778)
						)
						(arc
							(start -0.1016 0.1778)
							(mid -0.137521 0.162921)
							(end -0.1524 0.127)
						)
						(arc
							(start -0.1524 -0.127)
							(mid -0.137521 -0.162921)
							(end -0.1016 -0.1778)
						)
						(arc
							(start 0.1016 -0.1778)
							(mid 0.137521 -0.162921)
							(end 0.1524 -0.127)
						)
					)
					(width 0)
					(fill yes)
				)
			)
		)
		(pad "2" smd custom
			(at 0 0.2794 90)
			(size 0.0762 0.0762)
			(layers "B.Cu" "B.Mask" "B.Paste")
			(net "GND")
			(options
				(clearance outline)
				(anchor circle)
			)
			(primitives
				(gr_poly
					(pts
						(arc
							(start 0.1524 0.127)
							(mid 0.137521 0.162921)
							(end 0.1016 0.1778)
						)
						(arc
							(start -0.1016 0.1778)
							(mid -0.137521 0.162921)
							(end -0.1524 0.127)
						)
						(arc
							(start -0.1524 -0.127)
							(mid -0.137521 -0.162921)
							(end -0.1016 -0.1778)
						)
						(arc
							(start 0.1016 -0.1778)
							(mid 0.137521 -0.162921)
							(end 0.1524 -0.127)
						)
					)
					(width 0)
					(fill yes)
				)
			)
		)
	)
	(footprint ""
		(layer "B.Cu")
		(at 122.530108 -59.455812)
		(property "Reference" "C282"
			(at 0 0 0)
			(layer "B.SilkS")
			(hide yes)
			(effects
				(font
					(size 1.27 1.27)
				)
				(justify mirror)
			)
		)
		(property "Value" "SCD1U6D3V1KX-GP"
			(at 2.8321 -1.7399 0)
			(unlocked yes)
			(layer "B.Fab")
			(hide yes)
			(effects
				(font
					(size 1.016 1.016)
					(thickness 0.1524)
				)
				(justify mirror)
			)
		)
		(property "Device Type" "C0201H13"
			(at 2.8321 -3.2639 0)
			(unlocked yes)
			(layer "B.Fab")
			(hide yes)
			(effects
				(font
					(size 1.016 1.016)
					(thickness 0.1524)
				)
				(justify mirror)
			)
		)
		(duplicate_pad_numbers_are_jumpers no)
		(fp_rect
			(start 0.2794 0.6477)
			(end -0.2794 -0.6477)
			(stroke
				(width 0)
				(type default)
			)
			(fill no)
			(layer "B.CrtYd")
		)
		(fp_rect
			(start 0.2794 0.6477)
			(end -0.2794 -0.6477)
			(stroke
				(width 0)
				(type default)
			)
			(fill no)
			(layer "B.Fab")
		)
		(pad "1" smd custom
			(at 0 -0.2794 180)
			(size 0.0762 0.0762)
			(layers "B.Cu" "B.Mask" "B.Paste")
			(net "GB_VDDA")
			(options
				(clearance outline)
				(anchor circle)
			)
			(primitives
				(gr_poly
					(pts
						(arc
							(start 0.1524 0.127)
							(mid 0.137521 0.162921)
							(end 0.1016 0.1778)
						)
						(arc
							(start -0.1016 0.1778)
							(mid -0.137521 0.162921)
							(end -0.1524 0.127)
						)
						(arc
							(start -0.1524 -0.127)
							(mid -0.137521 -0.162921)
							(end -0.1016 -0.1778)
						)
						(arc
							(start 0.1016 -0.1778)
							(mid 0.137521 -0.162921)
							(end 0.1524 -0.127)
						)
					)
					(width 0)
					(fill yes)
				)
			)
		)
		(pad "2" smd custom
			(at 0 0.2794 180)
			(size 0.0762 0.0762)
			(layers "B.Cu" "B.Mask" "B.Paste")
			(net "GND")
			(options
				(clearance outline)
				(anchor circle)
			)
			(primitives
				(gr_poly
					(pts
						(arc
							(start 0.1524 0.127)
							(mid 0.137521 0.162921)
							(end 0.1016 0.1778)
						)
						(arc
							(start -0.1016 0.1778)
							(mid -0.137521 0.162921)
							(end -0.1524 0.127)
						)
						(arc
							(start -0.1524 -0.127)
							(mid -0.137521 -0.162921)
							(end -0.1016 -0.1778)
						)
						(arc
							(start 0.1016 -0.1778)
							(mid 0.137521 -0.162921)
							(end 0.1524 -0.127)
						)
					)
					(width 0)
					(fill yes)
				)
			)
		)
	)
	(footprint ""
		(layer "B.Cu")
		(at 108.5342 -64.516 -90)
		(property "Reference" "C157"
			(at 0 0 90)
			(layer "B.SilkS")
			(hide yes)
			(effects
				(font
					(size 1.27 1.27)
				)
				(justify mirror)
			)
		)
		(property "Value" "SCD1U6D3V1KX-GP"
			(at 2.8321 -1.7399 270)
			(unlocked yes)
			(layer "B.Fab")
			(hide yes)
			(effects
				(font
					(size 1.016 1.016)
					(thickness 0.1524)
				)
				(justify mirror)
			)
		)
		(property "Device Type" "C0201H13"
			(at 2.8321 -3.2639 270)
			(unlocked yes)
			(layer "B.Fab")
			(hide yes)
			(effects
				(font
					(size 1.016 1.016)
					(thickness 0.1524)
				)
				(justify mirror)
			)
		)
		(duplicate_pad_numbers_are_jumpers no)
		(fp_rect
			(start 0.2794 0.6477)
			(end -0.2794 -0.6477)
			(stroke
				(width 0)
				(type default)
			)
			(fill no)
			(layer "B.CrtYd")
		)
		(fp_rect
			(start 0.2794 0.6477)
			(end -0.2794 -0.6477)
			(stroke
				(width 0)
				(type default)
			)
			(fill no)
			(layer "B.Fab")
		)
		(pad "1" smd custom
			(at 0 -0.2794 90)
			(size 0.0762 0.0762)
			(layers "B.Cu" "B.Mask" "B.Paste")
			(net "P1V8_E")
			(options
				(clearance outline)
				(anchor circle)
			)
			(primitives
				(gr_poly
					(pts
						(arc
							(start 0.1524 0.127)
							(mid 0.137521 0.162921)
							(end 0.1016 0.1778)
						)
						(arc
							(start -0.1016 0.1778)
							(mid -0.137521 0.162921)
							(end -0.1524 0.127)
						)
						(arc
							(start -0.1524 -0.127)
							(mid -0.137521 -0.162921)
							(end -0.1016 -0.1778)
						)
						(arc
							(start 0.1016 -0.1778)
							(mid 0.137521 -0.162921)
							(end 0.1524 -0.127)
						)
					)
					(width 0)
					(fill yes)
				)
			)
		)
		(pad "2" smd custom
			(at 0 0.2794 90)
			(size 0.0762 0.0762)
			(layers "B.Cu" "B.Mask" "B.Paste")
			(net "GND")
			(options
				(clearance outline)
				(anchor circle)
			)
			(primitives
				(gr_poly
					(pts
						(arc
							(start 0.1524 0.127)
							(mid 0.137521 0.162921)
							(end 0.1016 0.1778)
						)
						(arc
							(start -0.1016 0.1778)
							(mid -0.137521 0.162921)
							(end -0.1524 0.127)
						)
						(arc
							(start -0.1524 -0.127)
							(mid -0.137521 -0.162921)
							(end -0.1016 -0.1778)
						)
						(arc
							(start 0.1016 -0.1778)
							(mid 0.137521 -0.162921)
							(end 0.1524 -0.127)
						)
					)
					(width 0)
					(fill yes)
				)
			)
		)
	)
	(footprint ""
		(layer "B.Cu")
		(at 173.8122 -39.9669 -90)
		(property "Reference" "C444"
			(at 0 0 90)
			(layer "B.SilkS")
			(hide yes)
			(effects
				(font
					(size 1.27 1.27)
				)
				(justify mirror)
			)
		)
		(property "Value" "SC1KP50V2KX-1GP"
			(at -1.1811 -2.7051 270)
			(unlocked yes)
			(layer "B.Fab")
			(hide yes)
			(effects
				(font
					(size 1.016 1.016)
					(thickness 0.1524)
				)
				(justify mirror)
			)
		)
		(property "Device Type" "C402H22"
			(at -1.1811 -4.2291 270)
			(unlocked yes)
			(layer "B.Fab")
			(hide yes)
			(effects
				(font
					(size 1.016 1.016)
					(thickness 0.1524)
				)
				(justify mirror)
			)
		)
		(duplicate_pad_numbers_are_jumpers no)
		(fp_rect
			(start 0.4318 0.9525)
			(end -0.4318 -0.9525)
			(stroke
				(width 0)
				(type default)
			)
			(fill no)
			(layer "B.CrtYd")
		)
		(fp_rect
			(start 0.4318 0.9525)
			(end -0.4318 -0.9525)
			(stroke
				(width 0)
				(type default)
			)
			(fill no)
			(layer "B.Fab")
		)
		(pad "1" smd custom
			(at 0 -0.4445 90)
			(size 0.1524 0.1524)
			(layers "B.Cu" "B.Mask" "B.Paste")
			(net "P0V975")
			(options
				(clearance outline)
				(anchor circle)
			)
			(primitives
				(gr_poly
					(pts
						(arc
							(start 0.3048 0.2032)
							(mid 0.275042 0.275042)
							(end 0.2032 0.3048)
						)
						(arc
							(start -0.2032 0.3048)
							(mid -0.275042 0.275042)
							(end -0.3048 0.2032)
						)
						(arc
							(start -0.3048 -0.2032)
							(mid -0.275042 -0.275042)
							(end -0.2032 -0.3048)
						)
						(arc
							(start 0.2032 -0.3048)
							(mid 0.275042 -0.275042)
							(end 0.3048 -0.2032)
						)
					)
					(width 0)
					(fill yes)
				)
			)
		)
		(pad "2" smd custom
			(at 0 0.4445 90)
			(size 0.1524 0.1524)
			(layers "B.Cu" "B.Mask" "B.Paste")
			(net "GND")
			(options
				(clearance outline)
				(anchor circle)
			)
			(primitives
				(gr_poly
					(pts
						(arc
							(start 0.3048 0.2032)
							(mid 0.275042 0.275042)
							(end 0.2032 0.3048)
						)
						(arc
							(start -0.2032 0.3048)
							(mid -0.275042 0.275042)
							(end -0.3048 0.2032)
						)
						(arc
							(start -0.3048 -0.2032)
							(mid -0.275042 -0.275042)
							(end -0.2032 -0.3048)
						)
						(arc
							(start 0.2032 -0.3048)
							(mid 0.275042 -0.275042)
							(end 0.3048 -0.2032)
						)
					)
					(width 0)
					(fill yes)
				)
			)
		)
	)
	(footprint ""
		(layer "B.Cu")
		(at 183.668416 -87.639652 90)
		(property "Reference" "C629"
			(at 0 0 90)
			(layer "B.SilkS")
			(hide yes)
			(effects
				(font
					(size 1.27 1.27)
				)
				(justify mirror)
			)
		)
		(property "Value" "SC10U6D3V5KX-4GP"
			(at 0.0762 -6.1214 90)
			(unlocked yes)
			(layer "B.Fab")
			(hide yes)
			(effects
				(font
					(size 1.016 1.016)
					(thickness 0.1524)
				)
				(justify mirror)
			)
		)
		(property "Device Type" "C805H58"
			(at 0.0762 -8.1534 90)
			(unlocked yes)
			(layer "B.Fab")
			(hide yes)
			(effects
				(font
					(size 1.016 1.016)
					(thickness 0.1524)
				)
				(justify mirror)
			)
		)
		(duplicate_pad_numbers_are_jumpers no)
		(fp_line
			(start -0.635 0)
			(end 0.635 0)
			(stroke
				(width 0.508)
				(type default)
			)
			(layer "B.SilkS")
		)
		(fp_rect
			(start 0.9652 1.778)
			(end -0.9652 -1.778)
			(stroke
				(width 0)
				(type default)
			)
			(fill no)
			(layer "B.CrtYd")
		)
		(fp_poly
			(pts
				(xy 0.9652 -1.778) (xy -0.9652 -1.778) (xy -0.9652 1.778) (xy 0.9652 1.778)
			)
			(stroke
				(width 0)
				(type default)
			)
			(fill no)
			(layer "B.Fab")
		)
		(pad "1" smd rect
			(at 0 -0.9652 270)
			(size 1.397 1.143)
			(layers "B.Cu" "B.Mask" "B.Paste")
			(net "P0V975")
		)
		(pad "2" smd rect
			(at 0 0.9652 270)
			(size 1.397 1.143)
			(layers "B.Cu" "B.Mask" "B.Paste")
			(net "GND")
		)
	)
	(footprint ""
		(layer "B.Cu")
		(at 82.622898 -70.40118)
		(property "Reference" "C515"
			(at 0 0 0)
			(layer "B.SilkS")
			(hide yes)
			(effects
				(font
					(size 1.27 1.27)
				)
				(justify mirror)
			)
		)
		(property "Value" "SCD1U16V2KX-3GP"
			(at -1.1811 -2.7051 0)
			(unlocked yes)
			(layer "B.Fab")
			(hide yes)
			(effects
				(font
					(size 1.016 1.016)
					(thickness 0.1524)
				)
				(justify mirror)
			)
		)
		(property "Device Type" "C402H22"
			(at -1.1811 -4.2291 0)
			(unlocked yes)
			(layer "B.Fab")
			(hide yes)
			(effects
				(font
					(size 1.016 1.016)
					(thickness 0.1524)
				)
				(justify mirror)
			)
		)
		(duplicate_pad_numbers_are_jumpers no)
		(fp_rect
			(start 0.4318 0.9525)
			(end -0.4318 -0.9525)
			(stroke
				(width 0)
				(type default)
			)
			(fill no)
			(layer "B.CrtYd")
		)
		(fp_rect
			(start 0.4318 0.9525)
			(end -0.4318 -0.9525)
			(stroke
				(width 0)
				(type default)
			)
			(fill no)
			(layer "B.Fab")
		)
		(pad "1" smd custom
			(at 0 -0.4445 180)
			(size 0.1524 0.1524)
			(layers "B.Cu" "B.Mask" "B.Paste")
			(net "P3V3")
			(options
				(clearance outline)
				(anchor circle)
			)
			(primitives
				(gr_poly
					(pts
						(arc
							(start 0.3048 0.2032)
							(mid 0.275042 0.275042)
							(end 0.2032 0.3048)
						)
						(arc
							(start -0.2032 0.3048)
							(mid -0.275042 0.275042)
							(end -0.3048 0.2032)
						)
						(arc
							(start -0.3048 -0.2032)
							(mid -0.275042 -0.275042)
							(end -0.2032 -0.3048)
						)
						(arc
							(start 0.2032 -0.3048)
							(mid 0.275042 -0.275042)
							(end 0.3048 -0.2032)
						)
					)
					(width 0)
					(fill yes)
				)
			)
		)
		(pad "2" smd custom
			(at 0 0.4445 180)
			(size 0.1524 0.1524)
			(layers "B.Cu" "B.Mask" "B.Paste")
			(net "GND")
			(options
				(clearance outline)
				(anchor circle)
			)
			(primitives
				(gr_poly
					(pts
						(arc
							(start 0.3048 0.2032)
							(mid 0.275042 0.275042)
							(end 0.2032 0.3048)
						)
						(arc
							(start -0.2032 0.3048)
							(mid -0.275042 0.275042)
							(end -0.3048 0.2032)
						)
						(arc
							(start -0.3048 -0.2032)
							(mid -0.275042 -0.275042)
							(end -0.2032 -0.3048)
						)
						(arc
							(start 0.2032 -0.3048)
							(mid 0.275042 -0.275042)
							(end 0.3048 -0.2032)
						)
					)
					(width 0)
					(fill yes)
				)
			)
		)
	)
	(footprint ""
		(layer "B.Cu")
		(at 192.73901 -34.641282 -90)
		(property "Reference" "R190"
			(at 0 0 90)
			(layer "B.SilkS")
			(hide yes)
			(effects
				(font
					(size 1.27 1.27)
				)
				(justify mirror)
			)
		)
		(property "Value" "2K2R2F-GP"
			(at -0.064008 -3.993896 270)
			(unlocked yes)
			(layer "B.Fab")
			(hide yes)
			(effects
				(font
					(size 1.016 1.016)
					(thickness 0.1524)
				)
				(justify mirror)
			)
		)
		(property "Device Type" "R402H16"
			(at -0.064008 -5.517896 270)
			(unlocked yes)
			(layer "B.Fab")
			(hide yes)
			(effects
				(font
					(size 1.016 1.016)
					(thickness 0.1524)
				)
				(justify mirror)
			)
		)
		(duplicate_pad_numbers_are_jumpers no)
		(fp_line
			(start -0.508 -0.9398)
			(end 0.508 -0.9398)
			(stroke
				(width 0.1524)
				(type default)
			)
			(layer "B.SilkS")
		)
		(fp_line
			(start 0.508 -0.9398)
			(end 0.508 0.9398)
			(stroke
				(width 0.1524)
				(type default)
			)
			(layer "B.SilkS")
		)
		(fp_rect
			(start 0.508 0.9398)
			(end -0.508 -0.9398)
			(stroke
				(width 0)
				(type default)
			)
			(fill no)
			(layer "B.CrtYd")
		)
		(fp_rect
			(start 0.508 0.9398)
			(end -0.508 -0.9398)
			(stroke
				(width 0)
				(type default)
			)
			(fill no)
			(layer "B.Fab")
		)
		(pad "1" smd custom
			(at 0 -0.4445 90)
			(size 0.1397 0.1397)
			(layers "B.Cu" "B.Mask" "B.Paste")
			(net "P1V8_C")
			(options
				(clearance outline)
				(anchor circle)
			)
			(primitives
				(gr_poly
					(pts
						(arc
							(start -0.1778 0.2794)
							(mid -0.249642 0.249642)
							(end -0.2794 0.1778)
						)
						(arc
							(start -0.2794 -0.1778)
							(mid -0.249642 -0.249642)
							(end -0.1778 -0.2794)
						)
						(arc
							(start 0.1778 -0.2794)
							(mid 0.249642 -0.249642)
							(end 0.2794 -0.1778)
						)
						(arc
							(start 0.2794 0.1778)
							(mid 0.249642 0.249642)
							(end 0.1778 0.2794)
						)
					)
					(width 0)
					(fill yes)
				)
			)
		)
		(pad "2" smd custom
			(at 0 0.4445 90)
			(size 0.1397 0.1397)
			(layers "B.Cu" "B.Mask" "B.Paste")
			(net "I2C_IOC_4_SCL")
			(options
				(clearance outline)
				(anchor circle)
			)
			(primitives
				(gr_poly
					(pts
						(arc
							(start -0.1778 0.2794)
							(mid -0.249642 0.249642)
							(end -0.2794 0.1778)
						)
						(arc
							(start -0.2794 -0.1778)
							(mid -0.249642 -0.249642)
							(end -0.1778 -0.2794)
						)
						(arc
							(start 0.1778 -0.2794)
							(mid 0.249642 -0.249642)
							(end 0.2794 -0.1778)
						)
						(arc
							(start 0.2794 0.1778)
							(mid 0.249642 0.249642)
							(end 0.1778 0.2794)
						)
					)
					(width 0)
					(fill yes)
				)
			)
		)
	)
	(footprint ""
		(layer "B.Cu")
		(at 203.884784 -35.3314 180)
		(property "Reference" "R209"
			(at 0 0 0)
			(layer "B.SilkS")
			(hide yes)
			(effects
				(font
					(size 1.27 1.27)
				)
				(justify mirror)
			)
		)
		(property "Value" "4K7R2F-GP"
			(at -0.064008 -3.993896 180)
			(unlocked yes)
			(layer "B.Fab")
			(hide yes)
			(effects
				(font
					(size 1.016 1.016)
					(thickness 0.1524)
				)
				(justify mirror)
			)
		)
		(property "Device Type" "R402H16"
			(at -0.064008 -5.517896 180)
			(unlocked yes)
			(layer "B.Fab")
			(hide yes)
			(effects
				(font
					(size 1.016 1.016)
					(thickness 0.1524)
				)
				(justify mirror)
			)
		)
		(duplicate_pad_numbers_are_jumpers no)
		(fp_line
			(start 0.508 -0.9398)
			(end 0.508 0.9398)
			(stroke
				(width 0.1524)
				(type default)
			)
			(layer "B.SilkS")
		)
		(fp_line
			(start -0.508 -0.9398)
			(end 0.508 -0.9398)
			(stroke
				(width 0.1524)
				(type default)
			)
			(layer "B.SilkS")
		)
		(fp_rect
			(start 0.508 0.9398)
			(end -0.508 -0.9398)
			(stroke
				(width 0)
				(type default)
			)
			(fill no)
			(layer "B.CrtYd")
		)
		(fp_rect
			(start 0.508 0.9398)
			(end -0.508 -0.9398)
			(stroke
				(width 0)
				(type default)
			)
			(fill no)
			(layer "B.Fab")
		)
		(pad "1" smd custom
			(at 0 -0.4445)
			(size 0.1397 0.1397)
			(layers "B.Cu" "B.Mask" "B.Paste")
			(net "P1V8_C")
			(options
				(clearance outline)
				(anchor circle)
			)
			(primitives
				(gr_poly
					(pts
						(arc
							(start -0.1778 0.2794)
							(mid -0.249642 0.249642)
							(end -0.2794 0.1778)
						)
						(arc
							(start -0.2794 -0.1778)
							(mid -0.249642 -0.249642)
							(end -0.1778 -0.2794)
						)
						(arc
							(start 0.1778 -0.2794)
							(mid 0.249642 -0.249642)
							(end 0.2794 -0.1778)
						)
						(arc
							(start 0.2794 0.1778)
							(mid 0.249642 0.249642)
							(end 0.1778 0.2794)
						)
					)
					(width 0)
					(fill yes)
				)
			)
		)
		(pad "2" smd custom
			(at 0 0.4445)
			(size 0.1397 0.1397)
			(layers "B.Cu" "B.Mask" "B.Paste")
			(net "IOC_EEPROM_A0")
			(options
				(clearance outline)
				(anchor circle)
			)
			(primitives
				(gr_poly
					(pts
						(arc
							(start -0.1778 0.2794)
							(mid -0.249642 0.249642)
							(end -0.2794 0.1778)
						)
						(arc
							(start -0.2794 -0.1778)
							(mid -0.249642 -0.249642)
							(end -0.1778 -0.2794)
						)
						(arc
							(start 0.1778 -0.2794)
							(mid 0.249642 -0.249642)
							(end 0.2794 -0.1778)
						)
						(arc
							(start 0.2794 0.1778)
							(mid 0.249642 0.249642)
							(end 0.1778 0.2794)
						)
					)
					(width 0)
					(fill yes)
				)
			)
		)
	)
	(footprint ""
		(layer "B.Cu")
		(at 125.001528 -75.837542 180)
		(property "Reference" "C118"
			(at 0 0 0)
			(layer "B.SilkS")
			(hide yes)
			(effects
				(font
					(size 1.27 1.27)
				)
				(justify mirror)
			)
		)
		(property "Value" "SC10U6D3V2MX-GP-U"
			(at 1.524 -1.905 180)
			(unlocked yes)
			(layer "B.Fab")
			(hide yes)
			(effects
				(font
					(size 1.016 1.016)
					(thickness 0.1524)
				)
				(justify mirror)
			)
		)
		(property "Device Type" "C402-TO0D2H28"
			(at 1.524 -3.429 180)
			(unlocked yes)
			(layer "B.Fab")
			(hide yes)
			(effects
				(font
					(size 1.016 1.016)
					(thickness 0.1524)
				)
				(justify mirror)
			)
		)
		(duplicate_pad_numbers_are_jumpers no)
		(fp_rect
			(start 0.4826 0.889)
			(end -0.4826 -0.889)
			(stroke
				(width 0)
				(type default)
			)
			(fill no)
			(layer "B.CrtYd")
		)
		(fp_rect
			(start 0.4826 0.889)
			(end -0.4826 -0.889)
			(stroke
				(width 0)
				(type default)
			)
			(fill no)
			(layer "B.Fab")
		)
		(pad "1" smd custom
			(at 0 -0.4572)
			(size 0.1524 0.1524)
			(layers "B.Cu" "B.Mask" "B.Paste")
			(net "P1V8_E")
			(options
				(clearance outline)
				(anchor circle)
			)
			(primitives
				(gr_poly
					(pts
						(arc
							(start -0.254 -0.3048)
							(mid -0.325842 -0.275042)
							(end -0.3556 -0.2032)
						)
						(arc
							(start -0.3556 0.2032)
							(mid -0.325842 0.275042)
							(end -0.254 0.3048)
						)
						(arc
							(start 0.254 0.3048)
							(mid 0.325842 0.275042)
							(end 0.3556 0.2032)
						)
						(arc
							(start 0.3556 -0.2032)
							(mid 0.325842 -0.275042)
							(end 0.254 -0.3048)
						)
					)
					(width 0)
					(fill yes)
				)
			)
		)
		(pad "2" smd custom
			(at 0 0.4572)
			(size 0.1524 0.1524)
			(layers "B.Cu" "B.Mask" "B.Paste")
			(net "GND")
			(options
				(clearance outline)
				(anchor circle)
			)
			(primitives
				(gr_poly
					(pts
						(arc
							(start -0.254 -0.3048)
							(mid -0.325842 -0.275042)
							(end -0.3556 -0.2032)
						)
						(arc
							(start -0.3556 0.2032)
							(mid -0.325842 0.275042)
							(end -0.254 0.3048)
						)
						(arc
							(start 0.254 0.3048)
							(mid 0.325842 0.275042)
							(end 0.3556 0.2032)
						)
						(arc
							(start 0.3556 -0.2032)
							(mid 0.325842 -0.275042)
							(end 0.254 -0.3048)
						)
					)
					(width 0)
					(fill yes)
				)
			)
		)
	)
	(footprint ""
		(layer "B.Cu")
		(at 202.21194 -46.8884 180)
		(property "Reference" "R193"
			(at 0 0 0)
			(layer "B.SilkS")
			(hide yes)
			(effects
				(font
					(size 1.27 1.27)
				)
				(justify mirror)
			)
		)
		(property "Value" "0R2J-2-GP"
			(at -0.064008 -3.993896 180)
			(unlocked yes)
			(layer "B.Fab")
			(hide yes)
			(effects
				(font
					(size 1.016 1.016)
					(thickness 0.1524)
				)
				(justify mirror)
			)
		)
		(property "Device Type" "R402H16"
			(at -0.064008 -5.517896 180)
			(unlocked yes)
			(layer "B.Fab")
			(hide yes)
			(effects
				(font
					(size 1.016 1.016)
					(thickness 0.1524)
				)
				(justify mirror)
			)
		)
		(duplicate_pad_numbers_are_jumpers no)
		(fp_line
			(start 0.508 -0.9398)
			(end 0.508 0.9398)
			(stroke
				(width 0.1524)
				(type default)
			)
			(layer "B.SilkS")
		)
		(fp_line
			(start -0.508 -0.9398)
			(end 0.508 -0.9398)
			(stroke
				(width 0.1524)
				(type default)
			)
			(layer "B.SilkS")
		)
		(fp_rect
			(start 0.508 0.9398)
			(end -0.508 -0.9398)
			(stroke
				(width 0)
				(type default)
			)
			(fill no)
			(layer "B.CrtYd")
		)
		(fp_rect
			(start 0.508 0.9398)
			(end -0.508 -0.9398)
			(stroke
				(width 0)
				(type default)
			)
			(fill no)
			(layer "B.Fab")
		)
		(pad "1" smd custom
			(at 0 -0.4445)
			(size 0.1397 0.1397)
			(layers "B.Cu" "B.Mask" "B.Paste")
			(net "IOC_EEPROM_WP")
			(options
				(clearance outline)
				(anchor circle)
			)
			(primitives
				(gr_poly
					(pts
						(arc
							(start -0.1778 0.2794)
							(mid -0.249642 0.249642)
							(end -0.2794 0.1778)
						)
						(arc
							(start -0.2794 -0.1778)
							(mid -0.249642 -0.249642)
							(end -0.1778 -0.2794)
						)
						(arc
							(start 0.1778 -0.2794)
							(mid 0.249642 -0.249642)
							(end 0.2794 -0.1778)
						)
						(arc
							(start 0.2794 0.1778)
							(mid 0.249642 0.249642)
							(end 0.1778 0.2794)
						)
					)
					(width 0)
					(fill yes)
				)
			)
		)
		(pad "2" smd custom
			(at 0 0.4445)
			(size 0.1397 0.1397)
			(layers "B.Cu" "B.Mask" "B.Paste")
			(net "GND")
			(options
				(clearance outline)
				(anchor circle)
			)
			(primitives
				(gr_poly
					(pts
						(arc
							(start -0.1778 0.2794)
							(mid -0.249642 0.249642)
							(end -0.2794 0.1778)
						)
						(arc
							(start -0.2794 -0.1778)
							(mid -0.249642 -0.249642)
							(end -0.1778 -0.2794)
						)
						(arc
							(start 0.1778 -0.2794)
							(mid 0.249642 -0.249642)
							(end 0.2794 -0.1778)
						)
						(arc
							(start 0.2794 0.1778)
							(mid 0.249642 0.249642)
							(end 0.1778 0.2794)
						)
					)
					(width 0)
					(fill yes)
				)
			)
		)
	)
	(footprint ""
		(layer "B.Cu")
		(at 175.739298 -67.608958 180)
		(property "Reference" "R288"
			(at 0 0 0)
			(layer "B.SilkS")
			(hide yes)
			(effects
				(font
					(size 1.27 1.27)
				)
				(justify mirror)
			)
		)
		(property "Value" "0R2J-2-GP"
			(at -0.064008 -3.993896 180)
			(unlocked yes)
			(layer "B.Fab")
			(hide yes)
			(effects
				(font
					(size 1.016 1.016)
					(thickness 0.1524)
				)
				(justify mirror)
			)
		)
		(property "Device Type" "R402H16"
			(at -0.064008 -5.517896 180)
			(unlocked yes)
			(layer "B.Fab")
			(hide yes)
			(effects
				(font
					(size 1.016 1.016)
					(thickness 0.1524)
				)
				(justify mirror)
			)
		)
		(duplicate_pad_numbers_are_jumpers no)
		(fp_line
			(start 0.508 -0.9398)
			(end 0.508 0.9398)
			(stroke
				(width 0.1524)
				(type default)
			)
			(layer "B.SilkS")
		)
		(fp_line
			(start -0.508 -0.9398)
			(end 0.508 -0.9398)
			(stroke
				(width 0.1524)
				(type default)
			)
			(layer "B.SilkS")
		)
		(fp_rect
			(start 0.508 0.9398)
			(end -0.508 -0.9398)
			(stroke
				(width 0)
				(type default)
			)
			(fill no)
			(layer "B.CrtYd")
		)
		(fp_rect
			(start 0.508 0.9398)
			(end -0.508 -0.9398)
			(stroke
				(width 0)
				(type default)
			)
			(fill no)
			(layer "B.Fab")
		)
		(pad "1" smd custom
			(at 0 -0.4445)
			(size 0.1397 0.1397)
			(layers "B.Cu" "B.Mask" "B.Paste")
			(net "IOC_VREF_SET_LS")
			(options
				(clearance outline)
				(anchor circle)
			)
			(primitives
				(gr_poly
					(pts
						(arc
							(start -0.1778 0.2794)
							(mid -0.249642 0.249642)
							(end -0.2794 0.1778)
						)
						(arc
							(start -0.2794 -0.1778)
							(mid -0.249642 -0.249642)
							(end -0.1778 -0.2794)
						)
						(arc
							(start 0.1778 -0.2794)
							(mid 0.249642 -0.249642)
							(end 0.2794 -0.1778)
						)
						(arc
							(start 0.2794 0.1778)
							(mid 0.249642 0.249642)
							(end 0.1778 0.2794)
						)
					)
					(width 0)
					(fill yes)
				)
			)
		)
		(pad "2" smd custom
			(at 0 0.4445)
			(size 0.1397 0.1397)
			(layers "B.Cu" "B.Mask" "B.Paste")
			(net "SYS_RST_Q8")
			(options
				(clearance outline)
				(anchor circle)
			)
			(primitives
				(gr_poly
					(pts
						(arc
							(start -0.1778 0.2794)
							(mid -0.249642 0.249642)
							(end -0.2794 0.1778)
						)
						(arc
							(start -0.2794 -0.1778)
							(mid -0.249642 -0.249642)
							(end -0.1778 -0.2794)
						)
						(arc
							(start 0.1778 -0.2794)
							(mid 0.249642 -0.249642)
							(end 0.2794 -0.1778)
						)
						(arc
							(start 0.2794 0.1778)
							(mid 0.249642 0.249642)
							(end 0.1778 0.2794)
						)
					)
					(width 0)
					(fill yes)
				)
			)
		)
	)
	(footprint ""
		(layer "B.Cu")
		(at 112.649 -64.4779)
		(property "Reference" "C170"
			(at 0 0 0)
			(layer "B.SilkS")
			(hide yes)
			(effects
				(font
					(size 1.27 1.27)
				)
				(justify mirror)
			)
		)
		(property "Value" "SCD1U6D3V1KX-GP"
			(at 2.8321 -1.7399 0)
			(unlocked yes)
			(layer "B.Fab")
			(hide yes)
			(effects
				(font
					(size 1.016 1.016)
					(thickness 0.1524)
				)
				(justify mirror)
			)
		)
		(property "Device Type" "C0201H13"
			(at 2.8321 -3.2639 0)
			(unlocked yes)
			(layer "B.Fab")
			(hide yes)
			(effects
				(font
					(size 1.016 1.016)
					(thickness 0.1524)
				)
				(justify mirror)
			)
		)
		(duplicate_pad_numbers_are_jumpers no)
		(fp_rect
			(start 0.2794 0.6477)
			(end -0.2794 -0.6477)
			(stroke
				(width 0)
				(type default)
			)
			(fill no)
			(layer "B.CrtYd")
		)
		(fp_rect
			(start 0.2794 0.6477)
			(end -0.2794 -0.6477)
			(stroke
				(width 0)
				(type default)
			)
			(fill no)
			(layer "B.Fab")
		)
		(pad "1" smd custom
			(at 0 -0.2794 180)
			(size 0.0762 0.0762)
			(layers "B.Cu" "B.Mask" "B.Paste")
			(net "P0V9")
			(options
				(clearance outline)
				(anchor circle)
			)
			(primitives
				(gr_poly
					(pts
						(arc
							(start 0.1524 0.127)
							(mid 0.137521 0.162921)
							(end 0.1016 0.1778)
						)
						(arc
							(start -0.1016 0.1778)
							(mid -0.137521 0.162921)
							(end -0.1524 0.127)
						)
						(arc
							(start -0.1524 -0.127)
							(mid -0.137521 -0.162921)
							(end -0.1016 -0.1778)
						)
						(arc
							(start 0.1016 -0.1778)
							(mid 0.137521 -0.162921)
							(end 0.1524 -0.127)
						)
					)
					(width 0)
					(fill yes)
				)
			)
		)
		(pad "2" smd custom
			(at 0 0.2794 180)
			(size 0.0762 0.0762)
			(layers "B.Cu" "B.Mask" "B.Paste")
			(net "GND")
			(options
				(clearance outline)
				(anchor circle)
			)
			(primitives
				(gr_poly
					(pts
						(arc
							(start 0.1524 0.127)
							(mid 0.137521 0.162921)
							(end 0.1016 0.1778)
						)
						(arc
							(start -0.1016 0.1778)
							(mid -0.137521 0.162921)
							(end -0.1524 0.127)
						)
						(arc
							(start -0.1524 -0.127)
							(mid -0.137521 -0.162921)
							(end -0.1016 -0.1778)
						)
						(arc
							(start 0.1016 -0.1778)
							(mid 0.137521 -0.162921)
							(end 0.1524 -0.127)
						)
					)
					(width 0)
					(fill yes)
				)
			)
		)
	)
	(footprint ""
		(layer "B.Cu")
		(at 120.0404 -78.8416)
		(property "Reference" "TP27"
			(at 0 0 0)
			(layer "B.SilkS")
			(hide yes)
			(effects
				(font
					(size 1.27 1.27)
				)
				(justify mirror)
			)
		)
		(property "Value" "TPAD28-2-GP"
			(at 0.0127 -1.6637 0)
			(unlocked yes)
			(layer "B.Fab")
			(hide yes)
			(effects
				(font
					(size 1.016 1.016)
					(thickness 0.1524)
				)
				(justify mirror)
			)
		)
		(property "Device Type" "TPAD28"
			(at 0.0127 -3.1877 0)
			(unlocked yes)
			(layer "B.Fab")
			(hide yes)
			(effects
				(font
					(size 1.016 1.016)
					(thickness 0.1524)
				)
				(justify mirror)
			)
		)
		(duplicate_pad_numbers_are_jumpers no)
		(fp_poly
			(pts
				(arc
					(start 0.3556 0)
					(mid -0.3556 0)
					(end 0.3556 0)
				)
			)
			(stroke
				(width 0)
				(type default)
			)
			(fill no)
			(layer "B.CrtYd")
		)
		(fp_poly
			(pts
				(arc
					(start 0.6096 0)
					(mid -0.6096 0)
					(end 0.6096 0)
				)
			)
			(stroke
				(width 0)
				(type default)
			)
			(fill no)
			(layer "B.Fab")
		)
		(pad "1" smd circle
			(at 0 0 180)
			(size 0.7112 0.7112)
			(layers "B.Cu" "B.Mask" "B.Paste")
			(net "EXP_GPIO12")
		)
	)
	(footprint ""
		(layer "B.Cu")
		(at 139.5476 -123.87326 180)
		(property "Reference" "R2"
			(at 0 0 0)
			(layer "B.SilkS")
			(hide yes)
			(effects
				(font
					(size 1.27 1.27)
				)
				(justify mirror)
			)
		)
		(property "Value" "10KR2F-2-GP"
			(at -0.064008 -3.993896 180)
			(unlocked yes)
			(layer "B.Fab")
			(hide yes)
			(effects
				(font
					(size 1.016 1.016)
					(thickness 0.1524)
				)
				(justify mirror)
			)
		)
		(property "Device Type" "R402H16"
			(at -0.064008 -5.517896 180)
			(unlocked yes)
			(layer "B.Fab")
			(hide yes)
			(effects
				(font
					(size 1.016 1.016)
					(thickness 0.1524)
				)
				(justify mirror)
			)
		)
		(duplicate_pad_numbers_are_jumpers no)
		(fp_line
			(start 0.508 -0.9398)
			(end 0.508 0.9398)
			(stroke
				(width 0.1524)
				(type default)
			)
			(layer "B.SilkS")
		)
		(fp_line
			(start -0.508 -0.9398)
			(end 0.508 -0.9398)
			(stroke
				(width 0.1524)
				(type default)
			)
			(layer "B.SilkS")
		)
		(fp_rect
			(start 0.508 0.9398)
			(end -0.508 -0.9398)
			(stroke
				(width 0)
				(type default)
			)
			(fill no)
			(layer "B.CrtYd")
		)
		(fp_rect
			(start 0.508 0.9398)
			(end -0.508 -0.9398)
			(stroke
				(width 0)
				(type default)
			)
			(fill no)
			(layer "B.Fab")
		)
		(pad "1" smd custom
			(at 0 -0.4445)
			(size 0.1397 0.1397)
			(layers "B.Cu" "B.Mask" "B.Paste")
			(net "P12V_STBY_SCC")
			(options
				(clearance outline)
				(anchor circle)
			)
			(primitives
				(gr_poly
					(pts
						(arc
							(start -0.1778 0.2794)
							(mid -0.249642 0.249642)
							(end -0.2794 0.1778)
						)
						(arc
							(start -0.2794 -0.1778)
							(mid -0.249642 -0.249642)
							(end -0.1778 -0.2794)
						)
						(arc
							(start 0.1778 -0.2794)
							(mid 0.249642 -0.249642)
							(end 0.2794 -0.1778)
						)
						(arc
							(start 0.2794 0.1778)
							(mid 0.249642 0.249642)
							(end 0.1778 0.2794)
						)
					)
					(width 0)
					(fill yes)
				)
			)
		)
		(pad "2" smd custom
			(at 0 0.4445)
			(size 0.1397 0.1397)
			(layers "B.Cu" "B.Mask" "B.Paste")
			(net "P12V_STBY_Q10_G")
			(options
				(clearance outline)
				(anchor circle)
			)
			(primitives
				(gr_poly
					(pts
						(arc
							(start -0.1778 0.2794)
							(mid -0.249642 0.249642)
							(end -0.2794 0.1778)
						)
						(arc
							(start -0.2794 -0.1778)
							(mid -0.249642 -0.249642)
							(end -0.1778 -0.2794)
						)
						(arc
							(start 0.1778 -0.2794)
							(mid 0.249642 -0.249642)
							(end 0.2794 -0.1778)
						)
						(arc
							(start 0.2794 0.1778)
							(mid 0.249642 0.249642)
							(end 0.1778 0.2794)
						)
					)
					(width 0)
					(fill yes)
				)
			)
		)
	)
	(footprint ""
		(layer "B.Cu")
		(at 62.1792 -58.6486 -90)
		(property "Reference" "C617"
			(at 0 0 90)
			(layer "B.SilkS")
			(hide yes)
			(effects
				(font
					(size 1.27 1.27)
				)
				(justify mirror)
			)
		)
		(property "Value" "SC10U6D3V5KX-4GP"
			(at 0.0762 -6.1214 270)
			(unlocked yes)
			(layer "B.Fab")
			(hide yes)
			(effects
				(font
					(size 1.016 1.016)
					(thickness 0.1524)
				)
				(justify mirror)
			)
		)
		(property "Device Type" "C805H58"
			(at 0.0762 -8.1534 270)
			(unlocked yes)
			(layer "B.Fab")
			(hide yes)
			(effects
				(font
					(size 1.016 1.016)
					(thickness 0.1524)
				)
				(justify mirror)
			)
		)
		(duplicate_pad_numbers_are_jumpers no)
		(fp_line
			(start -0.635 0)
			(end 0.635 0)
			(stroke
				(width 0.508)
				(type default)
			)
			(layer "B.SilkS")
		)
		(fp_rect
			(start 0.9652 1.778)
			(end -0.9652 -1.778)
			(stroke
				(width 0)
				(type default)
			)
			(fill no)
			(layer "B.CrtYd")
		)
		(fp_poly
			(pts
				(xy 0.9652 -1.778) (xy -0.9652 -1.778) (xy -0.9652 1.778) (xy 0.9652 1.778)
			)
			(stroke
				(width 0)
				(type default)
			)
			(fill no)
			(layer "B.Fab")
		)
		(pad "1" smd rect
			(at 0 -0.9652 90)
			(size 1.397 1.143)
			(layers "B.Cu" "B.Mask" "B.Paste")
			(net "P0V9")
		)
		(pad "2" smd rect
			(at 0 0.9652 90)
			(size 1.397 1.143)
			(layers "B.Cu" "B.Mask" "B.Paste")
			(net "GND")
		)
	)
	(footprint ""
		(layer "B.Cu")
		(at 90.1192 -82.6008)
		(property "Reference" "U23"
			(at 0 0 0)
			(layer "B.SilkS")
			(hide yes)
			(effects
				(font
					(size 1.27 1.27)
				)
				(justify mirror)
			)
		)
		(property "Value" "TPS3808G01DBVT-GP"
			(at 0.0254 -11.9634 0)
			(unlocked yes)
			(layer "B.Fab")
			(hide yes)
			(effects
				(font
					(size 1.016 1.016)
					(thickness 0.1524)
				)
				(justify mirror)
			)
		)
		(property "Device Type" "SOT-6H58"
			(at 0.0254 -13.5636 0)
			(unlocked yes)
			(layer "B.Fab")
			(hide yes)
			(effects
				(font
					(size 1.016 1.016)
					(thickness 0.1524)
				)
				(justify mirror)
			)
		)
		(duplicate_pad_numbers_are_jumpers no)
		(fp_line
			(start -1.7145 -0.5842)
			(end 1.9685 -0.5842)
			(stroke
				(width 0.1524)
				(type default)
			)
			(layer "B.SilkS")
		)
		(fp_line
			(start -1.7145 0.5842)
			(end -1.7145 -0.5842)
			(stroke
				(width 0.1524)
				(type default)
			)
			(layer "B.SilkS")
		)
		(fp_line
			(start 1.5621 0)
			(end 1.9685 0.4064)
			(stroke
				(width 0.1524)
				(type default)
			)
			(layer "B.SilkS")
		)
		(fp_line
			(start 1.9685 -0.5842)
			(end 1.9685 0.5842)
			(stroke
				(width 0.1524)
				(type default)
			)
			(layer "B.SilkS")
		)
		(fp_line
			(start 1.9685 -0.4064)
			(end 1.5621 0)
			(stroke
				(width 0.1524)
				(type default)
			)
			(layer "B.SilkS")
		)
		(fp_line
			(start 1.9685 0.5842)
			(end -1.7145 0.5842)
			(stroke
				(width 0.1524)
				(type default)
			)
			(layer "B.SilkS")
		)
		(fp_line
			(start 1.9685 0.5842)
			(end 1.9685 2.3622)
			(stroke
				(width 0.508)
				(type default)
			)
			(layer "B.SilkS")
		)
		(fp_poly
			(pts
				(xy 1.27 -0.635) (xy -1.27 -0.635) (xy -1.27 0.635) (xy 1.27 0.635)
			)
			(stroke
				(width 0)
				(type default)
			)
			(fill yes)
			(layer "B.SilkS")
		)
		(fp_rect
			(start 1.9685 2.3622)
			(end -1.9685 -2.3622)
			(stroke
				(width 0)
				(type default)
			)
			(fill no)
			(layer "B.CrtYd")
		)
		(fp_poly
			(pts
				(xy 1.9685 -2.3622) (xy -1.9685 -2.3622) (xy -1.9685 2.3622) (xy 1.9685 2.3622)
			)
			(stroke
				(width 0)
				(type default)
			)
			(fill no)
			(layer "B.Fab")
		)
		(pad "1" smd rect
			(at 0.9525 1.3462 180)
			(size 0.5842 1.016)
			(layers "B.Cu" "B.Mask" "B.Paste")
			(net "EXP_RESET_R_U23_N")
		)
		(pad "2" smd rect
			(at 0 1.3462 180)
			(size 0.5842 1.016)
			(layers "B.Cu" "B.Mask" "B.Paste")
			(net "GND")
		)
		(pad "3" smd rect
			(at -0.9525 1.3462 180)
			(size 0.5842 1.016)
			(layers "B.Cu" "B.Mask" "B.Paste")
			(net "RESET_MR#")
		)
		(pad "4" smd rect
			(at -0.9525 -1.3462 180)
			(size 0.5842 1.016)
			(layers "B.Cu" "B.Mask" "B.Paste")
			(net "RESET_CT")
		)
		(pad "5" smd rect
			(at 0 -1.3462 180)
			(size 0.5842 1.016)
			(layers "B.Cu" "B.Mask" "B.Paste")
			(net "RESET_SENSE")
		)
		(pad "6" smd rect
			(at 0.9525 -1.3462 180)
			(size 0.5842 1.016)
			(layers "B.Cu" "B.Mask" "B.Paste")
			(net "P3V3")
		)
	)
	(footprint ""
		(layer "B.Cu")
		(at 160.472374 -33.403032 180)
		(property "Reference" "C371"
			(at 0 0 0)
			(layer "B.SilkS")
			(hide yes)
			(effects
				(font
					(size 1.27 1.27)
				)
				(justify mirror)
			)
		)
		(property "Value" "SC22U6D3V3MX-9-GP-U"
			(at 0 -2.8194 180)
			(unlocked yes)
			(layer "B.Fab")
			(hide yes)
			(effects
				(font
					(size 1.016 1.016)
					(thickness 0.1524)
				)
				(justify mirror)
			)
		)
		(property "Device Type" "C603H40"
			(at 0 -4.3434 180)
			(unlocked yes)
			(layer "B.Fab")
			(hide yes)
			(effects
				(font
					(size 1.016 1.016)
					(thickness 0.1524)
				)
				(justify mirror)
			)
		)
		(duplicate_pad_numbers_are_jumpers no)
		(fp_line
			(start -0.508 0)
			(end 0.508 0)
			(stroke
				(width 0.2032)
				(type default)
			)
			(layer "B.SilkS")
		)
		(fp_rect
			(start 0.5842 1.3335)
			(end -0.5842 -1.3335)
			(stroke
				(width 0)
				(type default)
			)
			(fill no)
			(layer "B.CrtYd")
		)
		(fp_rect
			(start 0.5842 1.3335)
			(end -0.5842 -1.3335)
			(stroke
				(width 0)
				(type default)
			)
			(fill no)
			(layer "B.Fab")
		)
		(pad "1" smd custom
			(at 0 -0.762)
			(size 0.2159 0.2159)
			(layers "B.Cu" "B.Mask" "B.Paste")
			(net "SAS0_VDDH")
			(options
				(clearance outline)
				(anchor circle)
			)
			(primitives
				(gr_poly
					(pts
						(arc
							(start -0.3302 0.4318)
							(mid -0.402042 0.402042)
							(end -0.4318 0.3302)
						)
						(arc
							(start -0.4318 -0.3302)
							(mid -0.402042 -0.402042)
							(end -0.3302 -0.4318)
						)
						(arc
							(start 0.3302 -0.4318)
							(mid 0.402042 -0.402042)
							(end 0.4318 -0.3302)
						)
						(arc
							(start 0.4318 0.3302)
							(mid 0.402042 0.402042)
							(end 0.3302 0.4318)
						)
					)
					(width 0)
					(fill yes)
				)
			)
		)
		(pad "2" smd custom
			(at 0 0.762)
			(size 0.2159 0.2159)
			(layers "B.Cu" "B.Mask" "B.Paste")
			(net "GND")
			(options
				(clearance outline)
				(anchor circle)
			)
			(primitives
				(gr_poly
					(pts
						(arc
							(start -0.3302 0.4318)
							(mid -0.402042 0.402042)
							(end -0.4318 0.3302)
						)
						(arc
							(start -0.4318 -0.3302)
							(mid -0.402042 -0.402042)
							(end -0.3302 -0.4318)
						)
						(arc
							(start 0.3302 -0.4318)
							(mid 0.402042 -0.402042)
							(end 0.4318 -0.3302)
						)
						(arc
							(start 0.4318 0.3302)
							(mid 0.402042 0.402042)
							(end 0.3302 0.4318)
						)
					)
					(width 0)
					(fill yes)
				)
			)
		)
	)
	(footprint ""
		(layer "B.Cu")
		(at 167.6019 -12.319)
		(property "Reference" "R577"
			(at 0 0 0)
			(layer "B.SilkS")
			(hide yes)
			(effects
				(font
					(size 1.27 1.27)
				)
				(justify mirror)
			)
		)
		(property "Value" "10KR2F-2-GP"
			(at -0.064008 -3.993896 0)
			(unlocked yes)
			(layer "B.Fab")
			(hide yes)
			(effects
				(font
					(size 1.016 1.016)
					(thickness 0.1524)
				)
				(justify mirror)
			)
		)
		(property "Device Type" "R402H16"
			(at -0.064008 -5.517896 0)
			(unlocked yes)
			(layer "B.Fab")
			(hide yes)
			(effects
				(font
					(size 1.016 1.016)
					(thickness 0.1524)
				)
				(justify mirror)
			)
		)
		(duplicate_pad_numbers_are_jumpers no)
		(fp_line
			(start -0.508 -0.9398)
			(end 0.508 -0.9398)
			(stroke
				(width 0.1524)
				(type default)
			)
			(layer "B.SilkS")
		)
		(fp_line
			(start 0.508 -0.9398)
			(end 0.508 0.9398)
			(stroke
				(width 0.1524)
				(type default)
			)
			(layer "B.SilkS")
		)
		(fp_rect
			(start 0.508 0.9398)
			(end -0.508 -0.9398)
			(stroke
				(width 0)
				(type default)
			)
			(fill no)
			(layer "B.CrtYd")
		)
		(fp_rect
			(start 0.508 0.9398)
			(end -0.508 -0.9398)
			(stroke
				(width 0)
				(type default)
			)
			(fill no)
			(layer "B.Fab")
		)
		(pad "1" smd custom
			(at 0 -0.4445 180)
			(size 0.1397 0.1397)
			(layers "B.Cu" "B.Mask" "B.Paste")
			(net "P3V3")
			(options
				(clearance outline)
				(anchor circle)
			)
			(primitives
				(gr_poly
					(pts
						(arc
							(start -0.1778 0.2794)
							(mid -0.249642 0.249642)
							(end -0.2794 0.1778)
						)
						(arc
							(start -0.2794 -0.1778)
							(mid -0.249642 -0.249642)
							(end -0.1778 -0.2794)
						)
						(arc
							(start 0.1778 -0.2794)
							(mid 0.249642 -0.249642)
							(end 0.2794 -0.1778)
						)
						(arc
							(start 0.2794 0.1778)
							(mid 0.249642 0.249642)
							(end 0.1778 0.2794)
						)
					)
					(width 0)
					(fill yes)
				)
			)
		)
		(pad "2" smd custom
			(at 0 0.4445 180)
			(size 0.1397 0.1397)
			(layers "B.Cu" "B.Mask" "B.Paste")
			(net "U50_OE")
			(options
				(clearance outline)
				(anchor circle)
			)
			(primitives
				(gr_poly
					(pts
						(arc
							(start -0.1778 0.2794)
							(mid -0.249642 0.249642)
							(end -0.2794 0.1778)
						)
						(arc
							(start -0.2794 -0.1778)
							(mid -0.249642 -0.249642)
							(end -0.1778 -0.2794)
						)
						(arc
							(start 0.1778 -0.2794)
							(mid 0.249642 -0.249642)
							(end 0.2794 -0.1778)
						)
						(arc
							(start 0.2794 0.1778)
							(mid 0.249642 0.249642)
							(end 0.1778 0.2794)
						)
					)
					(width 0)
					(fill yes)
				)
			)
		)
	)
	(footprint ""
		(layer "B.Cu")
		(at 107.498134 -74.4982)
		(property "Reference" "TP168"
			(at 0 0 0)
			(layer "B.SilkS")
			(hide yes)
			(effects
				(font
					(size 1.27 1.27)
				)
				(justify mirror)
			)
		)
		(property "Value" "TPAD28-2-GP"
			(at 0.0127 -1.6637 0)
			(unlocked yes)
			(layer "B.Fab")
			(hide yes)
			(effects
				(font
					(size 1.016 1.016)
					(thickness 0.1524)
				)
				(justify mirror)
			)
		)
		(property "Device Type" "TPAD28"
			(at 0.0127 -3.1877 0)
			(unlocked yes)
			(layer "B.Fab")
			(hide yes)
			(effects
				(font
					(size 1.016 1.016)
					(thickness 0.1524)
				)
				(justify mirror)
			)
		)
		(duplicate_pad_numbers_are_jumpers no)
		(fp_poly
			(pts
				(arc
					(start 0.3556 0)
					(mid -0.3556 0)
					(end 0.3556 0)
				)
			)
			(stroke
				(width 0)
				(type default)
			)
			(fill no)
			(layer "B.CrtYd")
		)
		(fp_poly
			(pts
				(arc
					(start 0.6096 0)
					(mid -0.6096 0)
					(end 0.6096 0)
				)
			)
			(stroke
				(width 0)
				(type default)
			)
			(fill no)
			(layer "B.Fab")
		)
		(pad "1" smd circle
			(at 0 0 180)
			(size 0.7112 0.7112)
			(layers "B.Cu" "B.Mask" "B.Paste")
			(net "LED8")
		)
	)
	(footprint ""
		(layer "B.Cu")
		(at 112.6236 -57.4802)
		(property "Reference" "C231"
			(at 0 0 0)
			(layer "B.SilkS")
			(hide yes)
			(effects
				(font
					(size 1.27 1.27)
				)
				(justify mirror)
			)
		)
		(property "Value" "SCD1U6D3V1KX-GP"
			(at 2.8321 -1.7399 0)
			(unlocked yes)
			(layer "B.Fab")
			(hide yes)
			(effects
				(font
					(size 1.016 1.016)
					(thickness 0.1524)
				)
				(justify mirror)
			)
		)
		(property "Device Type" "C0201H13"
			(at 2.8321 -3.2639 0)
			(unlocked yes)
			(layer "B.Fab")
			(hide yes)
			(effects
				(font
					(size 1.016 1.016)
					(thickness 0.1524)
				)
				(justify mirror)
			)
		)
		(duplicate_pad_numbers_are_jumpers no)
		(fp_rect
			(start 0.2794 0.6477)
			(end -0.2794 -0.6477)
			(stroke
				(width 0)
				(type default)
			)
			(fill no)
			(layer "B.CrtYd")
		)
		(fp_rect
			(start 0.2794 0.6477)
			(end -0.2794 -0.6477)
			(stroke
				(width 0)
				(type default)
			)
			(fill no)
			(layer "B.Fab")
		)
		(pad "1" smd custom
			(at 0 -0.2794 180)
			(size 0.0762 0.0762)
			(layers "B.Cu" "B.Mask" "B.Paste")
			(net "GB_VDDA")
			(options
				(clearance outline)
				(anchor circle)
			)
			(primitives
				(gr_poly
					(pts
						(arc
							(start 0.1524 0.127)
							(mid 0.137521 0.162921)
							(end 0.1016 0.1778)
						)
						(arc
							(start -0.1016 0.1778)
							(mid -0.137521 0.162921)
							(end -0.1524 0.127)
						)
						(arc
							(start -0.1524 -0.127)
							(mid -0.137521 -0.162921)
							(end -0.1016 -0.1778)
						)
						(arc
							(start 0.1016 -0.1778)
							(mid 0.137521 -0.162921)
							(end 0.1524 -0.127)
						)
					)
					(width 0)
					(fill yes)
				)
			)
		)
		(pad "2" smd custom
			(at 0 0.2794 180)
			(size 0.0762 0.0762)
			(layers "B.Cu" "B.Mask" "B.Paste")
			(net "GND")
			(options
				(clearance outline)
				(anchor circle)
			)
			(primitives
				(gr_poly
					(pts
						(arc
							(start 0.1524 0.127)
							(mid 0.137521 0.162921)
							(end 0.1016 0.1778)
						)
						(arc
							(start -0.1016 0.1778)
							(mid -0.137521 0.162921)
							(end -0.1524 0.127)
						)
						(arc
							(start -0.1524 -0.127)
							(mid -0.137521 -0.162921)
							(end -0.1016 -0.1778)
						)
						(arc
							(start 0.1016 -0.1778)
							(mid 0.137521 -0.162921)
							(end 0.1524 -0.127)
						)
					)
					(width 0)
					(fill yes)
				)
			)
		)
	)
	(footprint ""
		(layer "B.Cu")
		(at 181.6862 -54.4576 -90)
		(property "Reference" "TP102"
			(at 0 0 90)
			(layer "B.SilkS")
			(hide yes)
			(effects
				(font
					(size 1.27 1.27)
				)
				(justify mirror)
			)
		)
		(property "Value" "TPAD28-2-GP"
			(at 0.0127 -1.6637 270)
			(unlocked yes)
			(layer "B.Fab")
			(hide yes)
			(effects
				(font
					(size 1.016 1.016)
					(thickness 0.1524)
				)
				(justify mirror)
			)
		)
		(property "Device Type" "TPAD28"
			(at 0.0127 -3.1877 270)
			(unlocked yes)
			(layer "B.Fab")
			(hide yes)
			(effects
				(font
					(size 1.016 1.016)
					(thickness 0.1524)
				)
				(justify mirror)
			)
		)
		(duplicate_pad_numbers_are_jumpers no)
		(fp_poly
			(pts
				(arc
					(start 0 -0.3556)
					(mid 0 0.3556)
					(end 0 -0.3556)
				)
			)
			(stroke
				(width 0)
				(type default)
			)
			(fill no)
			(layer "B.CrtYd")
		)
		(fp_poly
			(pts
				(arc
					(start 0 -0.6096)
					(mid 0 0.6096)
					(end 0 -0.6096)
				)
			)
			(stroke
				(width 0)
				(type default)
			)
			(fill no)
			(layer "B.Fab")
		)
		(pad "1" smd circle
			(at 0 0 90)
			(size 0.7112 0.7112)
			(layers "B.Cu" "B.Mask" "B.Paste")
			(net "XM_ADDR_0")
		)
	)
	(footprint ""
		(layer "B.Cu")
		(at 101.727 -57.5056 90)
		(property "Reference" "C194"
			(at 0 0 90)
			(layer "B.SilkS")
			(hide yes)
			(effects
				(font
					(size 1.27 1.27)
				)
				(justify mirror)
			)
		)
		(property "Value" "SC1U6D3V1MX-GP"
			(at -1.9177 2.0193 90)
			(unlocked yes)
			(layer "B.Fab")
			(hide yes)
			(effects
				(font
					(size 1.016 1.016)
					(thickness 0.1524)
				)
				(justify mirror)
			)
		)
		(property "Device Type" "C0201H14"
			(at -1.9177 0.4953 90)
			(unlocked yes)
			(layer "B.Fab")
			(hide yes)
			(effects
				(font
					(size 1.016 1.016)
					(thickness 0.1524)
				)
				(justify mirror)
			)
		)
		(duplicate_pad_numbers_are_jumpers no)
		(fp_rect
			(start 0.1524 0.3048)
			(end -0.1524 -0.3048)
			(stroke
				(width 0)
				(type default)
			)
			(fill no)
			(layer "B.CrtYd")
		)
		(fp_poly
			(pts
				(xy 0.2794 0.6477) (xy 0.2794 -0.6477) (xy -0.2794 -0.6477) (xy -0.2794 -0.1905) (xy -0.1524 -0.1905)
				(xy -0.1524 -0.3048) (xy 0.1524 -0.3048) (xy 0.1524 0.3048) (xy -0.1524 0.3048) (xy -0.1524 -0.1778)
				(xy -0.2794 -0.1778) (xy -0.2794 0.6477)
			)
			(stroke
				(width 0)
				(type default)
			)
			(fill no)
			(layer "B.CrtYd")
		)
		(fp_rect
			(start 0.2794 0.6477)
			(end -0.2794 -0.6477)
			(stroke
				(width 0)
				(type default)
			)
			(fill no)
			(layer "B.Fab")
		)
		(pad "1" smd custom
			(at 0 -0.2794 270)
			(size 0.0762 0.0762)
			(layers "B.Cu" "B.Mask" "B.Paste")
			(net "XTAL_VDDA18")
			(options
				(clearance outline)
				(anchor circle)
			)
			(primitives
				(gr_poly
					(pts
						(arc
							(start 0.1524 0.127)
							(mid 0.137521 0.162921)
							(end 0.1016 0.1778)
						)
						(arc
							(start -0.1016 0.1778)
							(mid -0.137521 0.162921)
							(end -0.1524 0.127)
						)
						(arc
							(start -0.1524 -0.127)
							(mid -0.137521 -0.162921)
							(end -0.1016 -0.1778)
						)
						(arc
							(start 0.1016 -0.1778)
							(mid 0.137521 -0.162921)
							(end 0.1524 -0.127)
						)
					)
					(width 0)
					(fill yes)
				)
			)
		)
		(pad "2" smd custom
			(at 0 0.2794 270)
			(size 0.0762 0.0762)
			(layers "B.Cu" "B.Mask" "B.Paste")
			(net "GND")
			(options
				(clearance outline)
				(anchor circle)
			)
			(primitives
				(gr_poly
					(pts
						(arc
							(start 0.1524 0.127)
							(mid 0.137521 0.162921)
							(end 0.1016 0.1778)
						)
						(arc
							(start -0.1016 0.1778)
							(mid -0.137521 0.162921)
							(end -0.1524 0.127)
						)
						(arc
							(start -0.1524 -0.127)
							(mid -0.137521 -0.162921)
							(end -0.1016 -0.1778)
						)
						(arc
							(start 0.1016 -0.1778)
							(mid 0.137521 -0.162921)
							(end 0.1524 -0.127)
						)
					)
					(width 0)
					(fill yes)
				)
			)
		)
	)
	(footprint ""
		(layer "B.Cu")
		(at 70.485 -37.465 90)
		(property "Reference" "L7"
			(at 0 0 90)
			(layer "B.SilkS")
			(hide yes)
			(effects
				(font
					(size 1.27 1.27)
				)
				(justify mirror)
			)
		)
		(property "Value" "MPZ2012S300AT-GP"
			(at 0 -4.2418 90)
			(unlocked yes)
			(layer "B.Fab")
			(hide yes)
			(effects
				(font
					(size 1.016 1.016)
					(thickness 0.1524)
				)
				(justify mirror)
			)
		)
		(property "Device Type" "L805H42"
			(at 0 -5.7912 90)
			(unlocked yes)
			(layer "B.Fab")
			(hide yes)
			(effects
				(font
					(size 1.016 1.016)
					(thickness 0.1524)
				)
				(justify mirror)
			)
		)
		(duplicate_pad_numbers_are_jumpers no)
		(fp_line
			(start 0.889 -1.7018)
			(end -0.889 -1.7018)
			(stroke
				(width 0.1524)
				(type default)
			)
			(layer "B.SilkS")
		)
		(fp_line
			(start -0.889 -1.7018)
			(end -0.889 1.7018)
			(stroke
				(width 0.1524)
				(type default)
			)
			(layer "B.SilkS")
		)
		(fp_line
			(start 0.889 1.7018)
			(end 0.889 -1.7018)
			(stroke
				(width 0.1524)
				(type default)
			)
			(layer "B.SilkS")
		)
		(fp_line
			(start -0.889 1.7018)
			(end 0.889 1.7018)
			(stroke
				(width 0.1524)
				(type default)
			)
			(layer "B.SilkS")
		)
		(fp_rect
			(start 0.9652 1.778)
			(end -0.9652 -1.778)
			(stroke
				(width 0)
				(type default)
			)
			(fill no)
			(layer "B.CrtYd")
		)
		(fp_rect
			(start 0.9652 1.778)
			(end -0.9652 -1.778)
			(stroke
				(width 0)
				(type default)
			)
			(fill no)
			(layer "B.Fab")
		)
		(pad "1" smd rect
			(at 0 -0.9652 270)
			(size 1.397 1.143)
			(layers "B.Cu" "B.Mask" "B.Paste")
			(net "P0V9")
		)
		(pad "2" smd rect
			(at 0 0.9652 270)
			(size 1.397 1.143)
			(layers "B.Cu" "B.Mask" "B.Paste")
			(net "GB_VDDA")
		)
	)
	(footprint ""
		(layer "B.Cu")
		(at 185.2676 -28.3972)
		(property "Reference" "TP115"
			(at 0 0 0)
			(layer "B.SilkS")
			(hide yes)
			(effects
				(font
					(size 1.27 1.27)
				)
				(justify mirror)
			)
		)
		(property "Value" "TPAD28-2-GP"
			(at 0.0127 -1.6637 0)
			(unlocked yes)
			(layer "B.Fab")
			(hide yes)
			(effects
				(font
					(size 1.016 1.016)
					(thickness 0.1524)
				)
				(justify mirror)
			)
		)
		(property "Device Type" "TPAD28"
			(at 0.0127 -3.1877 0)
			(unlocked yes)
			(layer "B.Fab")
			(hide yes)
			(effects
				(font
					(size 1.016 1.016)
					(thickness 0.1524)
				)
				(justify mirror)
			)
		)
		(duplicate_pad_numbers_are_jumpers no)
		(fp_poly
			(pts
				(arc
					(start 0.3556 0)
					(mid -0.3556 0)
					(end 0.3556 0)
				)
			)
			(stroke
				(width 0)
				(type default)
			)
			(fill no)
			(layer "B.CrtYd")
		)
		(fp_poly
			(pts
				(arc
					(start 0.6096 0)
					(mid -0.6096 0)
					(end 0.6096 0)
				)
			)
			(stroke
				(width 0)
				(type default)
			)
			(fill no)
			(layer "B.Fab")
		)
		(pad "1" smd circle
			(at 0 0 180)
			(size 0.7112 0.7112)
			(layers "B.Cu" "B.Mask" "B.Paste")
			(net "IOC_UART_1_RX")
		)
	)
	(footprint ""
		(layer "B.Cu")
		(at 112.498632 -74.497692)
		(property "Reference" "TP46"
			(at 0 0 0)
			(layer "B.SilkS")
			(hide yes)
			(effects
				(font
					(size 1.27 1.27)
				)
				(justify mirror)
			)
		)
		(property "Value" "TPAD28-2-GP"
			(at 0.0127 -1.6637 0)
			(unlocked yes)
			(layer "B.Fab")
			(hide yes)
			(effects
				(font
					(size 1.016 1.016)
					(thickness 0.1524)
				)
				(justify mirror)
			)
		)
		(property "Device Type" "TPAD28"
			(at 0.0127 -3.1877 0)
			(unlocked yes)
			(layer "B.Fab")
			(hide yes)
			(effects
				(font
					(size 1.016 1.016)
					(thickness 0.1524)
				)
				(justify mirror)
			)
		)
		(duplicate_pad_numbers_are_jumpers no)
		(fp_poly
			(pts
				(arc
					(start 0.3556 0)
					(mid -0.3556 0)
					(end 0.3556 0)
				)
			)
			(stroke
				(width 0)
				(type default)
			)
			(fill no)
			(layer "B.CrtYd")
		)
		(fp_poly
			(pts
				(arc
					(start 0.6096 0)
					(mid -0.6096 0)
					(end 0.6096 0)
				)
			)
			(stroke
				(width 0)
				(type default)
			)
			(fill no)
			(layer "B.Fab")
		)
		(pad "1" smd circle
			(at 0 0 180)
			(size 0.7112 0.7112)
			(layers "B.Cu" "B.Mask" "B.Paste")
			(net "EXP_XM_ADDR_24")
		)
	)
	(footprint ""
		(layer "B.Cu")
		(at 110.236 -81.8388)
		(property "Reference" "TP51"
			(at 0 0 0)
			(layer "B.SilkS")
			(hide yes)
			(effects
				(font
					(size 1.27 1.27)
				)
				(justify mirror)
			)
		)
		(property "Value" "TPAD28-2-GP"
			(at 0.0127 -1.6637 0)
			(unlocked yes)
			(layer "B.Fab")
			(hide yes)
			(effects
				(font
					(size 1.016 1.016)
					(thickness 0.1524)
				)
				(justify mirror)
			)
		)
		(property "Device Type" "TPAD28"
			(at 0.0127 -3.1877 0)
			(unlocked yes)
			(layer "B.Fab")
			(hide yes)
			(effects
				(font
					(size 1.016 1.016)
					(thickness 0.1524)
				)
				(justify mirror)
			)
		)
		(duplicate_pad_numbers_are_jumpers no)
		(fp_poly
			(pts
				(arc
					(start 0.3556 0)
					(mid -0.3556 0)
					(end 0.3556 0)
				)
			)
			(stroke
				(width 0)
				(type default)
			)
			(fill no)
			(layer "B.CrtYd")
		)
		(fp_poly
			(pts
				(arc
					(start 0.6096 0)
					(mid -0.6096 0)
					(end 0.6096 0)
				)
			)
			(stroke
				(width 0)
				(type default)
			)
			(fill no)
			(layer "B.Fab")
		)
		(pad "1" smd circle
			(at 0 0 180)
			(size 0.7112 0.7112)
			(layers "B.Cu" "B.Mask" "B.Paste")
			(net "XM_WBE_1#_TP")
		)
	)
	(footprint ""
		(layer "B.Cu")
		(at 166.627302 -42.399966 90)
		(property "Reference" "R255"
			(at 0 0 90)
			(layer "B.SilkS")
			(hide yes)
			(effects
				(font
					(size 1.27 1.27)
				)
				(justify mirror)
			)
		)
		(property "Value" "10KR2F-2-GP"
			(at -0.064008 -3.993896 90)
			(unlocked yes)
			(layer "B.Fab")
			(hide yes)
			(effects
				(font
					(size 1.016 1.016)
					(thickness 0.1524)
				)
				(justify mirror)
			)
		)
		(property "Device Type" "R402H16"
			(at -0.064008 -5.517896 90)
			(unlocked yes)
			(layer "B.Fab")
			(hide yes)
			(effects
				(font
					(size 1.016 1.016)
					(thickness 0.1524)
				)
				(justify mirror)
			)
		)
		(duplicate_pad_numbers_are_jumpers no)
		(fp_line
			(start 0.508 -0.9398)
			(end 0.508 0.9398)
			(stroke
				(width 0.1524)
				(type default)
			)
			(layer "B.SilkS")
		)
		(fp_line
			(start -0.508 -0.9398)
			(end 0.508 -0.9398)
			(stroke
				(width 0.1524)
				(type default)
			)
			(layer "B.SilkS")
		)
		(fp_rect
			(start 0.508 0.9398)
			(end -0.508 -0.9398)
			(stroke
				(width 0)
				(type default)
			)
			(fill no)
			(layer "B.CrtYd")
		)
		(fp_rect
			(start 0.508 0.9398)
			(end -0.508 -0.9398)
			(stroke
				(width 0)
				(type default)
			)
			(fill no)
			(layer "B.Fab")
		)
		(pad "1" smd custom
			(at 0 -0.4445 270)
			(size 0.1397 0.1397)
			(layers "B.Cu" "B.Mask" "B.Paste")
			(net "P1V8_C")
			(options
				(clearance outline)
				(anchor circle)
			)
			(primitives
				(gr_poly
					(pts
						(arc
							(start -0.1778 0.2794)
							(mid -0.249642 0.249642)
							(end -0.2794 0.1778)
						)
						(arc
							(start -0.2794 -0.1778)
							(mid -0.249642 -0.249642)
							(end -0.1778 -0.2794)
						)
						(arc
							(start 0.1778 -0.2794)
							(mid 0.249642 -0.249642)
							(end 0.2794 -0.1778)
						)
						(arc
							(start 0.2794 0.1778)
							(mid 0.249642 0.249642)
							(end 0.1778 0.2794)
						)
					)
					(width 0)
					(fill yes)
				)
			)
		)
		(pad "2" smd custom
			(at 0 0.4445 270)
			(size 0.1397 0.1397)
			(layers "B.Cu" "B.Mask" "B.Paste")
			(net "POWERLOSS#")
			(options
				(clearance outline)
				(anchor circle)
			)
			(primitives
				(gr_poly
					(pts
						(arc
							(start -0.1778 0.2794)
							(mid -0.249642 0.249642)
							(end -0.2794 0.1778)
						)
						(arc
							(start -0.2794 -0.1778)
							(mid -0.249642 -0.249642)
							(end -0.1778 -0.2794)
						)
						(arc
							(start 0.1778 -0.2794)
							(mid 0.249642 -0.249642)
							(end 0.2794 -0.1778)
						)
						(arc
							(start 0.2794 0.1778)
							(mid 0.249642 0.249642)
							(end 0.1778 0.2794)
						)
					)
					(width 0)
					(fill yes)
				)
			)
		)
	)
	(footprint ""
		(layer "B.Cu")
		(at 137.2108 -89.6874)
		(property "Reference" "R57"
			(at 0 0 0)
			(layer "B.SilkS")
			(hide yes)
			(effects
				(font
					(size 1.27 1.27)
				)
				(justify mirror)
			)
		)
		(property "Value" "4K7R2F-GP"
			(at -0.064008 -3.993896 0)
			(unlocked yes)
			(layer "B.Fab")
			(hide yes)
			(effects
				(font
					(size 1.016 1.016)
					(thickness 0.1524)
				)
				(justify mirror)
			)
		)
		(property "Device Type" "R402H16"
			(at -0.064008 -5.517896 0)
			(unlocked yes)
			(layer "B.Fab")
			(hide yes)
			(effects
				(font
					(size 1.016 1.016)
					(thickness 0.1524)
				)
				(justify mirror)
			)
		)
		(duplicate_pad_numbers_are_jumpers no)
		(fp_line
			(start -0.508 -0.9398)
			(end 0.508 -0.9398)
			(stroke
				(width 0.1524)
				(type default)
			)
			(layer "B.SilkS")
		)
		(fp_line
			(start 0.508 -0.9398)
			(end 0.508 0.9398)
			(stroke
				(width 0.1524)
				(type default)
			)
			(layer "B.SilkS")
		)
		(fp_rect
			(start 0.508 0.9398)
			(end -0.508 -0.9398)
			(stroke
				(width 0)
				(type default)
			)
			(fill no)
			(layer "B.CrtYd")
		)
		(fp_rect
			(start 0.508 0.9398)
			(end -0.508 -0.9398)
			(stroke
				(width 0)
				(type default)
			)
			(fill no)
			(layer "B.Fab")
		)
		(pad "1" smd custom
			(at 0 -0.4445 180)
			(size 0.1397 0.1397)
			(layers "B.Cu" "B.Mask" "B.Paste")
			(net "P1V8_E")
			(options
				(clearance outline)
				(anchor circle)
			)
			(primitives
				(gr_poly
					(pts
						(arc
							(start -0.1778 0.2794)
							(mid -0.249642 0.249642)
							(end -0.2794 0.1778)
						)
						(arc
							(start -0.2794 -0.1778)
							(mid -0.249642 -0.249642)
							(end -0.1778 -0.2794)
						)
						(arc
							(start 0.1778 -0.2794)
							(mid 0.249642 -0.249642)
							(end 0.2794 -0.1778)
						)
						(arc
							(start 0.2794 0.1778)
							(mid 0.249642 0.249642)
							(end 0.1778 0.2794)
						)
					)
					(width 0)
					(fill yes)
				)
			)
		)
		(pad "2" smd custom
			(at 0 0.4445 180)
			(size 0.1397 0.1397)
			(layers "B.Cu" "B.Mask" "B.Paste")
			(net "I2C_DRIVE_PWR_SDA4_LS")
			(options
				(clearance outline)
				(anchor circle)
			)
			(primitives
				(gr_poly
					(pts
						(arc
							(start -0.1778 0.2794)
							(mid -0.249642 0.249642)
							(end -0.2794 0.1778)
						)
						(arc
							(start -0.2794 -0.1778)
							(mid -0.249642 -0.249642)
							(end -0.1778 -0.2794)
						)
						(arc
							(start 0.1778 -0.2794)
							(mid 0.249642 -0.249642)
							(end 0.2794 -0.1778)
						)
						(arc
							(start 0.2794 0.1778)
							(mid 0.249642 0.249642)
							(end 0.1778 0.2794)
						)
					)
					(width 0)
					(fill yes)
				)
			)
		)
	)
	(footprint ""
		(layer "B.Cu")
		(at 113.3856 -59.4487)
		(property "Reference" "C284"
			(at 0 0 0)
			(layer "B.SilkS")
			(hide yes)
			(effects
				(font
					(size 1.27 1.27)
				)
				(justify mirror)
			)
		)
		(property "Value" "SCD1U6D3V1KX-GP"
			(at 2.8321 -1.7399 0)
			(unlocked yes)
			(layer "B.Fab")
			(hide yes)
			(effects
				(font
					(size 1.016 1.016)
					(thickness 0.1524)
				)
				(justify mirror)
			)
		)
		(property "Device Type" "C0201H13"
			(at 2.8321 -3.2639 0)
			(unlocked yes)
			(layer "B.Fab")
			(hide yes)
			(effects
				(font
					(size 1.016 1.016)
					(thickness 0.1524)
				)
				(justify mirror)
			)
		)
		(duplicate_pad_numbers_are_jumpers no)
		(fp_rect
			(start 0.2794 0.6477)
			(end -0.2794 -0.6477)
			(stroke
				(width 0)
				(type default)
			)
			(fill no)
			(layer "B.CrtYd")
		)
		(fp_rect
			(start 0.2794 0.6477)
			(end -0.2794 -0.6477)
			(stroke
				(width 0)
				(type default)
			)
			(fill no)
			(layer "B.Fab")
		)
		(pad "1" smd custom
			(at 0 -0.2794 180)
			(size 0.0762 0.0762)
			(layers "B.Cu" "B.Mask" "B.Paste")
			(net "GB_VDDA")
			(options
				(clearance outline)
				(anchor circle)
			)
			(primitives
				(gr_poly
					(pts
						(arc
							(start 0.1524 0.127)
							(mid 0.137521 0.162921)
							(end 0.1016 0.1778)
						)
						(arc
							(start -0.1016 0.1778)
							(mid -0.137521 0.162921)
							(end -0.1524 0.127)
						)
						(arc
							(start -0.1524 -0.127)
							(mid -0.137521 -0.162921)
							(end -0.1016 -0.1778)
						)
						(arc
							(start 0.1016 -0.1778)
							(mid 0.137521 -0.162921)
							(end 0.1524 -0.127)
						)
					)
					(width 0)
					(fill yes)
				)
			)
		)
		(pad "2" smd custom
			(at 0 0.2794 180)
			(size 0.0762 0.0762)
			(layers "B.Cu" "B.Mask" "B.Paste")
			(net "GND")
			(options
				(clearance outline)
				(anchor circle)
			)
			(primitives
				(gr_poly
					(pts
						(arc
							(start 0.1524 0.127)
							(mid 0.137521 0.162921)
							(end 0.1016 0.1778)
						)
						(arc
							(start -0.1016 0.1778)
							(mid -0.137521 0.162921)
							(end -0.1524 0.127)
						)
						(arc
							(start -0.1524 -0.127)
							(mid -0.137521 -0.162921)
							(end -0.1016 -0.1778)
						)
						(arc
							(start 0.1016 -0.1778)
							(mid 0.137521 -0.162921)
							(end 0.1524 -0.127)
						)
					)
					(width 0)
					(fill yes)
				)
			)
		)
	)
	(footprint ""
		(layer "B.Cu")
		(at 100.5332 -58.4962 -90)
		(property "Reference" "C136"
			(at 0 0 90)
			(layer "B.SilkS")
			(hide yes)
			(effects
				(font
					(size 1.27 1.27)
				)
				(justify mirror)
			)
		)
		(property "Value" "SCD1U6D3V1KX-GP"
			(at 2.8321 -1.7399 270)
			(unlocked yes)
			(layer "B.Fab")
			(hide yes)
			(effects
				(font
					(size 1.016 1.016)
					(thickness 0.1524)
				)
				(justify mirror)
			)
		)
		(property "Device Type" "C0201H13"
			(at 2.8321 -3.2639 270)
			(unlocked yes)
			(layer "B.Fab")
			(hide yes)
			(effects
				(font
					(size 1.016 1.016)
					(thickness 0.1524)
				)
				(justify mirror)
			)
		)
		(duplicate_pad_numbers_are_jumpers no)
		(fp_rect
			(start 0.2794 0.6477)
			(end -0.2794 -0.6477)
			(stroke
				(width 0)
				(type default)
			)
			(fill no)
			(layer "B.CrtYd")
		)
		(fp_rect
			(start 0.2794 0.6477)
			(end -0.2794 -0.6477)
			(stroke
				(width 0)
				(type default)
			)
			(fill no)
			(layer "B.Fab")
		)
		(pad "1" smd custom
			(at 0 -0.2794 90)
			(size 0.0762 0.0762)
			(layers "B.Cu" "B.Mask" "B.Paste")
			(net "P1V8_E")
			(options
				(clearance outline)
				(anchor circle)
			)
			(primitives
				(gr_poly
					(pts
						(arc
							(start 0.1524 0.127)
							(mid 0.137521 0.162921)
							(end 0.1016 0.1778)
						)
						(arc
							(start -0.1016 0.1778)
							(mid -0.137521 0.162921)
							(end -0.1524 0.127)
						)
						(arc
							(start -0.1524 -0.127)
							(mid -0.137521 -0.162921)
							(end -0.1016 -0.1778)
						)
						(arc
							(start 0.1016 -0.1778)
							(mid 0.137521 -0.162921)
							(end 0.1524 -0.127)
						)
					)
					(width 0)
					(fill yes)
				)
			)
		)
		(pad "2" smd custom
			(at 0 0.2794 90)
			(size 0.0762 0.0762)
			(layers "B.Cu" "B.Mask" "B.Paste")
			(net "GND")
			(options
				(clearance outline)
				(anchor circle)
			)
			(primitives
				(gr_poly
					(pts
						(arc
							(start 0.1524 0.127)
							(mid 0.137521 0.162921)
							(end 0.1016 0.1778)
						)
						(arc
							(start -0.1016 0.1778)
							(mid -0.137521 0.162921)
							(end -0.1524 0.127)
						)
						(arc
							(start -0.1524 -0.127)
							(mid -0.137521 -0.162921)
							(end -0.1016 -0.1778)
						)
						(arc
							(start 0.1016 -0.1778)
							(mid 0.137521 -0.162921)
							(end 0.1524 -0.127)
						)
					)
					(width 0)
					(fill yes)
				)
			)
		)
	)
	(footprint ""
		(layer "B.Cu")
		(at 171.437808 -38.33241 -90)
		(property "Reference" "C448"
			(at 0 0 90)
			(layer "B.SilkS")
			(hide yes)
			(effects
				(font
					(size 1.27 1.27)
				)
				(justify mirror)
			)
		)
		(property "Value" "SC1KP50V2KX-1GP"
			(at -1.1811 -2.7051 270)
			(unlocked yes)
			(layer "B.Fab")
			(hide yes)
			(effects
				(font
					(size 1.016 1.016)
					(thickness 0.1524)
				)
				(justify mirror)
			)
		)
		(property "Device Type" "C402H22"
			(at -1.1811 -4.2291 270)
			(unlocked yes)
			(layer "B.Fab")
			(hide yes)
			(effects
				(font
					(size 1.016 1.016)
					(thickness 0.1524)
				)
				(justify mirror)
			)
		)
		(duplicate_pad_numbers_are_jumpers no)
		(fp_rect
			(start 0.4318 0.9525)
			(end -0.4318 -0.9525)
			(stroke
				(width 0)
				(type default)
			)
			(fill no)
			(layer "B.CrtYd")
		)
		(fp_rect
			(start 0.4318 0.9525)
			(end -0.4318 -0.9525)
			(stroke
				(width 0)
				(type default)
			)
			(fill no)
			(layer "B.Fab")
		)
		(pad "1" smd custom
			(at 0 -0.4445 90)
			(size 0.1524 0.1524)
			(layers "B.Cu" "B.Mask" "B.Paste")
			(net "P0V975")
			(options
				(clearance outline)
				(anchor circle)
			)
			(primitives
				(gr_poly
					(pts
						(arc
							(start 0.3048 0.2032)
							(mid 0.275042 0.275042)
							(end 0.2032 0.3048)
						)
						(arc
							(start -0.2032 0.3048)
							(mid -0.275042 0.275042)
							(end -0.3048 0.2032)
						)
						(arc
							(start -0.3048 -0.2032)
							(mid -0.275042 -0.275042)
							(end -0.2032 -0.3048)
						)
						(arc
							(start 0.2032 -0.3048)
							(mid 0.275042 -0.275042)
							(end 0.3048 -0.2032)
						)
					)
					(width 0)
					(fill yes)
				)
			)
		)
		(pad "2" smd custom
			(at 0 0.4445 90)
			(size 0.1524 0.1524)
			(layers "B.Cu" "B.Mask" "B.Paste")
			(net "GND")
			(options
				(clearance outline)
				(anchor circle)
			)
			(primitives
				(gr_poly
					(pts
						(arc
							(start 0.3048 0.2032)
							(mid 0.275042 0.275042)
							(end 0.2032 0.3048)
						)
						(arc
							(start -0.2032 0.3048)
							(mid -0.275042 0.275042)
							(end -0.3048 0.2032)
						)
						(arc
							(start -0.3048 -0.2032)
							(mid -0.275042 -0.275042)
							(end -0.2032 -0.3048)
						)
						(arc
							(start 0.2032 -0.3048)
							(mid 0.275042 -0.275042)
							(end 0.3048 -0.2032)
						)
					)
					(width 0)
					(fill yes)
				)
			)
		)
	)
	(footprint ""
		(layer "B.Cu")
		(at 162.433 -66.802 180)
		(property "Reference" "L23"
			(at 0 0 0)
			(layer "B.SilkS")
			(hide yes)
			(effects
				(font
					(size 1.27 1.27)
				)
				(justify mirror)
			)
		)
		(property "Value" "MPZ2012S601AT-GP"
			(at 0 -4.2418 180)
			(unlocked yes)
			(layer "B.Fab")
			(hide yes)
			(effects
				(font
					(size 1.016 1.016)
					(thickness 0.1524)
				)
				(justify mirror)
			)
		)
		(property "Device Type" "L805H42"
			(at 0 -5.7912 180)
			(unlocked yes)
			(layer "B.Fab")
			(hide yes)
			(effects
				(font
					(size 1.016 1.016)
					(thickness 0.1524)
				)
				(justify mirror)
			)
		)
		(duplicate_pad_numbers_are_jumpers no)
		(fp_line
			(start 0.889 1.7018)
			(end 0.889 -1.7018)
			(stroke
				(width 0.1524)
				(type default)
			)
			(layer "B.SilkS")
		)
		(fp_line
			(start 0.889 -1.7018)
			(end -0.889 -1.7018)
			(stroke
				(width 0.1524)
				(type default)
			)
			(layer "B.SilkS")
		)
		(fp_line
			(start -0.889 1.7018)
			(end 0.889 1.7018)
			(stroke
				(width 0.1524)
				(type default)
			)
			(layer "B.SilkS")
		)
		(fp_line
			(start -0.889 -1.7018)
			(end -0.889 1.7018)
			(stroke
				(width 0.1524)
				(type default)
			)
			(layer "B.SilkS")
		)
		(fp_rect
			(start 0.9652 1.778)
			(end -0.9652 -1.778)
			(stroke
				(width 0)
				(type default)
			)
			(fill no)
			(layer "B.CrtYd")
		)
		(fp_rect
			(start 0.9652 1.778)
			(end -0.9652 -1.778)
			(stroke
				(width 0)
				(type default)
			)
			(fill no)
			(layer "B.Fab")
		)
		(pad "1" smd rect
			(at 0 -0.9652)
			(size 1.397 1.143)
			(layers "B.Cu" "B.Mask" "B.Paste")
			(net "VDDA_SAS_REF_CLK")
		)
		(pad "2" smd rect
			(at 0 0.9652)
			(size 1.397 1.143)
			(layers "B.Cu" "B.Mask" "B.Paste")
			(net "P1V8_C")
		)
	)
	(footprint ""
		(layer "B.Cu")
		(at 181.26964 -21.27504 90)
		(property "Reference" "C325"
			(at 0 0 90)
			(layer "B.SilkS")
			(hide yes)
			(effects
				(font
					(size 1.27 1.27)
				)
				(justify mirror)
			)
		)
		(property "Value" "SCD22U10V1KX-GP"
			(at 2.8321 -1.7399 90)
			(unlocked yes)
			(layer "B.Fab")
			(hide yes)
			(effects
				(font
					(size 1.016 1.016)
					(thickness 0.1524)
				)
				(justify mirror)
			)
		)
		(property "Device Type" "C0201H13"
			(at 2.8321 -3.2639 90)
			(unlocked yes)
			(layer "B.Fab")
			(hide yes)
			(effects
				(font
					(size 1.016 1.016)
					(thickness 0.1524)
				)
				(justify mirror)
			)
		)
		(duplicate_pad_numbers_are_jumpers no)
		(fp_rect
			(start 0.2794 0.6477)
			(end -0.2794 -0.6477)
			(stroke
				(width 0)
				(type default)
			)
			(fill no)
			(layer "B.CrtYd")
		)
		(fp_rect
			(start 0.2794 0.6477)
			(end -0.2794 -0.6477)
			(stroke
				(width 0)
				(type default)
			)
			(fill no)
			(layer "B.Fab")
		)
		(pad "1" smd custom
			(at 0 -0.2794 270)
			(size 0.0762 0.0762)
			(layers "B.Cu" "B.Mask" "B.Paste")
			(net "PCIE_SCC_TO_COMP_C_7_DP")
			(options
				(clearance outline)
				(anchor circle)
			)
			(primitives
				(gr_poly
					(pts
						(arc
							(start 0.1524 0.127)
							(mid 0.137521 0.162921)
							(end 0.1016 0.1778)
						)
						(arc
							(start -0.1016 0.1778)
							(mid -0.137521 0.162921)
							(end -0.1524 0.127)
						)
						(arc
							(start -0.1524 -0.127)
							(mid -0.137521 -0.162921)
							(end -0.1016 -0.1778)
						)
						(arc
							(start 0.1016 -0.1778)
							(mid 0.137521 -0.162921)
							(end 0.1524 -0.127)
						)
					)
					(width 0)
					(fill yes)
				)
			)
		)
		(pad "2" smd custom
			(at 0 0.2794 270)
			(size 0.0762 0.0762)
			(layers "B.Cu" "B.Mask" "B.Paste")
			(net "PCIE_SCC_TO_COMP_7_DP")
			(options
				(clearance outline)
				(anchor circle)
			)
			(primitives
				(gr_poly
					(pts
						(arc
							(start 0.1524 0.127)
							(mid 0.137521 0.162921)
							(end 0.1016 0.1778)
						)
						(arc
							(start -0.1016 0.1778)
							(mid -0.137521 0.162921)
							(end -0.1524 0.127)
						)
						(arc
							(start -0.1524 -0.127)
							(mid -0.137521 -0.162921)
							(end -0.1016 -0.1778)
						)
						(arc
							(start 0.1016 -0.1778)
							(mid 0.137521 -0.162921)
							(end 0.1524 -0.127)
						)
					)
					(width 0)
					(fill yes)
				)
			)
		)
	)
	(footprint ""
		(layer "B.Cu")
		(at 129.397252 -56.71566 90)
		(property "Reference" "C232"
			(at 0 0 90)
			(layer "B.SilkS")
			(hide yes)
			(effects
				(font
					(size 1.27 1.27)
				)
				(justify mirror)
			)
		)
		(property "Value" "SCD1U6D3V1KX-GP"
			(at 2.8321 -1.7399 90)
			(unlocked yes)
			(layer "B.Fab")
			(hide yes)
			(effects
				(font
					(size 1.016 1.016)
					(thickness 0.1524)
				)
				(justify mirror)
			)
		)
		(property "Device Type" "C0201H13"
			(at 2.8321 -3.2639 90)
			(unlocked yes)
			(layer "B.Fab")
			(hide yes)
			(effects
				(font
					(size 1.016 1.016)
					(thickness 0.1524)
				)
				(justify mirror)
			)
		)
		(duplicate_pad_numbers_are_jumpers no)
		(fp_rect
			(start 0.2794 0.6477)
			(end -0.2794 -0.6477)
			(stroke
				(width 0)
				(type default)
			)
			(fill no)
			(layer "B.CrtYd")
		)
		(fp_rect
			(start 0.2794 0.6477)
			(end -0.2794 -0.6477)
			(stroke
				(width 0)
				(type default)
			)
			(fill no)
			(layer "B.Fab")
		)
		(pad "1" smd custom
			(at 0 -0.2794 270)
			(size 0.0762 0.0762)
			(layers "B.Cu" "B.Mask" "B.Paste")
			(net "GB_VDDA")
			(options
				(clearance outline)
				(anchor circle)
			)
			(primitives
				(gr_poly
					(pts
						(arc
							(start 0.1524 0.127)
							(mid 0.137521 0.162921)
							(end 0.1016 0.1778)
						)
						(arc
							(start -0.1016 0.1778)
							(mid -0.137521 0.162921)
							(end -0.1524 0.127)
						)
						(arc
							(start -0.1524 -0.127)
							(mid -0.137521 -0.162921)
							(end -0.1016 -0.1778)
						)
						(arc
							(start 0.1016 -0.1778)
							(mid 0.137521 -0.162921)
							(end 0.1524 -0.127)
						)
					)
					(width 0)
					(fill yes)
				)
			)
		)
		(pad "2" smd custom
			(at 0 0.2794 270)
			(size 0.0762 0.0762)
			(layers "B.Cu" "B.Mask" "B.Paste")
			(net "GND")
			(options
				(clearance outline)
				(anchor circle)
			)
			(primitives
				(gr_poly
					(pts
						(arc
							(start 0.1524 0.127)
							(mid 0.137521 0.162921)
							(end 0.1016 0.1778)
						)
						(arc
							(start -0.1016 0.1778)
							(mid -0.137521 0.162921)
							(end -0.1524 0.127)
						)
						(arc
							(start -0.1524 -0.127)
							(mid -0.137521 -0.162921)
							(end -0.1016 -0.1778)
						)
						(arc
							(start 0.1016 -0.1778)
							(mid 0.137521 -0.162921)
							(end 0.1524 -0.127)
						)
					)
					(width 0)
					(fill yes)
				)
			)
		)
	)
	(footprint ""
		(layer "B.Cu")
		(at 106.299 -64.516 -90)
		(property "Reference" "C203"
			(at 0 0 90)
			(layer "B.SilkS")
			(hide yes)
			(effects
				(font
					(size 1.27 1.27)
				)
				(justify mirror)
			)
		)
		(property "Value" "SCD1U6D3V1KX-GP"
			(at 2.8321 -1.7399 270)
			(unlocked yes)
			(layer "B.Fab")
			(hide yes)
			(effects
				(font
					(size 1.016 1.016)
					(thickness 0.1524)
				)
				(justify mirror)
			)
		)
		(property "Device Type" "C0201H13"
			(at 2.8321 -3.2639 270)
			(unlocked yes)
			(layer "B.Fab")
			(hide yes)
			(effects
				(font
					(size 1.016 1.016)
					(thickness 0.1524)
				)
				(justify mirror)
			)
		)
		(duplicate_pad_numbers_are_jumpers no)
		(fp_rect
			(start 0.2794 0.6477)
			(end -0.2794 -0.6477)
			(stroke
				(width 0)
				(type default)
			)
			(fill no)
			(layer "B.CrtYd")
		)
		(fp_rect
			(start 0.2794 0.6477)
			(end -0.2794 -0.6477)
			(stroke
				(width 0)
				(type default)
			)
			(fill no)
			(layer "B.Fab")
		)
		(pad "1" smd custom
			(at 0 -0.2794 90)
			(size 0.0762 0.0762)
			(layers "B.Cu" "B.Mask" "B.Paste")
			(net "PLLDDR_VDDA18")
			(options
				(clearance outline)
				(anchor circle)
			)
			(primitives
				(gr_poly
					(pts
						(arc
							(start 0.1524 0.127)
							(mid 0.137521 0.162921)
							(end 0.1016 0.1778)
						)
						(arc
							(start -0.1016 0.1778)
							(mid -0.137521 0.162921)
							(end -0.1524 0.127)
						)
						(arc
							(start -0.1524 -0.127)
							(mid -0.137521 -0.162921)
							(end -0.1016 -0.1778)
						)
						(arc
							(start 0.1016 -0.1778)
							(mid 0.137521 -0.162921)
							(end 0.1524 -0.127)
						)
					)
					(width 0)
					(fill yes)
				)
			)
		)
		(pad "2" smd custom
			(at 0 0.2794 90)
			(size 0.0762 0.0762)
			(layers "B.Cu" "B.Mask" "B.Paste")
			(net "GND")
			(options
				(clearance outline)
				(anchor circle)
			)
			(primitives
				(gr_poly
					(pts
						(arc
							(start 0.1524 0.127)
							(mid 0.137521 0.162921)
							(end 0.1016 0.1778)
						)
						(arc
							(start -0.1016 0.1778)
							(mid -0.137521 0.162921)
							(end -0.1524 0.127)
						)
						(arc
							(start -0.1524 -0.127)
							(mid -0.137521 -0.162921)
							(end -0.1016 -0.1778)
						)
						(arc
							(start 0.1016 -0.1778)
							(mid 0.137521 -0.162921)
							(end 0.1524 -0.127)
						)
					)
					(width 0)
					(fill yes)
				)
			)
		)
	)
	(footprint ""
		(layer "B.Cu")
		(at 128.7018 -85.3948)
		(property "Reference" "TP159"
			(at 0 0 0)
			(layer "B.SilkS")
			(hide yes)
			(effects
				(font
					(size 1.27 1.27)
				)
				(justify mirror)
			)
		)
		(property "Value" "TPAD28-2-GP"
			(at 0.0127 -1.6637 0)
			(unlocked yes)
			(layer "B.Fab")
			(hide yes)
			(effects
				(font
					(size 1.016 1.016)
					(thickness 0.1524)
				)
				(justify mirror)
			)
		)
		(property "Device Type" "TPAD28"
			(at 0.0127 -3.1877 0)
			(unlocked yes)
			(layer "B.Fab")
			(hide yes)
			(effects
				(font
					(size 1.016 1.016)
					(thickness 0.1524)
				)
				(justify mirror)
			)
		)
		(duplicate_pad_numbers_are_jumpers no)
		(fp_poly
			(pts
				(arc
					(start 0.3556 0)
					(mid -0.3556 0)
					(end 0.3556 0)
				)
			)
			(stroke
				(width 0)
				(type default)
			)
			(fill no)
			(layer "B.CrtYd")
		)
		(fp_poly
			(pts
				(arc
					(start 0.6096 0)
					(mid -0.6096 0)
					(end 0.6096 0)
				)
			)
			(stroke
				(width 0)
				(type default)
			)
			(fill no)
			(layer "B.Fab")
		)
		(pad "1" smd circle
			(at 0 0 180)
			(size 0.7112 0.7112)
			(layers "B.Cu" "B.Mask" "B.Paste")
			(net "ICE_TMS")
		)
	)
	(footprint ""
		(layer "B.Cu")
		(at 168.963848 -49.70907 90)
		(property "Reference" "C494"
			(at 0 0 90)
			(layer "B.SilkS")
			(hide yes)
			(effects
				(font
					(size 1.27 1.27)
				)
				(justify mirror)
			)
		)
		(property "Value" "SC1KP50V2KX-1GP"
			(at -1.1811 -2.7051 90)
			(unlocked yes)
			(layer "B.Fab")
			(hide yes)
			(effects
				(font
					(size 1.016 1.016)
					(thickness 0.1524)
				)
				(justify mirror)
			)
		)
		(property "Device Type" "C402H22"
			(at -1.1811 -4.2291 90)
			(unlocked yes)
			(layer "B.Fab")
			(hide yes)
			(effects
				(font
					(size 1.016 1.016)
					(thickness 0.1524)
				)
				(justify mirror)
			)
		)
		(duplicate_pad_numbers_are_jumpers no)
		(fp_rect
			(start 0.4318 0.9525)
			(end -0.4318 -0.9525)
			(stroke
				(width 0)
				(type default)
			)
			(fill no)
			(layer "B.CrtYd")
		)
		(fp_rect
			(start 0.4318 0.9525)
			(end -0.4318 -0.9525)
			(stroke
				(width 0)
				(type default)
			)
			(fill no)
			(layer "B.Fab")
		)
		(pad "1" smd custom
			(at 0 -0.4445 270)
			(size 0.1524 0.1524)
			(layers "B.Cu" "B.Mask" "B.Paste")
			(net "P1V8_C")
			(options
				(clearance outline)
				(anchor circle)
			)
			(primitives
				(gr_poly
					(pts
						(arc
							(start 0.3048 0.2032)
							(mid 0.275042 0.275042)
							(end 0.2032 0.3048)
						)
						(arc
							(start -0.2032 0.3048)
							(mid -0.275042 0.275042)
							(end -0.3048 0.2032)
						)
						(arc
							(start -0.3048 -0.2032)
							(mid -0.275042 -0.275042)
							(end -0.2032 -0.3048)
						)
						(arc
							(start 0.2032 -0.3048)
							(mid 0.275042 -0.275042)
							(end 0.3048 -0.2032)
						)
					)
					(width 0)
					(fill yes)
				)
			)
		)
		(pad "2" smd custom
			(at 0 0.4445 270)
			(size 0.1524 0.1524)
			(layers "B.Cu" "B.Mask" "B.Paste")
			(net "GND")
			(options
				(clearance outline)
				(anchor circle)
			)
			(primitives
				(gr_poly
					(pts
						(arc
							(start 0.3048 0.2032)
							(mid 0.275042 0.275042)
							(end 0.2032 0.3048)
						)
						(arc
							(start -0.2032 0.3048)
							(mid -0.275042 0.275042)
							(end -0.3048 0.2032)
						)
						(arc
							(start -0.3048 -0.2032)
							(mid -0.275042 -0.275042)
							(end -0.2032 -0.3048)
						)
						(arc
							(start 0.2032 -0.3048)
							(mid 0.275042 -0.275042)
							(end 0.3048 -0.2032)
						)
					)
					(width 0)
					(fill yes)
				)
			)
		)
	)
	(footprint ""
		(layer "B.Cu")
		(at 96.497394 -53.744368 90)
		(property "Reference" "C93"
			(at 0 0 90)
			(layer "B.SilkS")
			(hide yes)
			(effects
				(font
					(size 1.27 1.27)
				)
				(justify mirror)
			)
		)
		(property "Value" "SCD01U16V1KX-GP"
			(at 2.8321 -1.7399 90)
			(unlocked yes)
			(layer "B.Fab")
			(hide yes)
			(effects
				(font
					(size 1.016 1.016)
					(thickness 0.1524)
				)
				(justify mirror)
			)
		)
		(property "Device Type" "C0201H13"
			(at 2.8321 -3.2639 90)
			(unlocked yes)
			(layer "B.Fab")
			(hide yes)
			(effects
				(font
					(size 1.016 1.016)
					(thickness 0.1524)
				)
				(justify mirror)
			)
		)
		(duplicate_pad_numbers_are_jumpers no)
		(fp_rect
			(start 0.2794 0.6477)
			(end -0.2794 -0.6477)
			(stroke
				(width 0)
				(type default)
			)
			(fill no)
			(layer "B.CrtYd")
		)
		(fp_rect
			(start 0.2794 0.6477)
			(end -0.2794 -0.6477)
			(stroke
				(width 0)
				(type default)
			)
			(fill no)
			(layer "B.Fab")
		)
		(pad "1" smd custom
			(at 0 -0.2794 270)
			(size 0.0762 0.0762)
			(layers "B.Cu" "B.Mask" "B.Paste")
			(net "PHY_DPB_TO_SCC_13_DN")
			(options
				(clearance outline)
				(anchor circle)
			)
			(primitives
				(gr_poly
					(pts
						(arc
							(start 0.1524 0.127)
							(mid 0.137521 0.162921)
							(end 0.1016 0.1778)
						)
						(arc
							(start -0.1016 0.1778)
							(mid -0.137521 0.162921)
							(end -0.1524 0.127)
						)
						(arc
							(start -0.1524 -0.127)
							(mid -0.137521 -0.162921)
							(end -0.1016 -0.1778)
						)
						(arc
							(start 0.1016 -0.1778)
							(mid 0.137521 -0.162921)
							(end 0.1524 -0.127)
						)
					)
					(width 0)
					(fill yes)
				)
			)
		)
		(pad "2" smd custom
			(at 0 0.2794 270)
			(size 0.0762 0.0762)
			(layers "B.Cu" "B.Mask" "B.Paste")
			(net "PHY_DPB_TO_SCC_C_13_DN")
			(options
				(clearance outline)
				(anchor circle)
			)
			(primitives
				(gr_poly
					(pts
						(arc
							(start 0.1524 0.127)
							(mid 0.137521 0.162921)
							(end 0.1016 0.1778)
						)
						(arc
							(start -0.1016 0.1778)
							(mid -0.137521 0.162921)
							(end -0.1524 0.127)
						)
						(arc
							(start -0.1524 -0.127)
							(mid -0.137521 -0.162921)
							(end -0.1016 -0.1778)
						)
						(arc
							(start 0.1016 -0.1778)
							(mid 0.137521 -0.162921)
							(end 0.1524 -0.127)
						)
					)
					(width 0)
					(fill yes)
				)
			)
		)
	)
	(footprint ""
		(layer "B.Cu")
		(at 173.629828 -49.65573 -90)
		(property "Reference" "C466"
			(at 0 0 90)
			(layer "B.SilkS")
			(hide yes)
			(effects
				(font
					(size 1.27 1.27)
				)
				(justify mirror)
			)
		)
		(property "Value" "SCD1U6D3V1KX-GP"
			(at 2.8321 -1.7399 270)
			(unlocked yes)
			(layer "B.Fab")
			(hide yes)
			(effects
				(font
					(size 1.016 1.016)
					(thickness 0.1524)
				)
				(justify mirror)
			)
		)
		(property "Device Type" "C0201H13"
			(at 2.8321 -3.2639 270)
			(unlocked yes)
			(layer "B.Fab")
			(hide yes)
			(effects
				(font
					(size 1.016 1.016)
					(thickness 0.1524)
				)
				(justify mirror)
			)
		)
		(duplicate_pad_numbers_are_jumpers no)
		(fp_rect
			(start 0.2794 0.6477)
			(end -0.2794 -0.6477)
			(stroke
				(width 0)
				(type default)
			)
			(fill no)
			(layer "B.CrtYd")
		)
		(fp_rect
			(start 0.2794 0.6477)
			(end -0.2794 -0.6477)
			(stroke
				(width 0)
				(type default)
			)
			(fill no)
			(layer "B.Fab")
		)
		(pad "1" smd custom
			(at 0 -0.2794 90)
			(size 0.0762 0.0762)
			(layers "B.Cu" "B.Mask" "B.Paste")
			(net "P1V8_C")
			(options
				(clearance outline)
				(anchor circle)
			)
			(primitives
				(gr_poly
					(pts
						(arc
							(start 0.1524 0.127)
							(mid 0.137521 0.162921)
							(end 0.1016 0.1778)
						)
						(arc
							(start -0.1016 0.1778)
							(mid -0.137521 0.162921)
							(end -0.1524 0.127)
						)
						(arc
							(start -0.1524 -0.127)
							(mid -0.137521 -0.162921)
							(end -0.1016 -0.1778)
						)
						(arc
							(start 0.1016 -0.1778)
							(mid 0.137521 -0.162921)
							(end 0.1524 -0.127)
						)
					)
					(width 0)
					(fill yes)
				)
			)
		)
		(pad "2" smd custom
			(at 0 0.2794 90)
			(size 0.0762 0.0762)
			(layers "B.Cu" "B.Mask" "B.Paste")
			(net "GND")
			(options
				(clearance outline)
				(anchor circle)
			)
			(primitives
				(gr_poly
					(pts
						(arc
							(start 0.1524 0.127)
							(mid 0.137521 0.162921)
							(end 0.1016 0.1778)
						)
						(arc
							(start -0.1016 0.1778)
							(mid -0.137521 0.162921)
							(end -0.1524 0.127)
						)
						(arc
							(start -0.1524 -0.127)
							(mid -0.137521 -0.162921)
							(end -0.1016 -0.1778)
						)
						(arc
							(start 0.1016 -0.1778)
							(mid 0.137521 -0.162921)
							(end 0.1524 -0.127)
						)
					)
					(width 0)
					(fill yes)
				)
			)
		)
	)
	(footprint ""
		(layer "B.Cu")
		(at 182.913782 -49.633632 -90)
		(property "Reference" "C501"
			(at 0 0 90)
			(layer "B.SilkS")
			(hide yes)
			(effects
				(font
					(size 1.27 1.27)
				)
				(justify mirror)
			)
		)
		(property "Value" "SC1KP50V2KX-1GP"
			(at -1.1811 -2.7051 270)
			(unlocked yes)
			(layer "B.Fab")
			(hide yes)
			(effects
				(font
					(size 1.016 1.016)
					(thickness 0.1524)
				)
				(justify mirror)
			)
		)
		(property "Device Type" "C402H22"
			(at -1.1811 -4.2291 270)
			(unlocked yes)
			(layer "B.Fab")
			(hide yes)
			(effects
				(font
					(size 1.016 1.016)
					(thickness 0.1524)
				)
				(justify mirror)
			)
		)
		(duplicate_pad_numbers_are_jumpers no)
		(fp_rect
			(start 0.4318 0.9525)
			(end -0.4318 -0.9525)
			(stroke
				(width 0)
				(type default)
			)
			(fill no)
			(layer "B.CrtYd")
		)
		(fp_rect
			(start 0.4318 0.9525)
			(end -0.4318 -0.9525)
			(stroke
				(width 0)
				(type default)
			)
			(fill no)
			(layer "B.Fab")
		)
		(pad "1" smd custom
			(at 0 -0.4445 90)
			(size 0.1524 0.1524)
			(layers "B.Cu" "B.Mask" "B.Paste")
			(net "P1V8_C")
			(options
				(clearance outline)
				(anchor circle)
			)
			(primitives
				(gr_poly
					(pts
						(arc
							(start 0.3048 0.2032)
							(mid 0.275042 0.275042)
							(end 0.2032 0.3048)
						)
						(arc
							(start -0.2032 0.3048)
							(mid -0.275042 0.275042)
							(end -0.3048 0.2032)
						)
						(arc
							(start -0.3048 -0.2032)
							(mid -0.275042 -0.275042)
							(end -0.2032 -0.3048)
						)
						(arc
							(start 0.2032 -0.3048)
							(mid 0.275042 -0.275042)
							(end 0.3048 -0.2032)
						)
					)
					(width 0)
					(fill yes)
				)
			)
		)
		(pad "2" smd custom
			(at 0 0.4445 90)
			(size 0.1524 0.1524)
			(layers "B.Cu" "B.Mask" "B.Paste")
			(net "GND")
			(options
				(clearance outline)
				(anchor circle)
			)
			(primitives
				(gr_poly
					(pts
						(arc
							(start 0.3048 0.2032)
							(mid 0.275042 0.275042)
							(end 0.2032 0.3048)
						)
						(arc
							(start -0.2032 0.3048)
							(mid -0.275042 0.275042)
							(end -0.3048 0.2032)
						)
						(arc
							(start -0.3048 -0.2032)
							(mid -0.275042 -0.275042)
							(end -0.2032 -0.3048)
						)
						(arc
							(start 0.2032 -0.3048)
							(mid 0.275042 -0.275042)
							(end 0.3048 -0.2032)
						)
					)
					(width 0)
					(fill yes)
				)
			)
		)
	)
	(footprint ""
		(layer "B.Cu")
		(at 178.7144 -28.0924)
		(property "Reference" "TP116"
			(at 0 0 0)
			(layer "B.SilkS")
			(hide yes)
			(effects
				(font
					(size 1.27 1.27)
				)
				(justify mirror)
			)
		)
		(property "Value" "TPAD28-2-GP"
			(at 0.0127 -1.6637 0)
			(unlocked yes)
			(layer "B.Fab")
			(hide yes)
			(effects
				(font
					(size 1.016 1.016)
					(thickness 0.1524)
				)
				(justify mirror)
			)
		)
		(property "Device Type" "TPAD28"
			(at 0.0127 -3.1877 0)
			(unlocked yes)
			(layer "B.Fab")
			(hide yes)
			(effects
				(font
					(size 1.016 1.016)
					(thickness 0.1524)
				)
				(justify mirror)
			)
		)
		(duplicate_pad_numbers_are_jumpers no)
		(fp_poly
			(pts
				(arc
					(start 0.3556 0)
					(mid -0.3556 0)
					(end 0.3556 0)
				)
			)
			(stroke
				(width 0)
				(type default)
			)
			(fill no)
			(layer "B.CrtYd")
		)
		(fp_poly
			(pts
				(arc
					(start 0.6096 0)
					(mid -0.6096 0)
					(end 0.6096 0)
				)
			)
			(stroke
				(width 0)
				(type default)
			)
			(fill no)
			(layer "B.Fab")
		)
		(pad "1" smd circle
			(at 0 0 180)
			(size 0.7112 0.7112)
			(layers "B.Cu" "B.Mask" "B.Paste")
			(net "IOC_UART_1_TX")
		)
	)
	(footprint ""
		(layer "B.Cu")
		(at 177.799746 -33.636458)
		(property "Reference" "TP149"
			(at 0 0 0)
			(layer "B.SilkS")
			(hide yes)
			(effects
				(font
					(size 1.27 1.27)
				)
				(justify mirror)
			)
		)
		(property "Value" "TPAD28-2-GP"
			(at 0.0127 -1.6637 0)
			(unlocked yes)
			(layer "B.Fab")
			(hide yes)
			(effects
				(font
					(size 1.016 1.016)
					(thickness 0.1524)
				)
				(justify mirror)
			)
		)
		(property "Device Type" "TPAD28"
			(at 0.0127 -3.1877 0)
			(unlocked yes)
			(layer "B.Fab")
			(hide yes)
			(effects
				(font
					(size 1.016 1.016)
					(thickness 0.1524)
				)
				(justify mirror)
			)
		)
		(duplicate_pad_numbers_are_jumpers no)
		(fp_poly
			(pts
				(arc
					(start 0.3556 0)
					(mid -0.3556 0)
					(end 0.3556 0)
				)
			)
			(stroke
				(width 0)
				(type default)
			)
			(fill no)
			(layer "B.CrtYd")
		)
		(fp_poly
			(pts
				(arc
					(start 0.6096 0)
					(mid -0.6096 0)
					(end 0.6096 0)
				)
			)
			(stroke
				(width 0)
				(type default)
			)
			(fill no)
			(layer "B.Fab")
		)
		(pad "1" smd circle
			(at 0 0 180)
			(size 0.7112 0.7112)
			(layers "B.Cu" "B.Mask" "B.Paste")
			(net "SPARE5")
		)
	)
	(footprint ""
		(layer "B.Cu")
		(at 111.887 -44.2214 180)
		(property "Reference" "C68"
			(at 0 0 0)
			(layer "B.SilkS")
			(hide yes)
			(effects
				(font
					(size 1.27 1.27)
				)
				(justify mirror)
			)
		)
		(property "Value" "SCD01U16V1KX-GP"
			(at 2.8321 -1.7399 180)
			(unlocked yes)
			(layer "B.Fab")
			(hide yes)
			(effects
				(font
					(size 1.016 1.016)
					(thickness 0.1524)
				)
				(justify mirror)
			)
		)
		(property "Device Type" "C0201H13"
			(at 2.8321 -3.2639 180)
			(unlocked yes)
			(layer "B.Fab")
			(hide yes)
			(effects
				(font
					(size 1.016 1.016)
					(thickness 0.1524)
				)
				(justify mirror)
			)
		)
		(duplicate_pad_numbers_are_jumpers no)
		(fp_rect
			(start 0.2794 0.6477)
			(end -0.2794 -0.6477)
			(stroke
				(width 0)
				(type default)
			)
			(fill no)
			(layer "B.CrtYd")
		)
		(fp_rect
			(start 0.2794 0.6477)
			(end -0.2794 -0.6477)
			(stroke
				(width 0)
				(type default)
			)
			(fill no)
			(layer "B.Fab")
		)
		(pad "1" smd custom
			(at 0 -0.2794)
			(size 0.0762 0.0762)
			(layers "B.Cu" "B.Mask" "B.Paste")
			(net "PHY_DPB_TO_SCC_26_DN")
			(options
				(clearance outline)
				(anchor circle)
			)
			(primitives
				(gr_poly
					(pts
						(arc
							(start 0.1524 0.127)
							(mid 0.137521 0.162921)
							(end 0.1016 0.1778)
						)
						(arc
							(start -0.1016 0.1778)
							(mid -0.137521 0.162921)
							(end -0.1524 0.127)
						)
						(arc
							(start -0.1524 -0.127)
							(mid -0.137521 -0.162921)
							(end -0.1016 -0.1778)
						)
						(arc
							(start 0.1016 -0.1778)
							(mid 0.137521 -0.162921)
							(end 0.1524 -0.127)
						)
					)
					(width 0)
					(fill yes)
				)
			)
		)
		(pad "2" smd custom
			(at 0 0.2794)
			(size 0.0762 0.0762)
			(layers "B.Cu" "B.Mask" "B.Paste")
			(net "PHY_DPB_TO_SCC_C_26_DN")
			(options
				(clearance outline)
				(anchor circle)
			)
			(primitives
				(gr_poly
					(pts
						(arc
							(start 0.1524 0.127)
							(mid 0.137521 0.162921)
							(end 0.1016 0.1778)
						)
						(arc
							(start -0.1016 0.1778)
							(mid -0.137521 0.162921)
							(end -0.1524 0.127)
						)
						(arc
							(start -0.1524 -0.127)
							(mid -0.137521 -0.162921)
							(end -0.1016 -0.1778)
						)
						(arc
							(start 0.1016 -0.1778)
							(mid 0.137521 -0.162921)
							(end 0.1524 -0.127)
						)
					)
					(width 0)
					(fill yes)
				)
			)
		)
	)
	(footprint ""
		(layer "B.Cu")
		(at 183.4134 -35.433 -90)
		(property "Reference" "C473"
			(at 0 0 90)
			(layer "B.SilkS")
			(hide yes)
			(effects
				(font
					(size 1.27 1.27)
				)
				(justify mirror)
			)
		)
		(property "Value" "SCD1U6D3V1KX-GP"
			(at 2.8321 -1.7399 270)
			(unlocked yes)
			(layer "B.Fab")
			(hide yes)
			(effects
				(font
					(size 1.016 1.016)
					(thickness 0.1524)
				)
				(justify mirror)
			)
		)
		(property "Device Type" "C0201H13"
			(at 2.8321 -3.2639 270)
			(unlocked yes)
			(layer "B.Fab")
			(hide yes)
			(effects
				(font
					(size 1.016 1.016)
					(thickness 0.1524)
				)
				(justify mirror)
			)
		)
		(duplicate_pad_numbers_are_jumpers no)
		(fp_rect
			(start 0.2794 0.6477)
			(end -0.2794 -0.6477)
			(stroke
				(width 0)
				(type default)
			)
			(fill no)
			(layer "B.CrtYd")
		)
		(fp_rect
			(start 0.2794 0.6477)
			(end -0.2794 -0.6477)
			(stroke
				(width 0)
				(type default)
			)
			(fill no)
			(layer "B.Fab")
		)
		(pad "1" smd custom
			(at 0 -0.2794 90)
			(size 0.0762 0.0762)
			(layers "B.Cu" "B.Mask" "B.Paste")
			(net "P1V8_C")
			(options
				(clearance outline)
				(anchor circle)
			)
			(primitives
				(gr_poly
					(pts
						(arc
							(start 0.1524 0.127)
							(mid 0.137521 0.162921)
							(end 0.1016 0.1778)
						)
						(arc
							(start -0.1016 0.1778)
							(mid -0.137521 0.162921)
							(end -0.1524 0.127)
						)
						(arc
							(start -0.1524 -0.127)
							(mid -0.137521 -0.162921)
							(end -0.1016 -0.1778)
						)
						(arc
							(start 0.1016 -0.1778)
							(mid 0.137521 -0.162921)
							(end 0.1524 -0.127)
						)
					)
					(width 0)
					(fill yes)
				)
			)
		)
		(pad "2" smd custom
			(at 0 0.2794 90)
			(size 0.0762 0.0762)
			(layers "B.Cu" "B.Mask" "B.Paste")
			(net "GND")
			(options
				(clearance outline)
				(anchor circle)
			)
			(primitives
				(gr_poly
					(pts
						(arc
							(start 0.1524 0.127)
							(mid 0.137521 0.162921)
							(end 0.1016 0.1778)
						)
						(arc
							(start -0.1016 0.1778)
							(mid -0.137521 0.162921)
							(end -0.1524 0.127)
						)
						(arc
							(start -0.1524 -0.127)
							(mid -0.137521 -0.162921)
							(end -0.1016 -0.1778)
						)
						(arc
							(start 0.1016 -0.1778)
							(mid 0.137521 -0.162921)
							(end 0.1524 -0.127)
						)
					)
					(width 0)
					(fill yes)
				)
			)
		)
	)
	(footprint ""
		(layer "B.Cu")
		(at 173.7741 -43.46702 -90)
		(property "Reference" "C418"
			(at 0 0 90)
			(layer "B.SilkS")
			(hide yes)
			(effects
				(font
					(size 1.27 1.27)
				)
				(justify mirror)
			)
		)
		(property "Value" "SCD1U6D3V1KX-GP"
			(at 2.8321 -1.7399 270)
			(unlocked yes)
			(layer "B.Fab")
			(hide yes)
			(effects
				(font
					(size 1.016 1.016)
					(thickness 0.1524)
				)
				(justify mirror)
			)
		)
		(property "Device Type" "C0201H13"
			(at 2.8321 -3.2639 270)
			(unlocked yes)
			(layer "B.Fab")
			(hide yes)
			(effects
				(font
					(size 1.016 1.016)
					(thickness 0.1524)
				)
				(justify mirror)
			)
		)
		(duplicate_pad_numbers_are_jumpers no)
		(fp_rect
			(start 0.2794 0.6477)
			(end -0.2794 -0.6477)
			(stroke
				(width 0)
				(type default)
			)
			(fill no)
			(layer "B.CrtYd")
		)
		(fp_rect
			(start 0.2794 0.6477)
			(end -0.2794 -0.6477)
			(stroke
				(width 0)
				(type default)
			)
			(fill no)
			(layer "B.Fab")
		)
		(pad "1" smd custom
			(at 0 -0.2794 90)
			(size 0.0762 0.0762)
			(layers "B.Cu" "B.Mask" "B.Paste")
			(net "P0V975")
			(options
				(clearance outline)
				(anchor circle)
			)
			(primitives
				(gr_poly
					(pts
						(arc
							(start 0.1524 0.127)
							(mid 0.137521 0.162921)
							(end 0.1016 0.1778)
						)
						(arc
							(start -0.1016 0.1778)
							(mid -0.137521 0.162921)
							(end -0.1524 0.127)
						)
						(arc
							(start -0.1524 -0.127)
							(mid -0.137521 -0.162921)
							(end -0.1016 -0.1778)
						)
						(arc
							(start 0.1016 -0.1778)
							(mid 0.137521 -0.162921)
							(end 0.1524 -0.127)
						)
					)
					(width 0)
					(fill yes)
				)
			)
		)
		(pad "2" smd custom
			(at 0 0.2794 90)
			(size 0.0762 0.0762)
			(layers "B.Cu" "B.Mask" "B.Paste")
			(net "GND")
			(options
				(clearance outline)
				(anchor circle)
			)
			(primitives
				(gr_poly
					(pts
						(arc
							(start 0.1524 0.127)
							(mid 0.137521 0.162921)
							(end 0.1016 0.1778)
						)
						(arc
							(start -0.1016 0.1778)
							(mid -0.137521 0.162921)
							(end -0.1524 0.127)
						)
						(arc
							(start -0.1524 -0.127)
							(mid -0.137521 -0.162921)
							(end -0.1016 -0.1778)
						)
						(arc
							(start 0.1016 -0.1778)
							(mid 0.137521 -0.162921)
							(end 0.1524 -0.127)
						)
					)
					(width 0)
					(fill yes)
				)
			)
		)
	)
	(footprint ""
		(layer "B.Cu")
		(at 124.2441 -71.501 -90)
		(property "Reference" "C583"
			(at 0 0 90)
			(layer "B.SilkS")
			(hide yes)
			(effects
				(font
					(size 1.27 1.27)
				)
				(justify mirror)
			)
		)
		(property "Value" "SCD1U6D3V1KX-GP"
			(at 2.8321 -1.7399 270)
			(unlocked yes)
			(layer "B.Fab")
			(hide yes)
			(effects
				(font
					(size 1.016 1.016)
					(thickness 0.1524)
				)
				(justify mirror)
			)
		)
		(property "Device Type" "C0201H13"
			(at 2.8321 -3.2639 270)
			(unlocked yes)
			(layer "B.Fab")
			(hide yes)
			(effects
				(font
					(size 1.016 1.016)
					(thickness 0.1524)
				)
				(justify mirror)
			)
		)
		(duplicate_pad_numbers_are_jumpers no)
		(fp_rect
			(start 0.2794 0.6477)
			(end -0.2794 -0.6477)
			(stroke
				(width 0)
				(type default)
			)
			(fill no)
			(layer "B.CrtYd")
		)
		(fp_rect
			(start 0.2794 0.6477)
			(end -0.2794 -0.6477)
			(stroke
				(width 0)
				(type default)
			)
			(fill no)
			(layer "B.Fab")
		)
		(pad "1" smd custom
			(at 0 -0.2794 90)
			(size 0.0762 0.0762)
			(layers "B.Cu" "B.Mask" "B.Paste")
			(net "GB_VDDA")
			(options
				(clearance outline)
				(anchor circle)
			)
			(primitives
				(gr_poly
					(pts
						(arc
							(start 0.1524 0.127)
							(mid 0.137521 0.162921)
							(end 0.1016 0.1778)
						)
						(arc
							(start -0.1016 0.1778)
							(mid -0.137521 0.162921)
							(end -0.1524 0.127)
						)
						(arc
							(start -0.1524 -0.127)
							(mid -0.137521 -0.162921)
							(end -0.1016 -0.1778)
						)
						(arc
							(start 0.1016 -0.1778)
							(mid 0.137521 -0.162921)
							(end 0.1524 -0.127)
						)
					)
					(width 0)
					(fill yes)
				)
			)
		)
		(pad "2" smd custom
			(at 0 0.2794 90)
			(size 0.0762 0.0762)
			(layers "B.Cu" "B.Mask" "B.Paste")
			(net "GND")
			(options
				(clearance outline)
				(anchor circle)
			)
			(primitives
				(gr_poly
					(pts
						(arc
							(start 0.1524 0.127)
							(mid 0.137521 0.162921)
							(end 0.1016 0.1778)
						)
						(arc
							(start -0.1016 0.1778)
							(mid -0.137521 0.162921)
							(end -0.1524 0.127)
						)
						(arc
							(start -0.1524 -0.127)
							(mid -0.137521 -0.162921)
							(end -0.1016 -0.1778)
						)
						(arc
							(start 0.1016 -0.1778)
							(mid 0.137521 -0.162921)
							(end 0.1524 -0.127)
						)
					)
					(width 0)
					(fill yes)
				)
			)
		)
	)
	(footprint ""
		(layer "B.Cu")
		(at 104.495092 -58.547)
		(property "Reference" "C152"
			(at 0 0 0)
			(layer "B.SilkS")
			(hide yes)
			(effects
				(font
					(size 1.27 1.27)
				)
				(justify mirror)
			)
		)
		(property "Value" "SCD1U6D3V1KX-GP"
			(at 2.8321 -1.7399 0)
			(unlocked yes)
			(layer "B.Fab")
			(hide yes)
			(effects
				(font
					(size 1.016 1.016)
					(thickness 0.1524)
				)
				(justify mirror)
			)
		)
		(property "Device Type" "C0201H13"
			(at 2.8321 -3.2639 0)
			(unlocked yes)
			(layer "B.Fab")
			(hide yes)
			(effects
				(font
					(size 1.016 1.016)
					(thickness 0.1524)
				)
				(justify mirror)
			)
		)
		(duplicate_pad_numbers_are_jumpers no)
		(fp_rect
			(start 0.2794 0.6477)
			(end -0.2794 -0.6477)
			(stroke
				(width 0)
				(type default)
			)
			(fill no)
			(layer "B.CrtYd")
		)
		(fp_rect
			(start 0.2794 0.6477)
			(end -0.2794 -0.6477)
			(stroke
				(width 0)
				(type default)
			)
			(fill no)
			(layer "B.Fab")
		)
		(pad "1" smd custom
			(at 0 -0.2794 180)
			(size 0.0762 0.0762)
			(layers "B.Cu" "B.Mask" "B.Paste")
			(net "P1V8_E")
			(options
				(clearance outline)
				(anchor circle)
			)
			(primitives
				(gr_poly
					(pts
						(arc
							(start 0.1524 0.127)
							(mid 0.137521 0.162921)
							(end 0.1016 0.1778)
						)
						(arc
							(start -0.1016 0.1778)
							(mid -0.137521 0.162921)
							(end -0.1524 0.127)
						)
						(arc
							(start -0.1524 -0.127)
							(mid -0.137521 -0.162921)
							(end -0.1016 -0.1778)
						)
						(arc
							(start 0.1016 -0.1778)
							(mid 0.137521 -0.162921)
							(end 0.1524 -0.127)
						)
					)
					(width 0)
					(fill yes)
				)
			)
		)
		(pad "2" smd custom
			(at 0 0.2794 180)
			(size 0.0762 0.0762)
			(layers "B.Cu" "B.Mask" "B.Paste")
			(net "GND")
			(options
				(clearance outline)
				(anchor circle)
			)
			(primitives
				(gr_poly
					(pts
						(arc
							(start 0.1524 0.127)
							(mid 0.137521 0.162921)
							(end 0.1016 0.1778)
						)
						(arc
							(start -0.1016 0.1778)
							(mid -0.137521 0.162921)
							(end -0.1524 0.127)
						)
						(arc
							(start -0.1524 -0.127)
							(mid -0.137521 -0.162921)
							(end -0.1016 -0.1778)
						)
						(arc
							(start 0.1016 -0.1778)
							(mid 0.137521 -0.162921)
							(end 0.1524 -0.127)
						)
					)
					(width 0)
					(fill yes)
				)
			)
		)
	)
	(footprint ""
		(layer "B.Cu")
		(at 70.485 -62.484 90)
		(property "Reference" "R158"
			(at 0 0 90)
			(layer "B.SilkS")
			(hide yes)
			(effects
				(font
					(size 1.27 1.27)
				)
				(justify mirror)
			)
		)
		(property "Value" "D51R3F-2-GP"
			(at 0.0254 -2.5146 90)
			(unlocked yes)
			(layer "B.Fab")
			(hide yes)
			(effects
				(font
					(size 1.016 1.016)
					(thickness 0.1524)
				)
				(justify mirror)
			)
		)
		(property "Device Type" "R603H22"
			(at 0.0254 -4.0386 90)
			(unlocked yes)
			(layer "B.Fab")
			(hide yes)
			(effects
				(font
					(size 1.016 1.016)
					(thickness 0.1524)
				)
				(justify mirror)
			)
		)
		(duplicate_pad_numbers_are_jumpers no)
		(fp_line
			(start 0.4826 0)
			(end 0.2032 0)
			(stroke
				(width 0.2032)
				(type default)
			)
			(layer "B.SilkS")
		)
		(fp_line
			(start -0.2032 0)
			(end -0.4826 0)
			(stroke
				(width 0.2032)
				(type default)
			)
			(layer "B.SilkS")
		)
		(fp_rect
			(start 0.5842 1.3335)
			(end -0.5842 -1.3335)
			(stroke
				(width 0)
				(type default)
			)
			(fill no)
			(layer "B.CrtYd")
		)
		(fp_rect
			(start 0.5842 1.3335)
			(end -0.5842 -1.3335)
			(stroke
				(width 0)
				(type default)
			)
			(fill no)
			(layer "B.Fab")
		)
		(pad "1" smd custom
			(at 0 -0.762 270)
			(size 0.2159 0.2159)
			(layers "B.Cu" "B.Mask" "B.Paste")
			(net "P0V9")
			(options
				(clearance outline)
				(anchor circle)
			)
			(primitives
				(gr_poly
					(pts
						(arc
							(start -0.3302 0.4318)
							(mid -0.402042 0.402042)
							(end -0.4318 0.3302)
						)
						(arc
							(start -0.4318 -0.3302)
							(mid -0.402042 -0.402042)
							(end -0.3302 -0.4318)
						)
						(arc
							(start 0.3302 -0.4318)
							(mid 0.402042 -0.402042)
							(end 0.4318 -0.3302)
						)
						(arc
							(start 0.4318 0.3302)
							(mid 0.402042 0.402042)
							(end 0.3302 0.4318)
						)
					)
					(width 0)
					(fill yes)
				)
			)
		)
		(pad "2" smd custom
			(at 0 0.762 270)
			(size 0.2159 0.2159)
			(layers "B.Cu" "B.Mask" "B.Paste")
			(net "GB_VDDA")
			(options
				(clearance outline)
				(anchor circle)
			)
			(primitives
				(gr_poly
					(pts
						(arc
							(start -0.3302 0.4318)
							(mid -0.402042 0.402042)
							(end -0.4318 0.3302)
						)
						(arc
							(start -0.4318 -0.3302)
							(mid -0.402042 -0.402042)
							(end -0.3302 -0.4318)
						)
						(arc
							(start 0.3302 -0.4318)
							(mid 0.402042 -0.402042)
							(end 0.4318 -0.3302)
						)
						(arc
							(start 0.4318 0.3302)
							(mid 0.402042 0.402042)
							(end 0.3302 0.4318)
						)
					)
					(width 0)
					(fill yes)
				)
			)
		)
	)
	(footprint ""
		(layer "B.Cu")
		(at 122.6185 -57.4802)
		(property "Reference" "C591"
			(at 0 0 0)
			(layer "B.SilkS")
			(hide yes)
			(effects
				(font
					(size 1.27 1.27)
				)
				(justify mirror)
			)
		)
		(property "Value" "SCD1U6D3V1KX-GP"
			(at 2.8321 -1.7399 0)
			(unlocked yes)
			(layer "B.Fab")
			(hide yes)
			(effects
				(font
					(size 1.016 1.016)
					(thickness 0.1524)
				)
				(justify mirror)
			)
		)
		(property "Device Type" "C0201H13"
			(at 2.8321 -3.2639 0)
			(unlocked yes)
			(layer "B.Fab")
			(hide yes)
			(effects
				(font
					(size 1.016 1.016)
					(thickness 0.1524)
				)
				(justify mirror)
			)
		)
		(duplicate_pad_numbers_are_jumpers no)
		(fp_rect
			(start 0.2794 0.6477)
			(end -0.2794 -0.6477)
			(stroke
				(width 0)
				(type default)
			)
			(fill no)
			(layer "B.CrtYd")
		)
		(fp_rect
			(start 0.2794 0.6477)
			(end -0.2794 -0.6477)
			(stroke
				(width 0)
				(type default)
			)
			(fill no)
			(layer "B.Fab")
		)
		(pad "1" smd custom
			(at 0 -0.2794 180)
			(size 0.0762 0.0762)
			(layers "B.Cu" "B.Mask" "B.Paste")
			(net "GB_VDDA")
			(options
				(clearance outline)
				(anchor circle)
			)
			(primitives
				(gr_poly
					(pts
						(arc
							(start 0.1524 0.127)
							(mid 0.137521 0.162921)
							(end 0.1016 0.1778)
						)
						(arc
							(start -0.1016 0.1778)
							(mid -0.137521 0.162921)
							(end -0.1524 0.127)
						)
						(arc
							(start -0.1524 -0.127)
							(mid -0.137521 -0.162921)
							(end -0.1016 -0.1778)
						)
						(arc
							(start 0.1016 -0.1778)
							(mid 0.137521 -0.162921)
							(end 0.1524 -0.127)
						)
					)
					(width 0)
					(fill yes)
				)
			)
		)
		(pad "2" smd custom
			(at 0 0.2794 180)
			(size 0.0762 0.0762)
			(layers "B.Cu" "B.Mask" "B.Paste")
			(net "GND")
			(options
				(clearance outline)
				(anchor circle)
			)
			(primitives
				(gr_poly
					(pts
						(arc
							(start 0.1524 0.127)
							(mid 0.137521 0.162921)
							(end 0.1016 0.1778)
						)
						(arc
							(start -0.1016 0.1778)
							(mid -0.137521 0.162921)
							(end -0.1524 0.127)
						)
						(arc
							(start -0.1524 -0.127)
							(mid -0.137521 -0.162921)
							(end -0.1016 -0.1778)
						)
						(arc
							(start 0.1016 -0.1778)
							(mid 0.137521 -0.162921)
							(end 0.1524 -0.127)
						)
					)
					(width 0)
					(fill yes)
				)
			)
		)
	)
	(footprint ""
		(layer "B.Cu")
		(at 116.501418 -80.51927 180)
		(property "Reference" "C149"
			(at 0 0 0)
			(layer "B.SilkS")
			(hide yes)
			(effects
				(font
					(size 1.27 1.27)
				)
				(justify mirror)
			)
		)
		(property "Value" "SCD1U6D3V1KX-GP"
			(at 2.8321 -1.7399 180)
			(unlocked yes)
			(layer "B.Fab")
			(hide yes)
			(effects
				(font
					(size 1.016 1.016)
					(thickness 0.1524)
				)
				(justify mirror)
			)
		)
		(property "Device Type" "C0201H13"
			(at 2.8321 -3.2639 180)
			(unlocked yes)
			(layer "B.Fab")
			(hide yes)
			(effects
				(font
					(size 1.016 1.016)
					(thickness 0.1524)
				)
				(justify mirror)
			)
		)
		(duplicate_pad_numbers_are_jumpers no)
		(fp_rect
			(start 0.2794 0.6477)
			(end -0.2794 -0.6477)
			(stroke
				(width 0)
				(type default)
			)
			(fill no)
			(layer "B.CrtYd")
		)
		(fp_rect
			(start 0.2794 0.6477)
			(end -0.2794 -0.6477)
			(stroke
				(width 0)
				(type default)
			)
			(fill no)
			(layer "B.Fab")
		)
		(pad "1" smd custom
			(at 0 -0.2794)
			(size 0.0762 0.0762)
			(layers "B.Cu" "B.Mask" "B.Paste")
			(net "P1V8_E")
			(options
				(clearance outline)
				(anchor circle)
			)
			(primitives
				(gr_poly
					(pts
						(arc
							(start 0.1524 0.127)
							(mid 0.137521 0.162921)
							(end 0.1016 0.1778)
						)
						(arc
							(start -0.1016 0.1778)
							(mid -0.137521 0.162921)
							(end -0.1524 0.127)
						)
						(arc
							(start -0.1524 -0.127)
							(mid -0.137521 -0.162921)
							(end -0.1016 -0.1778)
						)
						(arc
							(start 0.1016 -0.1778)
							(mid 0.137521 -0.162921)
							(end 0.1524 -0.127)
						)
					)
					(width 0)
					(fill yes)
				)
			)
		)
		(pad "2" smd custom
			(at 0 0.2794)
			(size 0.0762 0.0762)
			(layers "B.Cu" "B.Mask" "B.Paste")
			(net "GND")
			(options
				(clearance outline)
				(anchor circle)
			)
			(primitives
				(gr_poly
					(pts
						(arc
							(start 0.1524 0.127)
							(mid 0.137521 0.162921)
							(end 0.1016 0.1778)
						)
						(arc
							(start -0.1016 0.1778)
							(mid -0.137521 0.162921)
							(end -0.1524 0.127)
						)
						(arc
							(start -0.1524 -0.127)
							(mid -0.137521 -0.162921)
							(end -0.1016 -0.1778)
						)
						(arc
							(start 0.1016 -0.1778)
							(mid 0.137521 -0.162921)
							(end 0.1524 -0.127)
						)
					)
					(width 0)
					(fill yes)
				)
			)
		)
	)
	(footprint ""
		(layer "B.Cu")
		(at 168.2496 -32.6771 -90)
		(property "Reference" "C381"
			(at 0 0 90)
			(layer "B.SilkS")
			(hide yes)
			(effects
				(font
					(size 1.27 1.27)
				)
				(justify mirror)
			)
		)
		(property "Value" "SCD1U16V2KX-3GP"
			(at -1.1811 -2.7051 270)
			(unlocked yes)
			(layer "B.Fab")
			(hide yes)
			(effects
				(font
					(size 1.016 1.016)
					(thickness 0.1524)
				)
				(justify mirror)
			)
		)
		(property "Device Type" "C402H22"
			(at -1.1811 -4.2291 270)
			(unlocked yes)
			(layer "B.Fab")
			(hide yes)
			(effects
				(font
					(size 1.016 1.016)
					(thickness 0.1524)
				)
				(justify mirror)
			)
		)
		(duplicate_pad_numbers_are_jumpers no)
		(fp_rect
			(start 0.4318 0.9525)
			(end -0.4318 -0.9525)
			(stroke
				(width 0)
				(type default)
			)
			(fill no)
			(layer "B.CrtYd")
		)
		(fp_rect
			(start 0.4318 0.9525)
			(end -0.4318 -0.9525)
			(stroke
				(width 0)
				(type default)
			)
			(fill no)
			(layer "B.Fab")
		)
		(pad "1" smd custom
			(at 0 -0.4445 90)
			(size 0.1524 0.1524)
			(layers "B.Cu" "B.Mask" "B.Paste")
			(net "PCE_VDDH")
			(options
				(clearance outline)
				(anchor circle)
			)
			(primitives
				(gr_poly
					(pts
						(arc
							(start 0.3048 0.2032)
							(mid 0.275042 0.275042)
							(end 0.2032 0.3048)
						)
						(arc
							(start -0.2032 0.3048)
							(mid -0.275042 0.275042)
							(end -0.3048 0.2032)
						)
						(arc
							(start -0.3048 -0.2032)
							(mid -0.275042 -0.275042)
							(end -0.2032 -0.3048)
						)
						(arc
							(start 0.2032 -0.3048)
							(mid 0.275042 -0.275042)
							(end 0.3048 -0.2032)
						)
					)
					(width 0)
					(fill yes)
				)
			)
		)
		(pad "2" smd custom
			(at 0 0.4445 90)
			(size 0.1524 0.1524)
			(layers "B.Cu" "B.Mask" "B.Paste")
			(net "GND")
			(options
				(clearance outline)
				(anchor circle)
			)
			(primitives
				(gr_poly
					(pts
						(arc
							(start 0.3048 0.2032)
							(mid 0.275042 0.275042)
							(end 0.2032 0.3048)
						)
						(arc
							(start -0.2032 0.3048)
							(mid -0.275042 0.275042)
							(end -0.3048 0.2032)
						)
						(arc
							(start -0.3048 -0.2032)
							(mid -0.275042 -0.275042)
							(end -0.2032 -0.3048)
						)
						(arc
							(start 0.2032 -0.3048)
							(mid 0.275042 -0.275042)
							(end 0.3048 -0.2032)
						)
					)
					(width 0)
					(fill yes)
				)
			)
		)
	)
	(footprint ""
		(layer "B.Cu")
		(at 122.4788 -62.484 -90)
		(property "Reference" "C301"
			(at 0 0 90)
			(layer "B.SilkS")
			(hide yes)
			(effects
				(font
					(size 1.27 1.27)
				)
				(justify mirror)
			)
		)
		(property "Value" "SCD1U6D3V1KX-GP"
			(at 2.8321 -1.7399 270)
			(unlocked yes)
			(layer "B.Fab")
			(hide yes)
			(effects
				(font
					(size 1.016 1.016)
					(thickness 0.1524)
				)
				(justify mirror)
			)
		)
		(property "Device Type" "C0201H13"
			(at 2.8321 -3.2639 270)
			(unlocked yes)
			(layer "B.Fab")
			(hide yes)
			(effects
				(font
					(size 1.016 1.016)
					(thickness 0.1524)
				)
				(justify mirror)
			)
		)
		(duplicate_pad_numbers_are_jumpers no)
		(fp_rect
			(start 0.2794 0.6477)
			(end -0.2794 -0.6477)
			(stroke
				(width 0)
				(type default)
			)
			(fill no)
			(layer "B.CrtYd")
		)
		(fp_rect
			(start 0.2794 0.6477)
			(end -0.2794 -0.6477)
			(stroke
				(width 0)
				(type default)
			)
			(fill no)
			(layer "B.Fab")
		)
		(pad "1" smd custom
			(at 0 -0.2794 90)
			(size 0.0762 0.0762)
			(layers "B.Cu" "B.Mask" "B.Paste")
			(net "GB_VDDA")
			(options
				(clearance outline)
				(anchor circle)
			)
			(primitives
				(gr_poly
					(pts
						(arc
							(start 0.1524 0.127)
							(mid 0.137521 0.162921)
							(end 0.1016 0.1778)
						)
						(arc
							(start -0.1016 0.1778)
							(mid -0.137521 0.162921)
							(end -0.1524 0.127)
						)
						(arc
							(start -0.1524 -0.127)
							(mid -0.137521 -0.162921)
							(end -0.1016 -0.1778)
						)
						(arc
							(start 0.1016 -0.1778)
							(mid 0.137521 -0.162921)
							(end 0.1524 -0.127)
						)
					)
					(width 0)
					(fill yes)
				)
			)
		)
		(pad "2" smd custom
			(at 0 0.2794 90)
			(size 0.0762 0.0762)
			(layers "B.Cu" "B.Mask" "B.Paste")
			(net "GND")
			(options
				(clearance outline)
				(anchor circle)
			)
			(primitives
				(gr_poly
					(pts
						(arc
							(start 0.1524 0.127)
							(mid 0.137521 0.162921)
							(end 0.1016 0.1778)
						)
						(arc
							(start -0.1016 0.1778)
							(mid -0.137521 0.162921)
							(end -0.1524 0.127)
						)
						(arc
							(start -0.1524 -0.127)
							(mid -0.137521 -0.162921)
							(end -0.1016 -0.1778)
						)
						(arc
							(start 0.1016 -0.1778)
							(mid 0.137521 -0.162921)
							(end 0.1524 -0.127)
						)
					)
					(width 0)
					(fill yes)
				)
			)
		)
	)
	(footprint ""
		(layer "B.Cu")
		(at 76.454 -41.148 180)
		(property "Reference" "C310"
			(at 0 0 0)
			(layer "B.SilkS")
			(hide yes)
			(effects
				(font
					(size 1.27 1.27)
				)
				(justify mirror)
			)
		)
		(property "Value" "SC22U6D3V3MX-9-GP-U"
			(at 0 -2.8194 180)
			(unlocked yes)
			(layer "B.Fab")
			(hide yes)
			(effects
				(font
					(size 1.016 1.016)
					(thickness 0.1524)
				)
				(justify mirror)
			)
		)
		(property "Device Type" "C603H40"
			(at 0 -4.3434 180)
			(unlocked yes)
			(layer "B.Fab")
			(hide yes)
			(effects
				(font
					(size 1.016 1.016)
					(thickness 0.1524)
				)
				(justify mirror)
			)
		)
		(duplicate_pad_numbers_are_jumpers no)
		(fp_line
			(start -0.508 0)
			(end 0.508 0)
			(stroke
				(width 0.2032)
				(type default)
			)
			(layer "B.SilkS")
		)
		(fp_rect
			(start 0.5842 1.3335)
			(end -0.5842 -1.3335)
			(stroke
				(width 0)
				(type default)
			)
			(fill no)
			(layer "B.CrtYd")
		)
		(fp_rect
			(start 0.5842 1.3335)
			(end -0.5842 -1.3335)
			(stroke
				(width 0)
				(type default)
			)
			(fill no)
			(layer "B.Fab")
		)
		(pad "1" smd custom
			(at 0 -0.762)
			(size 0.2159 0.2159)
			(layers "B.Cu" "B.Mask" "B.Paste")
			(net "GB_VDDA")
			(options
				(clearance outline)
				(anchor circle)
			)
			(primitives
				(gr_poly
					(pts
						(arc
							(start -0.3302 0.4318)
							(mid -0.402042 0.402042)
							(end -0.4318 0.3302)
						)
						(arc
							(start -0.4318 -0.3302)
							(mid -0.402042 -0.402042)
							(end -0.3302 -0.4318)
						)
						(arc
							(start 0.3302 -0.4318)
							(mid 0.402042 -0.402042)
							(end 0.4318 -0.3302)
						)
						(arc
							(start 0.4318 0.3302)
							(mid 0.402042 0.402042)
							(end 0.3302 0.4318)
						)
					)
					(width 0)
					(fill yes)
				)
			)
		)
		(pad "2" smd custom
			(at 0 0.762)
			(size 0.2159 0.2159)
			(layers "B.Cu" "B.Mask" "B.Paste")
			(net "GND")
			(options
				(clearance outline)
				(anchor circle)
			)
			(primitives
				(gr_poly
					(pts
						(arc
							(start -0.3302 0.4318)
							(mid -0.402042 0.402042)
							(end -0.4318 0.3302)
						)
						(arc
							(start -0.4318 -0.3302)
							(mid -0.402042 -0.402042)
							(end -0.3302 -0.4318)
						)
						(arc
							(start 0.3302 -0.4318)
							(mid 0.402042 -0.402042)
							(end 0.4318 -0.3302)
						)
						(arc
							(start 0.4318 0.3302)
							(mid 0.402042 0.402042)
							(end 0.3302 0.4318)
						)
					)
					(width 0)
					(fill yes)
				)
			)
		)
	)
	(footprint ""
		(layer "B.Cu")
		(at 130.429 -78.74 -90)
		(property "Reference" "C137"
			(at 0 0 90)
			(layer "B.SilkS")
			(hide yes)
			(effects
				(font
					(size 1.27 1.27)
				)
				(justify mirror)
			)
		)
		(property "Value" "SCD1U6D3V1KX-GP"
			(at 2.8321 -1.7399 270)
			(unlocked yes)
			(layer "B.Fab")
			(hide yes)
			(effects
				(font
					(size 1.016 1.016)
					(thickness 0.1524)
				)
				(justify mirror)
			)
		)
		(property "Device Type" "C0201H13"
			(at 2.8321 -3.2639 270)
			(unlocked yes)
			(layer "B.Fab")
			(hide yes)
			(effects
				(font
					(size 1.016 1.016)
					(thickness 0.1524)
				)
				(justify mirror)
			)
		)
		(duplicate_pad_numbers_are_jumpers no)
		(fp_rect
			(start 0.2794 0.6477)
			(end -0.2794 -0.6477)
			(stroke
				(width 0)
				(type default)
			)
			(fill no)
			(layer "B.CrtYd")
		)
		(fp_rect
			(start 0.2794 0.6477)
			(end -0.2794 -0.6477)
			(stroke
				(width 0)
				(type default)
			)
			(fill no)
			(layer "B.Fab")
		)
		(pad "1" smd custom
			(at 0 -0.2794 90)
			(size 0.0762 0.0762)
			(layers "B.Cu" "B.Mask" "B.Paste")
			(net "P1V8_E")
			(options
				(clearance outline)
				(anchor circle)
			)
			(primitives
				(gr_poly
					(pts
						(arc
							(start 0.1524 0.127)
							(mid 0.137521 0.162921)
							(end 0.1016 0.1778)
						)
						(arc
							(start -0.1016 0.1778)
							(mid -0.137521 0.162921)
							(end -0.1524 0.127)
						)
						(arc
							(start -0.1524 -0.127)
							(mid -0.137521 -0.162921)
							(end -0.1016 -0.1778)
						)
						(arc
							(start 0.1016 -0.1778)
							(mid 0.137521 -0.162921)
							(end 0.1524 -0.127)
						)
					)
					(width 0)
					(fill yes)
				)
			)
		)
		(pad "2" smd custom
			(at 0 0.2794 90)
			(size 0.0762 0.0762)
			(layers "B.Cu" "B.Mask" "B.Paste")
			(net "GND")
			(options
				(clearance outline)
				(anchor circle)
			)
			(primitives
				(gr_poly
					(pts
						(arc
							(start 0.1524 0.127)
							(mid 0.137521 0.162921)
							(end 0.1016 0.1778)
						)
						(arc
							(start -0.1016 0.1778)
							(mid -0.137521 0.162921)
							(end -0.1524 0.127)
						)
						(arc
							(start -0.1524 -0.127)
							(mid -0.137521 -0.162921)
							(end -0.1016 -0.1778)
						)
						(arc
							(start 0.1016 -0.1778)
							(mid 0.137521 -0.162921)
							(end 0.1524 -0.127)
						)
					)
					(width 0)
					(fill yes)
				)
			)
		)
	)
	(footprint ""
		(layer "B.Cu")
		(at 129.417318 -87.260684)
		(property "Reference" "R212"
			(at 0 0 0)
			(layer "B.SilkS")
			(hide yes)
			(effects
				(font
					(size 1.27 1.27)
				)
				(justify mirror)
			)
		)
		(property "Value" "4K75R2F-1-GP"
			(at -0.064008 -3.993896 0)
			(unlocked yes)
			(layer "B.Fab")
			(hide yes)
			(effects
				(font
					(size 1.016 1.016)
					(thickness 0.1524)
				)
				(justify mirror)
			)
		)
		(property "Device Type" "R402H16"
			(at -0.064008 -5.517896 0)
			(unlocked yes)
			(layer "B.Fab")
			(hide yes)
			(effects
				(font
					(size 1.016 1.016)
					(thickness 0.1524)
				)
				(justify mirror)
			)
		)
		(duplicate_pad_numbers_are_jumpers no)
		(fp_line
			(start -0.508 -0.9398)
			(end 0.508 -0.9398)
			(stroke
				(width 0.1524)
				(type default)
			)
			(layer "B.SilkS")
		)
		(fp_line
			(start 0.508 -0.9398)
			(end 0.508 0.9398)
			(stroke
				(width 0.1524)
				(type default)
			)
			(layer "B.SilkS")
		)
		(fp_rect
			(start 0.508 0.9398)
			(end -0.508 -0.9398)
			(stroke
				(width 0)
				(type default)
			)
			(fill no)
			(layer "B.CrtYd")
		)
		(fp_rect
			(start 0.508 0.9398)
			(end -0.508 -0.9398)
			(stroke
				(width 0)
				(type default)
			)
			(fill no)
			(layer "B.Fab")
		)
		(pad "1" smd custom
			(at 0 -0.4445 180)
			(size 0.1397 0.1397)
			(layers "B.Cu" "B.Mask" "B.Paste")
			(net "P1V8_E")
			(options
				(clearance outline)
				(anchor circle)
			)
			(primitives
				(gr_poly
					(pts
						(arc
							(start -0.1778 0.2794)
							(mid -0.249642 0.249642)
							(end -0.2794 0.1778)
						)
						(arc
							(start -0.2794 -0.1778)
							(mid -0.249642 -0.249642)
							(end -0.1778 -0.2794)
						)
						(arc
							(start 0.1778 -0.2794)
							(mid 0.249642 -0.249642)
							(end 0.2794 -0.1778)
						)
						(arc
							(start 0.2794 0.1778)
							(mid 0.249642 0.249642)
							(end 0.1778 0.2794)
						)
					)
					(width 0)
					(fill yes)
				)
			)
		)
		(pad "2" smd custom
			(at 0 0.4445 180)
			(size 0.1397 0.1397)
			(layers "B.Cu" "B.Mask" "B.Paste")
			(net "ICE_TMS")
			(options
				(clearance outline)
				(anchor circle)
			)
			(primitives
				(gr_poly
					(pts
						(arc
							(start -0.1778 0.2794)
							(mid -0.249642 0.249642)
							(end -0.2794 0.1778)
						)
						(arc
							(start -0.2794 -0.1778)
							(mid -0.249642 -0.249642)
							(end -0.1778 -0.2794)
						)
						(arc
							(start 0.1778 -0.2794)
							(mid 0.249642 -0.249642)
							(end 0.2794 -0.1778)
						)
						(arc
							(start 0.2794 0.1778)
							(mid 0.249642 0.249642)
							(end 0.1778 0.2794)
						)
					)
					(width 0)
					(fill yes)
				)
			)
		)
	)
	(footprint ""
		(layer "B.Cu")
		(at 180.848 -31.75 -90)
		(property "Reference" "C469"
			(at 0 0 90)
			(layer "B.SilkS")
			(hide yes)
			(effects
				(font
					(size 1.27 1.27)
				)
				(justify mirror)
			)
		)
		(property "Value" "SCD1U6D3V1KX-GP"
			(at 2.8321 -1.7399 270)
			(unlocked yes)
			(layer "B.Fab")
			(hide yes)
			(effects
				(font
					(size 1.016 1.016)
					(thickness 0.1524)
				)
				(justify mirror)
			)
		)
		(property "Device Type" "C0201H13"
			(at 2.8321 -3.2639 270)
			(unlocked yes)
			(layer "B.Fab")
			(hide yes)
			(effects
				(font
					(size 1.016 1.016)
					(thickness 0.1524)
				)
				(justify mirror)
			)
		)
		(duplicate_pad_numbers_are_jumpers no)
		(fp_rect
			(start 0.2794 0.6477)
			(end -0.2794 -0.6477)
			(stroke
				(width 0)
				(type default)
			)
			(fill no)
			(layer "B.CrtYd")
		)
		(fp_rect
			(start 0.2794 0.6477)
			(end -0.2794 -0.6477)
			(stroke
				(width 0)
				(type default)
			)
			(fill no)
			(layer "B.Fab")
		)
		(pad "1" smd custom
			(at 0 -0.2794 90)
			(size 0.0762 0.0762)
			(layers "B.Cu" "B.Mask" "B.Paste")
			(net "P1V8_C")
			(options
				(clearance outline)
				(anchor circle)
			)
			(primitives
				(gr_poly
					(pts
						(arc
							(start 0.1524 0.127)
							(mid 0.137521 0.162921)
							(end 0.1016 0.1778)
						)
						(arc
							(start -0.1016 0.1778)
							(mid -0.137521 0.162921)
							(end -0.1524 0.127)
						)
						(arc
							(start -0.1524 -0.127)
							(mid -0.137521 -0.162921)
							(end -0.1016 -0.1778)
						)
						(arc
							(start 0.1016 -0.1778)
							(mid 0.137521 -0.162921)
							(end 0.1524 -0.127)
						)
					)
					(width 0)
					(fill yes)
				)
			)
		)
		(pad "2" smd custom
			(at 0 0.2794 90)
			(size 0.0762 0.0762)
			(layers "B.Cu" "B.Mask" "B.Paste")
			(net "GND")
			(options
				(clearance outline)
				(anchor circle)
			)
			(primitives
				(gr_poly
					(pts
						(arc
							(start 0.1524 0.127)
							(mid 0.137521 0.162921)
							(end 0.1016 0.1778)
						)
						(arc
							(start -0.1016 0.1778)
							(mid -0.137521 0.162921)
							(end -0.1524 0.127)
						)
						(arc
							(start -0.1524 -0.127)
							(mid -0.137521 -0.162921)
							(end -0.1016 -0.1778)
						)
						(arc
							(start 0.1016 -0.1778)
							(mid 0.137521 -0.162921)
							(end 0.1524 -0.127)
						)
					)
					(width 0)
					(fill yes)
				)
			)
		)
	)
	(footprint ""
		(layer "B.Cu")
		(at 107.88523 -59.3217 -90)
		(property "Reference" "C250"
			(at 0 0 90)
			(layer "B.SilkS")
			(hide yes)
			(effects
				(font
					(size 1.27 1.27)
				)
				(justify mirror)
			)
		)
		(property "Value" "SC1U6D3V1MX-GP"
			(at -1.9177 2.0193 270)
			(unlocked yes)
			(layer "B.Fab")
			(hide yes)
			(effects
				(font
					(size 1.016 1.016)
					(thickness 0.1524)
				)
				(justify mirror)
			)
		)
		(property "Device Type" "C0201H14"
			(at -1.9177 0.4953 270)
			(unlocked yes)
			(layer "B.Fab")
			(hide yes)
			(effects
				(font
					(size 1.016 1.016)
					(thickness 0.1524)
				)
				(justify mirror)
			)
		)
		(duplicate_pad_numbers_are_jumpers no)
		(fp_rect
			(start 0.1524 0.3048)
			(end -0.1524 -0.3048)
			(stroke
				(width 0)
				(type default)
			)
			(fill no)
			(layer "B.CrtYd")
		)
		(fp_poly
			(pts
				(xy 0.2794 0.6477) (xy 0.2794 -0.6477) (xy -0.2794 -0.6477) (xy -0.2794 -0.1905) (xy -0.1524 -0.1905)
				(xy -0.1524 -0.3048) (xy 0.1524 -0.3048) (xy 0.1524 0.3048) (xy -0.1524 0.3048) (xy -0.1524 -0.1778)
				(xy -0.2794 -0.1778) (xy -0.2794 0.6477)
			)
			(stroke
				(width 0)
				(type default)
			)
			(fill no)
			(layer "B.CrtYd")
		)
		(fp_rect
			(start 0.2794 0.6477)
			(end -0.2794 -0.6477)
			(stroke
				(width 0)
				(type default)
			)
			(fill no)
			(layer "B.Fab")
		)
		(pad "1" smd custom
			(at 0 -0.2794 90)
			(size 0.0762 0.0762)
			(layers "B.Cu" "B.Mask" "B.Paste")
			(net "GB_VDDA")
			(options
				(clearance outline)
				(anchor circle)
			)
			(primitives
				(gr_poly
					(pts
						(arc
							(start 0.1524 0.127)
							(mid 0.137521 0.162921)
							(end 0.1016 0.1778)
						)
						(arc
							(start -0.1016 0.1778)
							(mid -0.137521 0.162921)
							(end -0.1524 0.127)
						)
						(arc
							(start -0.1524 -0.127)
							(mid -0.137521 -0.162921)
							(end -0.1016 -0.1778)
						)
						(arc
							(start 0.1016 -0.1778)
							(mid 0.137521 -0.162921)
							(end 0.1524 -0.127)
						)
					)
					(width 0)
					(fill yes)
				)
			)
		)
		(pad "2" smd custom
			(at 0 0.2794 90)
			(size 0.0762 0.0762)
			(layers "B.Cu" "B.Mask" "B.Paste")
			(net "GND")
			(options
				(clearance outline)
				(anchor circle)
			)
			(primitives
				(gr_poly
					(pts
						(arc
							(start 0.1524 0.127)
							(mid 0.137521 0.162921)
							(end 0.1016 0.1778)
						)
						(arc
							(start -0.1016 0.1778)
							(mid -0.137521 0.162921)
							(end -0.1524 0.127)
						)
						(arc
							(start -0.1524 -0.127)
							(mid -0.137521 -0.162921)
							(end -0.1016 -0.1778)
						)
						(arc
							(start 0.1016 -0.1778)
							(mid 0.137521 -0.162921)
							(end 0.1524 -0.127)
						)
					)
					(width 0)
					(fill yes)
				)
			)
		)
	)
	(footprint ""
		(layer "B.Cu")
		(at 165.197282 -27.684984 -90)
		(property "Reference" "C387"
			(at 0 0 90)
			(layer "B.SilkS")
			(hide yes)
			(effects
				(font
					(size 1.27 1.27)
				)
				(justify mirror)
			)
		)
		(property "Value" "SCD1U6D3V1KX-GP"
			(at 2.8321 -1.7399 270)
			(unlocked yes)
			(layer "B.Fab")
			(hide yes)
			(effects
				(font
					(size 1.016 1.016)
					(thickness 0.1524)
				)
				(justify mirror)
			)
		)
		(property "Device Type" "C0201H13"
			(at 2.8321 -3.2639 270)
			(unlocked yes)
			(layer "B.Fab")
			(hide yes)
			(effects
				(font
					(size 1.016 1.016)
					(thickness 0.1524)
				)
				(justify mirror)
			)
		)
		(duplicate_pad_numbers_are_jumpers no)
		(fp_rect
			(start 0.2794 0.6477)
			(end -0.2794 -0.6477)
			(stroke
				(width 0)
				(type default)
			)
			(fill no)
			(layer "B.CrtYd")
		)
		(fp_rect
			(start 0.2794 0.6477)
			(end -0.2794 -0.6477)
			(stroke
				(width 0)
				(type default)
			)
			(fill no)
			(layer "B.Fab")
		)
		(pad "1" smd custom
			(at 0 -0.2794 90)
			(size 0.0762 0.0762)
			(layers "B.Cu" "B.Mask" "B.Paste")
			(net "PCE_AVDD")
			(options
				(clearance outline)
				(anchor circle)
			)
			(primitives
				(gr_poly
					(pts
						(arc
							(start 0.1524 0.127)
							(mid 0.137521 0.162921)
							(end 0.1016 0.1778)
						)
						(arc
							(start -0.1016 0.1778)
							(mid -0.137521 0.162921)
							(end -0.1524 0.127)
						)
						(arc
							(start -0.1524 -0.127)
							(mid -0.137521 -0.162921)
							(end -0.1016 -0.1778)
						)
						(arc
							(start 0.1016 -0.1778)
							(mid 0.137521 -0.162921)
							(end 0.1524 -0.127)
						)
					)
					(width 0)
					(fill yes)
				)
			)
		)
		(pad "2" smd custom
			(at 0 0.2794 90)
			(size 0.0762 0.0762)
			(layers "B.Cu" "B.Mask" "B.Paste")
			(net "GND")
			(options
				(clearance outline)
				(anchor circle)
			)
			(primitives
				(gr_poly
					(pts
						(arc
							(start 0.1524 0.127)
							(mid 0.137521 0.162921)
							(end 0.1016 0.1778)
						)
						(arc
							(start -0.1016 0.1778)
							(mid -0.137521 0.162921)
							(end -0.1524 0.127)
						)
						(arc
							(start -0.1524 -0.127)
							(mid -0.137521 -0.162921)
							(end -0.1016 -0.1778)
						)
						(arc
							(start 0.1016 -0.1778)
							(mid 0.137521 -0.162921)
							(end 0.1524 -0.127)
						)
					)
					(width 0)
					(fill yes)
				)
			)
		)
	)
	(footprint ""
		(layer "B.Cu")
		(at 119.507 -44.2214 180)
		(property "Reference" "C58"
			(at 0 0 0)
			(layer "B.SilkS")
			(hide yes)
			(effects
				(font
					(size 1.27 1.27)
				)
				(justify mirror)
			)
		)
		(property "Value" "SCD01U16V1KX-GP"
			(at 2.8321 -1.7399 180)
			(unlocked yes)
			(layer "B.Fab")
			(hide yes)
			(effects
				(font
					(size 1.016 1.016)
					(thickness 0.1524)
				)
				(justify mirror)
			)
		)
		(property "Device Type" "C0201H13"
			(at 2.8321 -3.2639 180)
			(unlocked yes)
			(layer "B.Fab")
			(hide yes)
			(effects
				(font
					(size 1.016 1.016)
					(thickness 0.1524)
				)
				(justify mirror)
			)
		)
		(duplicate_pad_numbers_are_jumpers no)
		(fp_rect
			(start 0.2794 0.6477)
			(end -0.2794 -0.6477)
			(stroke
				(width 0)
				(type default)
			)
			(fill no)
			(layer "B.CrtYd")
		)
		(fp_rect
			(start 0.2794 0.6477)
			(end -0.2794 -0.6477)
			(stroke
				(width 0)
				(type default)
			)
			(fill no)
			(layer "B.Fab")
		)
		(pad "1" smd custom
			(at 0 -0.2794)
			(size 0.0762 0.0762)
			(layers "B.Cu" "B.Mask" "B.Paste")
			(net "PHY_DPB_TO_SCC_35_DN")
			(options
				(clearance outline)
				(anchor circle)
			)
			(primitives
				(gr_poly
					(pts
						(arc
							(start 0.1524 0.127)
							(mid 0.137521 0.162921)
							(end 0.1016 0.1778)
						)
						(arc
							(start -0.1016 0.1778)
							(mid -0.137521 0.162921)
							(end -0.1524 0.127)
						)
						(arc
							(start -0.1524 -0.127)
							(mid -0.137521 -0.162921)
							(end -0.1016 -0.1778)
						)
						(arc
							(start 0.1016 -0.1778)
							(mid 0.137521 -0.162921)
							(end 0.1524 -0.127)
						)
					)
					(width 0)
					(fill yes)
				)
			)
		)
		(pad "2" smd custom
			(at 0 0.2794)
			(size 0.0762 0.0762)
			(layers "B.Cu" "B.Mask" "B.Paste")
			(net "PHY_DPB_TO_SCC_C_35_DN")
			(options
				(clearance outline)
				(anchor circle)
			)
			(primitives
				(gr_poly
					(pts
						(arc
							(start 0.1524 0.127)
							(mid 0.137521 0.162921)
							(end 0.1016 0.1778)
						)
						(arc
							(start -0.1016 0.1778)
							(mid -0.137521 0.162921)
							(end -0.1524 0.127)
						)
						(arc
							(start -0.1524 -0.127)
							(mid -0.137521 -0.162921)
							(end -0.1016 -0.1778)
						)
						(arc
							(start 0.1016 -0.1778)
							(mid 0.137521 -0.162921)
							(end 0.1524 -0.127)
						)
					)
					(width 0)
					(fill yes)
				)
			)
		)
	)
	(footprint ""
		(layer "B.Cu")
		(at 183.170068 -40.05961 -90)
		(property "Reference" "C476"
			(at 0 0 90)
			(layer "B.SilkS")
			(hide yes)
			(effects
				(font
					(size 1.27 1.27)
				)
				(justify mirror)
			)
		)
		(property "Value" "SCD1U6D3V1KX-GP"
			(at 2.8321 -1.7399 270)
			(unlocked yes)
			(layer "B.Fab")
			(hide yes)
			(effects
				(font
					(size 1.016 1.016)
					(thickness 0.1524)
				)
				(justify mirror)
			)
		)
		(property "Device Type" "C0201H13"
			(at 2.8321 -3.2639 270)
			(unlocked yes)
			(layer "B.Fab")
			(hide yes)
			(effects
				(font
					(size 1.016 1.016)
					(thickness 0.1524)
				)
				(justify mirror)
			)
		)
		(duplicate_pad_numbers_are_jumpers no)
		(fp_rect
			(start 0.2794 0.6477)
			(end -0.2794 -0.6477)
			(stroke
				(width 0)
				(type default)
			)
			(fill no)
			(layer "B.CrtYd")
		)
		(fp_rect
			(start 0.2794 0.6477)
			(end -0.2794 -0.6477)
			(stroke
				(width 0)
				(type default)
			)
			(fill no)
			(layer "B.Fab")
		)
		(pad "1" smd custom
			(at 0 -0.2794 90)
			(size 0.0762 0.0762)
			(layers "B.Cu" "B.Mask" "B.Paste")
			(net "P1V8_C")
			(options
				(clearance outline)
				(anchor circle)
			)
			(primitives
				(gr_poly
					(pts
						(arc
							(start 0.1524 0.127)
							(mid 0.137521 0.162921)
							(end 0.1016 0.1778)
						)
						(arc
							(start -0.1016 0.1778)
							(mid -0.137521 0.162921)
							(end -0.1524 0.127)
						)
						(arc
							(start -0.1524 -0.127)
							(mid -0.137521 -0.162921)
							(end -0.1016 -0.1778)
						)
						(arc
							(start 0.1016 -0.1778)
							(mid 0.137521 -0.162921)
							(end 0.1524 -0.127)
						)
					)
					(width 0)
					(fill yes)
				)
			)
		)
		(pad "2" smd custom
			(at 0 0.2794 90)
			(size 0.0762 0.0762)
			(layers "B.Cu" "B.Mask" "B.Paste")
			(net "GND")
			(options
				(clearance outline)
				(anchor circle)
			)
			(primitives
				(gr_poly
					(pts
						(arc
							(start 0.1524 0.127)
							(mid 0.137521 0.162921)
							(end 0.1016 0.1778)
						)
						(arc
							(start -0.1016 0.1778)
							(mid -0.137521 0.162921)
							(end -0.1524 0.127)
						)
						(arc
							(start -0.1524 -0.127)
							(mid -0.137521 -0.162921)
							(end -0.1016 -0.1778)
						)
						(arc
							(start 0.1016 -0.1778)
							(mid 0.137521 -0.162921)
							(end 0.1524 -0.127)
						)
					)
					(width 0)
					(fill yes)
				)
			)
		)
	)
	(footprint ""
		(layer "B.Cu")
		(at 92.15374 -64.04356)
		(property "Reference" "C192"
			(at 0 0 0)
			(layer "B.SilkS")
			(hide yes)
			(effects
				(font
					(size 1.27 1.27)
				)
				(justify mirror)
			)
		)
		(property "Value" "SC22U6D3V3MX-9-GP-U"
			(at 0 -2.8194 0)
			(unlocked yes)
			(layer "B.Fab")
			(hide yes)
			(effects
				(font
					(size 1.016 1.016)
					(thickness 0.1524)
				)
				(justify mirror)
			)
		)
		(property "Device Type" "C603H40"
			(at 0 -4.3434 0)
			(unlocked yes)
			(layer "B.Fab")
			(hide yes)
			(effects
				(font
					(size 1.016 1.016)
					(thickness 0.1524)
				)
				(justify mirror)
			)
		)
		(duplicate_pad_numbers_are_jumpers no)
		(fp_line
			(start -0.508 0)
			(end 0.508 0)
			(stroke
				(width 0.2032)
				(type default)
			)
			(layer "B.SilkS")
		)
		(fp_rect
			(start 0.5842 1.3335)
			(end -0.5842 -1.3335)
			(stroke
				(width 0)
				(type default)
			)
			(fill no)
			(layer "B.CrtYd")
		)
		(fp_rect
			(start 0.5842 1.3335)
			(end -0.5842 -1.3335)
			(stroke
				(width 0)
				(type default)
			)
			(fill no)
			(layer "B.Fab")
		)
		(pad "1" smd custom
			(at 0 -0.762 180)
			(size 0.2159 0.2159)
			(layers "B.Cu" "B.Mask" "B.Paste")
			(net "XTAL_VDDA18")
			(options
				(clearance outline)
				(anchor circle)
			)
			(primitives
				(gr_poly
					(pts
						(arc
							(start -0.3302 0.4318)
							(mid -0.402042 0.402042)
							(end -0.4318 0.3302)
						)
						(arc
							(start -0.4318 -0.3302)
							(mid -0.402042 -0.402042)
							(end -0.3302 -0.4318)
						)
						(arc
							(start 0.3302 -0.4318)
							(mid 0.402042 -0.402042)
							(end 0.4318 -0.3302)
						)
						(arc
							(start 0.4318 0.3302)
							(mid 0.402042 0.402042)
							(end 0.3302 0.4318)
						)
					)
					(width 0)
					(fill yes)
				)
			)
		)
		(pad "2" smd custom
			(at 0 0.762 180)
			(size 0.2159 0.2159)
			(layers "B.Cu" "B.Mask" "B.Paste")
			(net "GND")
			(options
				(clearance outline)
				(anchor circle)
			)
			(primitives
				(gr_poly
					(pts
						(arc
							(start -0.3302 0.4318)
							(mid -0.402042 0.402042)
							(end -0.4318 0.3302)
						)
						(arc
							(start -0.4318 -0.3302)
							(mid -0.402042 -0.402042)
							(end -0.3302 -0.4318)
						)
						(arc
							(start 0.3302 -0.4318)
							(mid 0.402042 -0.402042)
							(end 0.4318 -0.3302)
						)
						(arc
							(start 0.4318 0.3302)
							(mid 0.402042 0.402042)
							(end 0.3302 0.4318)
						)
					)
					(width 0)
					(fill yes)
				)
			)
		)
	)
	(footprint ""
		(layer "B.Cu")
		(at 204.343 -45.80382 180)
		(property "Reference" "C345"
			(at 0 0 0)
			(layer "B.SilkS")
			(hide yes)
			(effects
				(font
					(size 1.27 1.27)
				)
				(justify mirror)
			)
		)
		(property "Value" "SCD1U16V2KX-3GP"
			(at -1.1811 -2.7051 180)
			(unlocked yes)
			(layer "B.Fab")
			(hide yes)
			(effects
				(font
					(size 1.016 1.016)
					(thickness 0.1524)
				)
				(justify mirror)
			)
		)
		(property "Device Type" "C402H22"
			(at -1.1811 -4.2291 180)
			(unlocked yes)
			(layer "B.Fab")
			(hide yes)
			(effects
				(font
					(size 1.016 1.016)
					(thickness 0.1524)
				)
				(justify mirror)
			)
		)
		(duplicate_pad_numbers_are_jumpers no)
		(fp_rect
			(start 0.4318 0.9525)
			(end -0.4318 -0.9525)
			(stroke
				(width 0)
				(type default)
			)
			(fill no)
			(layer "B.CrtYd")
		)
		(fp_rect
			(start 0.4318 0.9525)
			(end -0.4318 -0.9525)
			(stroke
				(width 0)
				(type default)
			)
			(fill no)
			(layer "B.Fab")
		)
		(pad "1" smd custom
			(at 0 -0.4445)
			(size 0.1524 0.1524)
			(layers "B.Cu" "B.Mask" "B.Paste")
			(net "P1V8_C")
			(options
				(clearance outline)
				(anchor circle)
			)
			(primitives
				(gr_poly
					(pts
						(arc
							(start 0.3048 0.2032)
							(mid 0.275042 0.275042)
							(end 0.2032 0.3048)
						)
						(arc
							(start -0.2032 0.3048)
							(mid -0.275042 0.275042)
							(end -0.3048 0.2032)
						)
						(arc
							(start -0.3048 -0.2032)
							(mid -0.275042 -0.275042)
							(end -0.2032 -0.3048)
						)
						(arc
							(start 0.2032 -0.3048)
							(mid 0.275042 -0.275042)
							(end 0.3048 -0.2032)
						)
					)
					(width 0)
					(fill yes)
				)
			)
		)
		(pad "2" smd custom
			(at 0 0.4445)
			(size 0.1524 0.1524)
			(layers "B.Cu" "B.Mask" "B.Paste")
			(net "GND")
			(options
				(clearance outline)
				(anchor circle)
			)
			(primitives
				(gr_poly
					(pts
						(arc
							(start 0.3048 0.2032)
							(mid 0.275042 0.275042)
							(end 0.2032 0.3048)
						)
						(arc
							(start -0.2032 0.3048)
							(mid -0.275042 0.275042)
							(end -0.3048 0.2032)
						)
						(arc
							(start -0.3048 -0.2032)
							(mid -0.275042 -0.275042)
							(end -0.2032 -0.3048)
						)
						(arc
							(start 0.2032 -0.3048)
							(mid 0.275042 -0.275042)
							(end 0.3048 -0.2032)
						)
					)
					(width 0)
					(fill yes)
				)
			)
		)
	)
	(footprint ""
		(layer "B.Cu")
		(at 118.3132 -71.9074)
		(property "Reference" "C143"
			(at 0 0 0)
			(layer "B.SilkS")
			(hide yes)
			(effects
				(font
					(size 1.27 1.27)
				)
				(justify mirror)
			)
		)
		(property "Value" "SCD1U6D3V1KX-GP"
			(at 2.8321 -1.7399 0)
			(unlocked yes)
			(layer "B.Fab")
			(hide yes)
			(effects
				(font
					(size 1.016 1.016)
					(thickness 0.1524)
				)
				(justify mirror)
			)
		)
		(property "Device Type" "C0201H13"
			(at 2.8321 -3.2639 0)
			(unlocked yes)
			(layer "B.Fab")
			(hide yes)
			(effects
				(font
					(size 1.016 1.016)
					(thickness 0.1524)
				)
				(justify mirror)
			)
		)
		(duplicate_pad_numbers_are_jumpers no)
		(fp_rect
			(start 0.2794 0.6477)
			(end -0.2794 -0.6477)
			(stroke
				(width 0)
				(type default)
			)
			(fill no)
			(layer "B.CrtYd")
		)
		(fp_rect
			(start 0.2794 0.6477)
			(end -0.2794 -0.6477)
			(stroke
				(width 0)
				(type default)
			)
			(fill no)
			(layer "B.Fab")
		)
		(pad "1" smd custom
			(at 0 -0.2794 180)
			(size 0.0762 0.0762)
			(layers "B.Cu" "B.Mask" "B.Paste")
			(net "P1V8_E")
			(options
				(clearance outline)
				(anchor circle)
			)
			(primitives
				(gr_poly
					(pts
						(arc
							(start 0.1524 0.127)
							(mid 0.137521 0.162921)
							(end 0.1016 0.1778)
						)
						(arc
							(start -0.1016 0.1778)
							(mid -0.137521 0.162921)
							(end -0.1524 0.127)
						)
						(arc
							(start -0.1524 -0.127)
							(mid -0.137521 -0.162921)
							(end -0.1016 -0.1778)
						)
						(arc
							(start 0.1016 -0.1778)
							(mid 0.137521 -0.162921)
							(end 0.1524 -0.127)
						)
					)
					(width 0)
					(fill yes)
				)
			)
		)
		(pad "2" smd custom
			(at 0 0.2794 180)
			(size 0.0762 0.0762)
			(layers "B.Cu" "B.Mask" "B.Paste")
			(net "GND")
			(options
				(clearance outline)
				(anchor circle)
			)
			(primitives
				(gr_poly
					(pts
						(arc
							(start 0.1524 0.127)
							(mid 0.137521 0.162921)
							(end 0.1016 0.1778)
						)
						(arc
							(start -0.1016 0.1778)
							(mid -0.137521 0.162921)
							(end -0.1524 0.127)
						)
						(arc
							(start -0.1524 -0.127)
							(mid -0.137521 -0.162921)
							(end -0.1016 -0.1778)
						)
						(arc
							(start 0.1016 -0.1778)
							(mid 0.137521 -0.162921)
							(end 0.1524 -0.127)
						)
					)
					(width 0)
					(fill yes)
				)
			)
		)
	)
	(footprint ""
		(layer "B.Cu")
		(at 117.348 -68.6562)
		(property "Reference" "C178"
			(at 0 0 0)
			(layer "B.SilkS")
			(hide yes)
			(effects
				(font
					(size 1.27 1.27)
				)
				(justify mirror)
			)
		)
		(property "Value" "SCD1U6D3V1KX-GP"
			(at 2.8321 -1.7399 0)
			(unlocked yes)
			(layer "B.Fab")
			(hide yes)
			(effects
				(font
					(size 1.016 1.016)
					(thickness 0.1524)
				)
				(justify mirror)
			)
		)
		(property "Device Type" "C0201H13"
			(at 2.8321 -3.2639 0)
			(unlocked yes)
			(layer "B.Fab")
			(hide yes)
			(effects
				(font
					(size 1.016 1.016)
					(thickness 0.1524)
				)
				(justify mirror)
			)
		)
		(duplicate_pad_numbers_are_jumpers no)
		(fp_rect
			(start 0.2794 0.6477)
			(end -0.2794 -0.6477)
			(stroke
				(width 0)
				(type default)
			)
			(fill no)
			(layer "B.CrtYd")
		)
		(fp_rect
			(start 0.2794 0.6477)
			(end -0.2794 -0.6477)
			(stroke
				(width 0)
				(type default)
			)
			(fill no)
			(layer "B.Fab")
		)
		(pad "1" smd custom
			(at 0 -0.2794 180)
			(size 0.0762 0.0762)
			(layers "B.Cu" "B.Mask" "B.Paste")
			(net "P0V9")
			(options
				(clearance outline)
				(anchor circle)
			)
			(primitives
				(gr_poly
					(pts
						(arc
							(start 0.1524 0.127)
							(mid 0.137521 0.162921)
							(end 0.1016 0.1778)
						)
						(arc
							(start -0.1016 0.1778)
							(mid -0.137521 0.162921)
							(end -0.1524 0.127)
						)
						(arc
							(start -0.1524 -0.127)
							(mid -0.137521 -0.162921)
							(end -0.1016 -0.1778)
						)
						(arc
							(start 0.1016 -0.1778)
							(mid 0.137521 -0.162921)
							(end 0.1524 -0.127)
						)
					)
					(width 0)
					(fill yes)
				)
			)
		)
		(pad "2" smd custom
			(at 0 0.2794 180)
			(size 0.0762 0.0762)
			(layers "B.Cu" "B.Mask" "B.Paste")
			(net "GND")
			(options
				(clearance outline)
				(anchor circle)
			)
			(primitives
				(gr_poly
					(pts
						(arc
							(start 0.1524 0.127)
							(mid 0.137521 0.162921)
							(end 0.1016 0.1778)
						)
						(arc
							(start -0.1016 0.1778)
							(mid -0.137521 0.162921)
							(end -0.1524 0.127)
						)
						(arc
							(start -0.1524 -0.127)
							(mid -0.137521 -0.162921)
							(end -0.1016 -0.1778)
						)
						(arc
							(start 0.1016 -0.1778)
							(mid 0.137521 -0.162921)
							(end 0.1524 -0.127)
						)
					)
					(width 0)
					(fill yes)
				)
			)
		)
	)
	(footprint ""
		(layer "B.Cu")
		(at 166.64432 -20.572984)
		(property "Reference" "C313"
			(at 0 0 0)
			(layer "B.SilkS")
			(hide yes)
			(effects
				(font
					(size 1.27 1.27)
				)
				(justify mirror)
			)
		)
		(property "Value" "SCD22U10V1KX-GP"
			(at 2.8321 -1.7399 0)
			(unlocked yes)
			(layer "B.Fab")
			(hide yes)
			(effects
				(font
					(size 1.016 1.016)
					(thickness 0.1524)
				)
				(justify mirror)
			)
		)
		(property "Device Type" "C0201H13"
			(at 2.8321 -3.2639 0)
			(unlocked yes)
			(layer "B.Fab")
			(hide yes)
			(effects
				(font
					(size 1.016 1.016)
					(thickness 0.1524)
				)
				(justify mirror)
			)
		)
		(duplicate_pad_numbers_are_jumpers no)
		(fp_rect
			(start 0.2794 0.6477)
			(end -0.2794 -0.6477)
			(stroke
				(width 0)
				(type default)
			)
			(fill no)
			(layer "B.CrtYd")
		)
		(fp_rect
			(start 0.2794 0.6477)
			(end -0.2794 -0.6477)
			(stroke
				(width 0)
				(type default)
			)
			(fill no)
			(layer "B.Fab")
		)
		(pad "1" smd custom
			(at 0 -0.2794 180)
			(size 0.0762 0.0762)
			(layers "B.Cu" "B.Mask" "B.Paste")
			(net "PCIE_SCC_TO_COMP_C_1_DP")
			(options
				(clearance outline)
				(anchor circle)
			)
			(primitives
				(gr_poly
					(pts
						(arc
							(start 0.1524 0.127)
							(mid 0.137521 0.162921)
							(end 0.1016 0.1778)
						)
						(arc
							(start -0.1016 0.1778)
							(mid -0.137521 0.162921)
							(end -0.1524 0.127)
						)
						(arc
							(start -0.1524 -0.127)
							(mid -0.137521 -0.162921)
							(end -0.1016 -0.1778)
						)
						(arc
							(start 0.1016 -0.1778)
							(mid 0.137521 -0.162921)
							(end 0.1524 -0.127)
						)
					)
					(width 0)
					(fill yes)
				)
			)
		)
		(pad "2" smd custom
			(at 0 0.2794 180)
			(size 0.0762 0.0762)
			(layers "B.Cu" "B.Mask" "B.Paste")
			(net "PCIE_SCC_TO_COMP_1_DP")
			(options
				(clearance outline)
				(anchor circle)
			)
			(primitives
				(gr_poly
					(pts
						(arc
							(start 0.1524 0.127)
							(mid 0.137521 0.162921)
							(end 0.1016 0.1778)
						)
						(arc
							(start -0.1016 0.1778)
							(mid -0.137521 0.162921)
							(end -0.1524 0.127)
						)
						(arc
							(start -0.1524 -0.127)
							(mid -0.137521 -0.162921)
							(end -0.1016 -0.1778)
						)
						(arc
							(start 0.1016 -0.1778)
							(mid 0.137521 -0.162921)
							(end 0.1524 -0.127)
						)
					)
					(width 0)
					(fill yes)
				)
			)
		)
	)
	(footprint ""
		(layer "B.Cu")
		(at 166.624 -52.07)
		(property "Reference" "R268"
			(at 0 0 0)
			(layer "B.SilkS")
			(hide yes)
			(effects
				(font
					(size 1.27 1.27)
				)
				(justify mirror)
			)
		)
		(property "Value" "4K7R2F-GP"
			(at -0.064008 -3.993896 0)
			(unlocked yes)
			(layer "B.Fab")
			(hide yes)
			(effects
				(font
					(size 1.016 1.016)
					(thickness 0.1524)
				)
				(justify mirror)
			)
		)
		(property "Device Type" "R402H16"
			(at -0.064008 -5.517896 0)
			(unlocked yes)
			(layer "B.Fab")
			(hide yes)
			(effects
				(font
					(size 1.016 1.016)
					(thickness 0.1524)
				)
				(justify mirror)
			)
		)
		(duplicate_pad_numbers_are_jumpers no)
		(fp_line
			(start -0.508 -0.9398)
			(end 0.508 -0.9398)
			(stroke
				(width 0.1524)
				(type default)
			)
			(layer "B.SilkS")
		)
		(fp_line
			(start 0.508 -0.9398)
			(end 0.508 0.9398)
			(stroke
				(width 0.1524)
				(type default)
			)
			(layer "B.SilkS")
		)
		(fp_rect
			(start 0.508 0.9398)
			(end -0.508 -0.9398)
			(stroke
				(width 0)
				(type default)
			)
			(fill no)
			(layer "B.CrtYd")
		)
		(fp_rect
			(start 0.508 0.9398)
			(end -0.508 -0.9398)
			(stroke
				(width 0)
				(type default)
			)
			(fill no)
			(layer "B.Fab")
		)
		(pad "1" smd custom
			(at 0 -0.4445 180)
			(size 0.1397 0.1397)
			(layers "B.Cu" "B.Mask" "B.Paste")
			(net "P1V8_C")
			(options
				(clearance outline)
				(anchor circle)
			)
			(primitives
				(gr_poly
					(pts
						(arc
							(start -0.1778 0.2794)
							(mid -0.249642 0.249642)
							(end -0.2794 0.1778)
						)
						(arc
							(start -0.2794 -0.1778)
							(mid -0.249642 -0.249642)
							(end -0.1778 -0.2794)
						)
						(arc
							(start 0.1778 -0.2794)
							(mid 0.249642 -0.249642)
							(end 0.2794 -0.1778)
						)
						(arc
							(start 0.2794 0.1778)
							(mid 0.249642 0.249642)
							(end 0.1778 0.2794)
						)
					)
					(width 0)
					(fill yes)
				)
			)
		)
		(pad "2" smd custom
			(at 0 0.4445 180)
			(size 0.1397 0.1397)
			(layers "B.Cu" "B.Mask" "B.Paste")
			(net "ICE_SEL")
			(options
				(clearance outline)
				(anchor circle)
			)
			(primitives
				(gr_poly
					(pts
						(arc
							(start -0.1778 0.2794)
							(mid -0.249642 0.249642)
							(end -0.2794 0.1778)
						)
						(arc
							(start -0.2794 -0.1778)
							(mid -0.249642 -0.249642)
							(end -0.1778 -0.2794)
						)
						(arc
							(start 0.1778 -0.2794)
							(mid 0.249642 -0.249642)
							(end 0.2794 -0.1778)
						)
						(arc
							(start 0.2794 0.1778)
							(mid 0.249642 0.249642)
							(end 0.1778 0.2794)
						)
					)
					(width 0)
					(fill yes)
				)
			)
		)
	)
	(footprint ""
		(layer "B.Cu")
		(at 168.028874 -96.109282 180)
		(property "Reference" "R483"
			(at 0 0 0)
			(layer "B.SilkS")
			(hide yes)
			(effects
				(font
					(size 1.27 1.27)
				)
				(justify mirror)
			)
		)
		(property "Value" "10KR2F-2-GP"
			(at -0.064008 -3.993896 180)
			(unlocked yes)
			(layer "B.Fab")
			(hide yes)
			(effects
				(font
					(size 1.016 1.016)
					(thickness 0.1524)
				)
				(justify mirror)
			)
		)
		(property "Device Type" "R402H16"
			(at -0.064008 -5.517896 180)
			(unlocked yes)
			(layer "B.Fab")
			(hide yes)
			(effects
				(font
					(size 1.016 1.016)
					(thickness 0.1524)
				)
				(justify mirror)
			)
		)
		(duplicate_pad_numbers_are_jumpers no)
		(fp_line
			(start 0.508 -0.9398)
			(end 0.508 0.9398)
			(stroke
				(width 0.1524)
				(type default)
			)
			(layer "B.SilkS")
		)
		(fp_line
			(start -0.508 -0.9398)
			(end 0.508 -0.9398)
			(stroke
				(width 0.1524)
				(type default)
			)
			(layer "B.SilkS")
		)
		(fp_rect
			(start 0.508 0.9398)
			(end -0.508 -0.9398)
			(stroke
				(width 0)
				(type default)
			)
			(fill no)
			(layer "B.CrtYd")
		)
		(fp_rect
			(start 0.508 0.9398)
			(end -0.508 -0.9398)
			(stroke
				(width 0)
				(type default)
			)
			(fill no)
			(layer "B.Fab")
		)
		(pad "1" smd custom
			(at 0 -0.4445)
			(size 0.1397 0.1397)
			(layers "B.Cu" "B.Mask" "B.Paste")
			(net "AGND_P0V975")
			(options
				(clearance outline)
				(anchor circle)
			)
			(primitives
				(gr_poly
					(pts
						(arc
							(start -0.1778 0.2794)
							(mid -0.249642 0.249642)
							(end -0.2794 0.1778)
						)
						(arc
							(start -0.2794 -0.1778)
							(mid -0.249642 -0.249642)
							(end -0.1778 -0.2794)
						)
						(arc
							(start 0.1778 -0.2794)
							(mid 0.249642 -0.249642)
							(end 0.2794 -0.1778)
						)
						(arc
							(start 0.2794 0.1778)
							(mid 0.249642 0.249642)
							(end 0.1778 0.2794)
						)
					)
					(width 0)
					(fill yes)
				)
			)
		)
		(pad "2" smd custom
			(at 0 0.4445)
			(size 0.1397 0.1397)
			(layers "B.Cu" "B.Mask" "B.Paste")
			(net "VT235_IMAX")
			(options
				(clearance outline)
				(anchor circle)
			)
			(primitives
				(gr_poly
					(pts
						(arc
							(start -0.1778 0.2794)
							(mid -0.249642 0.249642)
							(end -0.2794 0.1778)
						)
						(arc
							(start -0.2794 -0.1778)
							(mid -0.249642 -0.249642)
							(end -0.1778 -0.2794)
						)
						(arc
							(start 0.1778 -0.2794)
							(mid 0.249642 -0.249642)
							(end 0.2794 -0.1778)
						)
						(arc
							(start 0.2794 0.1778)
							(mid 0.249642 0.249642)
							(end 0.1778 0.2794)
						)
					)
					(width 0)
					(fill yes)
				)
			)
		)
	)
	(footprint ""
		(layer "B.Cu")
		(at 118.7704 -61.488066)
		(property "Reference" "C226"
			(at 0 0 0)
			(layer "B.SilkS")
			(hide yes)
			(effects
				(font
					(size 1.27 1.27)
				)
				(justify mirror)
			)
		)
		(property "Value" "SCD1U16V2KX-3GP"
			(at -1.1811 -2.7051 0)
			(unlocked yes)
			(layer "B.Fab")
			(hide yes)
			(effects
				(font
					(size 1.016 1.016)
					(thickness 0.1524)
				)
				(justify mirror)
			)
		)
		(property "Device Type" "C402H22"
			(at -1.1811 -4.2291 0)
			(unlocked yes)
			(layer "B.Fab")
			(hide yes)
			(effects
				(font
					(size 1.016 1.016)
					(thickness 0.1524)
				)
				(justify mirror)
			)
		)
		(duplicate_pad_numbers_are_jumpers no)
		(fp_rect
			(start 0.4318 0.9525)
			(end -0.4318 -0.9525)
			(stroke
				(width 0)
				(type default)
			)
			(fill no)
			(layer "B.CrtYd")
		)
		(fp_rect
			(start 0.4318 0.9525)
			(end -0.4318 -0.9525)
			(stroke
				(width 0)
				(type default)
			)
			(fill no)
			(layer "B.Fab")
		)
		(pad "1" smd custom
			(at 0 -0.4445 180)
			(size 0.1524 0.1524)
			(layers "B.Cu" "B.Mask" "B.Paste")
			(net "GB_VDDH")
			(options
				(clearance outline)
				(anchor circle)
			)
			(primitives
				(gr_poly
					(pts
						(arc
							(start 0.3048 0.2032)
							(mid 0.275042 0.275042)
							(end 0.2032 0.3048)
						)
						(arc
							(start -0.2032 0.3048)
							(mid -0.275042 0.275042)
							(end -0.3048 0.2032)
						)
						(arc
							(start -0.3048 -0.2032)
							(mid -0.275042 -0.275042)
							(end -0.2032 -0.3048)
						)
						(arc
							(start 0.2032 -0.3048)
							(mid 0.275042 -0.275042)
							(end 0.3048 -0.2032)
						)
					)
					(width 0)
					(fill yes)
				)
			)
		)
		(pad "2" smd custom
			(at 0 0.4445 180)
			(size 0.1524 0.1524)
			(layers "B.Cu" "B.Mask" "B.Paste")
			(net "GND")
			(options
				(clearance outline)
				(anchor circle)
			)
			(primitives
				(gr_poly
					(pts
						(arc
							(start 0.3048 0.2032)
							(mid 0.275042 0.275042)
							(end 0.2032 0.3048)
						)
						(arc
							(start -0.2032 0.3048)
							(mid -0.275042 0.275042)
							(end -0.3048 0.2032)
						)
						(arc
							(start -0.3048 -0.2032)
							(mid -0.275042 -0.275042)
							(end -0.2032 -0.3048)
						)
						(arc
							(start 0.2032 -0.3048)
							(mid 0.275042 -0.275042)
							(end 0.3048 -0.2032)
						)
					)
					(width 0)
					(fill yes)
				)
			)
		)
	)
	(footprint ""
		(layer "B.Cu")
		(at 115.4938 -44.2214 180)
		(property "Reference" "C63"
			(at 0 0 0)
			(layer "B.SilkS")
			(hide yes)
			(effects
				(font
					(size 1.27 1.27)
				)
				(justify mirror)
			)
		)
		(property "Value" "SCD01U16V1KX-GP"
			(at 2.8321 -1.7399 180)
			(unlocked yes)
			(layer "B.Fab")
			(hide yes)
			(effects
				(font
					(size 1.016 1.016)
					(thickness 0.1524)
				)
				(justify mirror)
			)
		)
		(property "Device Type" "C0201H13"
			(at 2.8321 -3.2639 180)
			(unlocked yes)
			(layer "B.Fab")
			(hide yes)
			(effects
				(font
					(size 1.016 1.016)
					(thickness 0.1524)
				)
				(justify mirror)
			)
		)
		(duplicate_pad_numbers_are_jumpers no)
		(fp_rect
			(start 0.2794 0.6477)
			(end -0.2794 -0.6477)
			(stroke
				(width 0)
				(type default)
			)
			(fill no)
			(layer "B.CrtYd")
		)
		(fp_rect
			(start 0.2794 0.6477)
			(end -0.2794 -0.6477)
			(stroke
				(width 0)
				(type default)
			)
			(fill no)
			(layer "B.Fab")
		)
		(pad "1" smd custom
			(at 0 -0.2794)
			(size 0.0762 0.0762)
			(layers "B.Cu" "B.Mask" "B.Paste")
			(net "PHY_DPB_TO_SCC_32_DP")
			(options
				(clearance outline)
				(anchor circle)
			)
			(primitives
				(gr_poly
					(pts
						(arc
							(start 0.1524 0.127)
							(mid 0.137521 0.162921)
							(end 0.1016 0.1778)
						)
						(arc
							(start -0.1016 0.1778)
							(mid -0.137521 0.162921)
							(end -0.1524 0.127)
						)
						(arc
							(start -0.1524 -0.127)
							(mid -0.137521 -0.162921)
							(end -0.1016 -0.1778)
						)
						(arc
							(start 0.1016 -0.1778)
							(mid 0.137521 -0.162921)
							(end 0.1524 -0.127)
						)
					)
					(width 0)
					(fill yes)
				)
			)
		)
		(pad "2" smd custom
			(at 0 0.2794)
			(size 0.0762 0.0762)
			(layers "B.Cu" "B.Mask" "B.Paste")
			(net "PHY_DPB_TO_SCC_C_32_DP")
			(options
				(clearance outline)
				(anchor circle)
			)
			(primitives
				(gr_poly
					(pts
						(arc
							(start 0.1524 0.127)
							(mid 0.137521 0.162921)
							(end 0.1016 0.1778)
						)
						(arc
							(start -0.1016 0.1778)
							(mid -0.137521 0.162921)
							(end -0.1524 0.127)
						)
						(arc
							(start -0.1524 -0.127)
							(mid -0.137521 -0.162921)
							(end -0.1016 -0.1778)
						)
						(arc
							(start 0.1016 -0.1778)
							(mid 0.137521 -0.162921)
							(end 0.1524 -0.127)
						)
					)
					(width 0)
					(fill yes)
				)
			)
		)
	)
	(footprint ""
		(layer "B.Cu")
		(at 184.465468 -48.05299 90)
		(property "Reference" "C457"
			(at 0 0 90)
			(layer "B.SilkS")
			(hide yes)
			(effects
				(font
					(size 1.27 1.27)
				)
				(justify mirror)
			)
		)
		(property "Value" "SCD1U6D3V1KX-GP"
			(at 2.8321 -1.7399 90)
			(unlocked yes)
			(layer "B.Fab")
			(hide yes)
			(effects
				(font
					(size 1.016 1.016)
					(thickness 0.1524)
				)
				(justify mirror)
			)
		)
		(property "Device Type" "C0201H13"
			(at 2.8321 -3.2639 90)
			(unlocked yes)
			(layer "B.Fab")
			(hide yes)
			(effects
				(font
					(size 1.016 1.016)
					(thickness 0.1524)
				)
				(justify mirror)
			)
		)
		(duplicate_pad_numbers_are_jumpers no)
		(fp_rect
			(start 0.2794 0.6477)
			(end -0.2794 -0.6477)
			(stroke
				(width 0)
				(type default)
			)
			(fill no)
			(layer "B.CrtYd")
		)
		(fp_rect
			(start 0.2794 0.6477)
			(end -0.2794 -0.6477)
			(stroke
				(width 0)
				(type default)
			)
			(fill no)
			(layer "B.Fab")
		)
		(pad "1" smd custom
			(at 0 -0.2794 270)
			(size 0.0762 0.0762)
			(layers "B.Cu" "B.Mask" "B.Paste")
			(net "P1V8_C")
			(options
				(clearance outline)
				(anchor circle)
			)
			(primitives
				(gr_poly
					(pts
						(arc
							(start 0.1524 0.127)
							(mid 0.137521 0.162921)
							(end 0.1016 0.1778)
						)
						(arc
							(start -0.1016 0.1778)
							(mid -0.137521 0.162921)
							(end -0.1524 0.127)
						)
						(arc
							(start -0.1524 -0.127)
							(mid -0.137521 -0.162921)
							(end -0.1016 -0.1778)
						)
						(arc
							(start 0.1016 -0.1778)
							(mid 0.137521 -0.162921)
							(end 0.1524 -0.127)
						)
					)
					(width 0)
					(fill yes)
				)
			)
		)
		(pad "2" smd custom
			(at 0 0.2794 270)
			(size 0.0762 0.0762)
			(layers "B.Cu" "B.Mask" "B.Paste")
			(net "GND")
			(options
				(clearance outline)
				(anchor circle)
			)
			(primitives
				(gr_poly
					(pts
						(arc
							(start 0.1524 0.127)
							(mid 0.137521 0.162921)
							(end 0.1016 0.1778)
						)
						(arc
							(start -0.1016 0.1778)
							(mid -0.137521 0.162921)
							(end -0.1524 0.127)
						)
						(arc
							(start -0.1524 -0.127)
							(mid -0.137521 -0.162921)
							(end -0.1016 -0.1778)
						)
						(arc
							(start 0.1016 -0.1778)
							(mid 0.137521 -0.162921)
							(end 0.1524 -0.127)
						)
					)
					(width 0)
					(fill yes)
				)
			)
		)
	)
	(footprint ""
		(layer "B.Cu")
		(at 182.140098 -24.735536)
		(property "Reference" "TP129"
			(at 0 0 0)
			(layer "B.SilkS")
			(hide yes)
			(effects
				(font
					(size 1.27 1.27)
				)
				(justify mirror)
			)
		)
		(property "Value" "TPAD28-2-GP"
			(at 0.0127 -1.6637 0)
			(unlocked yes)
			(layer "B.Fab")
			(hide yes)
			(effects
				(font
					(size 1.016 1.016)
					(thickness 0.1524)
				)
				(justify mirror)
			)
		)
		(property "Device Type" "TPAD28"
			(at 0.0127 -3.1877 0)
			(unlocked yes)
			(layer "B.Fab")
			(hide yes)
			(effects
				(font
					(size 1.016 1.016)
					(thickness 0.1524)
				)
				(justify mirror)
			)
		)
		(duplicate_pad_numbers_are_jumpers no)
		(fp_poly
			(pts
				(arc
					(start 0.3556 0)
					(mid -0.3556 0)
					(end 0.3556 0)
				)
			)
			(stroke
				(width 0)
				(type default)
			)
			(fill no)
			(layer "B.CrtYd")
		)
		(fp_poly
			(pts
				(arc
					(start 0.6096 0)
					(mid -0.6096 0)
					(end 0.6096 0)
				)
			)
			(stroke
				(width 0)
				(type default)
			)
			(fill no)
			(layer "B.Fab")
		)
		(pad "1" smd circle
			(at 0 0 180)
			(size 0.7112 0.7112)
			(layers "B.Cu" "B.Mask" "B.Paste")
			(net "SYS_ERROR1")
		)
	)
	(footprint ""
		(layer "B.Cu")
		(at 154.184604 -62.090808 -90)
		(property "Reference" "C356"
			(at 0 0 90)
			(layer "B.SilkS")
			(hide yes)
			(effects
				(font
					(size 1.27 1.27)
				)
				(justify mirror)
			)
		)
		(property "Value" "SC10U6D3V5KX-4GP"
			(at 0.0762 -6.1214 270)
			(unlocked yes)
			(layer "B.Fab")
			(hide yes)
			(effects
				(font
					(size 1.016 1.016)
					(thickness 0.1524)
				)
				(justify mirror)
			)
		)
		(property "Device Type" "C805H58"
			(at 0.0762 -8.1534 270)
			(unlocked yes)
			(layer "B.Fab")
			(hide yes)
			(effects
				(font
					(size 1.016 1.016)
					(thickness 0.1524)
				)
				(justify mirror)
			)
		)
		(duplicate_pad_numbers_are_jumpers no)
		(fp_line
			(start -0.635 0)
			(end 0.635 0)
			(stroke
				(width 0.508)
				(type default)
			)
			(layer "B.SilkS")
		)
		(fp_rect
			(start 0.9652 1.778)
			(end -0.9652 -1.778)
			(stroke
				(width 0)
				(type default)
			)
			(fill no)
			(layer "B.CrtYd")
		)
		(fp_poly
			(pts
				(xy 0.9652 -1.778) (xy -0.9652 -1.778) (xy -0.9652 1.778) (xy 0.9652 1.778)
			)
			(stroke
				(width 0)
				(type default)
			)
			(fill no)
			(layer "B.Fab")
		)
		(pad "1" smd rect
			(at 0 -0.9652 90)
			(size 1.397 1.143)
			(layers "B.Cu" "B.Mask" "B.Paste")
			(net "SYS_PLL_VDD")
		)
		(pad "2" smd rect
			(at 0 0.9652 90)
			(size 1.397 1.143)
			(layers "B.Cu" "B.Mask" "B.Paste")
			(net "GND")
		)
	)
	(footprint ""
		(layer "B.Cu")
		(at 114.945414 -89.31656 -90)
		(property "Reference" "R45"
			(at 0 0 90)
			(layer "B.SilkS")
			(hide yes)
			(effects
				(font
					(size 1.27 1.27)
				)
				(justify mirror)
			)
		)
		(property "Value" "4K7R2F-GP"
			(at -0.064008 -3.993896 270)
			(unlocked yes)
			(layer "B.Fab")
			(hide yes)
			(effects
				(font
					(size 1.016 1.016)
					(thickness 0.1524)
				)
				(justify mirror)
			)
		)
		(property "Device Type" "R402H16"
			(at -0.064008 -5.517896 270)
			(unlocked yes)
			(layer "B.Fab")
			(hide yes)
			(effects
				(font
					(size 1.016 1.016)
					(thickness 0.1524)
				)
				(justify mirror)
			)
		)
		(duplicate_pad_numbers_are_jumpers no)
		(fp_line
			(start -0.508 -0.9398)
			(end 0.508 -0.9398)
			(stroke
				(width 0.1524)
				(type default)
			)
			(layer "B.SilkS")
		)
		(fp_line
			(start 0.508 -0.9398)
			(end 0.508 0.9398)
			(stroke
				(width 0.1524)
				(type default)
			)
			(layer "B.SilkS")
		)
		(fp_rect
			(start 0.508 0.9398)
			(end -0.508 -0.9398)
			(stroke
				(width 0)
				(type default)
			)
			(fill no)
			(layer "B.CrtYd")
		)
		(fp_rect
			(start 0.508 0.9398)
			(end -0.508 -0.9398)
			(stroke
				(width 0)
				(type default)
			)
			(fill no)
			(layer "B.Fab")
		)
		(pad "1" smd custom
			(at 0 -0.4445 90)
			(size 0.1397 0.1397)
			(layers "B.Cu" "B.Mask" "B.Paste")
			(net "EXP_GPIO14")
			(options
				(clearance outline)
				(anchor circle)
			)
			(primitives
				(gr_poly
					(pts
						(arc
							(start -0.1778 0.2794)
							(mid -0.249642 0.249642)
							(end -0.2794 0.1778)
						)
						(arc
							(start -0.2794 -0.1778)
							(mid -0.249642 -0.249642)
							(end -0.1778 -0.2794)
						)
						(arc
							(start 0.1778 -0.2794)
							(mid 0.249642 -0.249642)
							(end 0.2794 -0.1778)
						)
						(arc
							(start 0.2794 0.1778)
							(mid 0.249642 0.249642)
							(end 0.1778 0.2794)
						)
					)
					(width 0)
					(fill yes)
				)
			)
		)
		(pad "2" smd custom
			(at 0 0.4445 90)
			(size 0.1397 0.1397)
			(layers "B.Cu" "B.Mask" "B.Paste")
			(net "GND")
			(options
				(clearance outline)
				(anchor circle)
			)
			(primitives
				(gr_poly
					(pts
						(arc
							(start -0.1778 0.2794)
							(mid -0.249642 0.249642)
							(end -0.2794 0.1778)
						)
						(arc
							(start -0.2794 -0.1778)
							(mid -0.249642 -0.249642)
							(end -0.1778 -0.2794)
						)
						(arc
							(start 0.1778 -0.2794)
							(mid 0.249642 -0.249642)
							(end 0.2794 -0.1778)
						)
						(arc
							(start 0.2794 0.1778)
							(mid 0.249642 0.249642)
							(end 0.1778 0.2794)
						)
					)
					(width 0)
					(fill yes)
				)
			)
		)
	)
	(footprint ""
		(layer "B.Cu")
		(at 169.4942 -38.8366 180)
		(property "Reference" "C401"
			(at 0 0 0)
			(layer "B.SilkS")
			(hide yes)
			(effects
				(font
					(size 1.27 1.27)
				)
				(justify mirror)
			)
		)
		(property "Value" "SCD1U16V2KX-3GP"
			(at -1.1811 -2.7051 180)
			(unlocked yes)
			(layer "B.Fab")
			(hide yes)
			(effects
				(font
					(size 1.016 1.016)
					(thickness 0.1524)
				)
				(justify mirror)
			)
		)
		(property "Device Type" "C402H22"
			(at -1.1811 -4.2291 180)
			(unlocked yes)
			(layer "B.Fab")
			(hide yes)
			(effects
				(font
					(size 1.016 1.016)
					(thickness 0.1524)
				)
				(justify mirror)
			)
		)
		(duplicate_pad_numbers_are_jumpers no)
		(fp_rect
			(start 0.4318 0.9525)
			(end -0.4318 -0.9525)
			(stroke
				(width 0)
				(type default)
			)
			(fill no)
			(layer "B.CrtYd")
		)
		(fp_rect
			(start 0.4318 0.9525)
			(end -0.4318 -0.9525)
			(stroke
				(width 0)
				(type default)
			)
			(fill no)
			(layer "B.Fab")
		)
		(pad "1" smd custom
			(at 0 -0.4445)
			(size 0.1524 0.1524)
			(layers "B.Cu" "B.Mask" "B.Paste")
			(net "SAS0_AVDD")
			(options
				(clearance outline)
				(anchor circle)
			)
			(primitives
				(gr_poly
					(pts
						(arc
							(start 0.3048 0.2032)
							(mid 0.275042 0.275042)
							(end 0.2032 0.3048)
						)
						(arc
							(start -0.2032 0.3048)
							(mid -0.275042 0.275042)
							(end -0.3048 0.2032)
						)
						(arc
							(start -0.3048 -0.2032)
							(mid -0.275042 -0.275042)
							(end -0.2032 -0.3048)
						)
						(arc
							(start 0.2032 -0.3048)
							(mid 0.275042 -0.275042)
							(end 0.3048 -0.2032)
						)
					)
					(width 0)
					(fill yes)
				)
			)
		)
		(pad "2" smd custom
			(at 0 0.4445)
			(size 0.1524 0.1524)
			(layers "B.Cu" "B.Mask" "B.Paste")
			(net "GND")
			(options
				(clearance outline)
				(anchor circle)
			)
			(primitives
				(gr_poly
					(pts
						(arc
							(start 0.3048 0.2032)
							(mid 0.275042 0.275042)
							(end 0.2032 0.3048)
						)
						(arc
							(start -0.2032 0.3048)
							(mid -0.275042 0.275042)
							(end -0.3048 0.2032)
						)
						(arc
							(start -0.3048 -0.2032)
							(mid -0.275042 -0.275042)
							(end -0.2032 -0.3048)
						)
						(arc
							(start 0.2032 -0.3048)
							(mid 0.275042 -0.275042)
							(end 0.3048 -0.2032)
						)
					)
					(width 0)
					(fill yes)
				)
			)
		)
	)
	(footprint ""
		(layer "B.Cu")
		(at 112.6998 -71.9074)
		(property "Reference" "C150"
			(at 0 0 0)
			(layer "B.SilkS")
			(hide yes)
			(effects
				(font
					(size 1.27 1.27)
				)
				(justify mirror)
			)
		)
		(property "Value" "SCD1U6D3V1KX-GP"
			(at 2.8321 -1.7399 0)
			(unlocked yes)
			(layer "B.Fab")
			(hide yes)
			(effects
				(font
					(size 1.016 1.016)
					(thickness 0.1524)
				)
				(justify mirror)
			)
		)
		(property "Device Type" "C0201H13"
			(at 2.8321 -3.2639 0)
			(unlocked yes)
			(layer "B.Fab")
			(hide yes)
			(effects
				(font
					(size 1.016 1.016)
					(thickness 0.1524)
				)
				(justify mirror)
			)
		)
		(duplicate_pad_numbers_are_jumpers no)
		(fp_rect
			(start 0.2794 0.6477)
			(end -0.2794 -0.6477)
			(stroke
				(width 0)
				(type default)
			)
			(fill no)
			(layer "B.CrtYd")
		)
		(fp_rect
			(start 0.2794 0.6477)
			(end -0.2794 -0.6477)
			(stroke
				(width 0)
				(type default)
			)
			(fill no)
			(layer "B.Fab")
		)
		(pad "1" smd custom
			(at 0 -0.2794 180)
			(size 0.0762 0.0762)
			(layers "B.Cu" "B.Mask" "B.Paste")
			(net "P1V8_E")
			(options
				(clearance outline)
				(anchor circle)
			)
			(primitives
				(gr_poly
					(pts
						(arc
							(start 0.1524 0.127)
							(mid 0.137521 0.162921)
							(end 0.1016 0.1778)
						)
						(arc
							(start -0.1016 0.1778)
							(mid -0.137521 0.162921)
							(end -0.1524 0.127)
						)
						(arc
							(start -0.1524 -0.127)
							(mid -0.137521 -0.162921)
							(end -0.1016 -0.1778)
						)
						(arc
							(start 0.1016 -0.1778)
							(mid 0.137521 -0.162921)
							(end 0.1524 -0.127)
						)
					)
					(width 0)
					(fill yes)
				)
			)
		)
		(pad "2" smd custom
			(at 0 0.2794 180)
			(size 0.0762 0.0762)
			(layers "B.Cu" "B.Mask" "B.Paste")
			(net "GND")
			(options
				(clearance outline)
				(anchor circle)
			)
			(primitives
				(gr_poly
					(pts
						(arc
							(start 0.1524 0.127)
							(mid 0.137521 0.162921)
							(end 0.1016 0.1778)
						)
						(arc
							(start -0.1016 0.1778)
							(mid -0.137521 0.162921)
							(end -0.1524 0.127)
						)
						(arc
							(start -0.1524 -0.127)
							(mid -0.137521 -0.162921)
							(end -0.1016 -0.1778)
						)
						(arc
							(start 0.1016 -0.1778)
							(mid 0.137521 -0.162921)
							(end 0.1524 -0.127)
						)
					)
					(width 0)
					(fill yes)
				)
			)
		)
	)
	(footprint ""
		(layer "B.Cu")
		(at 169.171874 -96.109282 180)
		(property "Reference" "R484"
			(at 0 0 0)
			(layer "B.SilkS")
			(hide yes)
			(effects
				(font
					(size 1.27 1.27)
				)
				(justify mirror)
			)
		)
		(property "Value" "10KR2F-2-GP"
			(at -0.064008 -3.993896 180)
			(unlocked yes)
			(layer "B.Fab")
			(hide yes)
			(effects
				(font
					(size 1.016 1.016)
					(thickness 0.1524)
				)
				(justify mirror)
			)
		)
		(property "Device Type" "R402H16"
			(at -0.064008 -5.517896 180)
			(unlocked yes)
			(layer "B.Fab")
			(hide yes)
			(effects
				(font
					(size 1.016 1.016)
					(thickness 0.1524)
				)
				(justify mirror)
			)
		)
		(duplicate_pad_numbers_are_jumpers no)
		(fp_line
			(start 0.508 -0.9398)
			(end 0.508 0.9398)
			(stroke
				(width 0.1524)
				(type default)
			)
			(layer "B.SilkS")
		)
		(fp_line
			(start -0.508 -0.9398)
			(end 0.508 -0.9398)
			(stroke
				(width 0.1524)
				(type default)
			)
			(layer "B.SilkS")
		)
		(fp_rect
			(start 0.508 0.9398)
			(end -0.508 -0.9398)
			(stroke
				(width 0)
				(type default)
			)
			(fill no)
			(layer "B.CrtYd")
		)
		(fp_rect
			(start 0.508 0.9398)
			(end -0.508 -0.9398)
			(stroke
				(width 0)
				(type default)
			)
			(fill no)
			(layer "B.Fab")
		)
		(pad "1" smd custom
			(at 0 -0.4445)
			(size 0.1397 0.1397)
			(layers "B.Cu" "B.Mask" "B.Paste")
			(net "AGND_P0V975")
			(options
				(clearance outline)
				(anchor circle)
			)
			(primitives
				(gr_poly
					(pts
						(arc
							(start -0.1778 0.2794)
							(mid -0.249642 0.249642)
							(end -0.2794 0.1778)
						)
						(arc
							(start -0.2794 -0.1778)
							(mid -0.249642 -0.249642)
							(end -0.1778 -0.2794)
						)
						(arc
							(start 0.1778 -0.2794)
							(mid 0.249642 -0.249642)
							(end 0.2794 -0.1778)
						)
						(arc
							(start 0.2794 0.1778)
							(mid 0.249642 0.249642)
							(end 0.1778 0.2794)
						)
					)
					(width 0)
					(fill yes)
				)
			)
		)
		(pad "2" smd custom
			(at 0 0.4445)
			(size 0.1397 0.1397)
			(layers "B.Cu" "B.Mask" "B.Paste")
			(net "VT235_BIAS")
			(options
				(clearance outline)
				(anchor circle)
			)
			(primitives
				(gr_poly
					(pts
						(arc
							(start -0.1778 0.2794)
							(mid -0.249642 0.249642)
							(end -0.2794 0.1778)
						)
						(arc
							(start -0.2794 -0.1778)
							(mid -0.249642 -0.249642)
							(end -0.1778 -0.2794)
						)
						(arc
							(start 0.1778 -0.2794)
							(mid 0.249642 -0.249642)
							(end 0.2794 -0.1778)
						)
						(arc
							(start 0.2794 0.1778)
							(mid 0.249642 0.249642)
							(end 0.1778 0.2794)
						)
					)
					(width 0)
					(fill yes)
				)
			)
		)
	)
	(footprint ""
		(layer "B.Cu")
		(at 100.457 -61.4934)
		(property "Reference" "C139"
			(at 0 0 0)
			(layer "B.SilkS")
			(hide yes)
			(effects
				(font
					(size 1.27 1.27)
				)
				(justify mirror)
			)
		)
		(property "Value" "SCD1U6D3V1KX-GP"
			(at 2.8321 -1.7399 0)
			(unlocked yes)
			(layer "B.Fab")
			(hide yes)
			(effects
				(font
					(size 1.016 1.016)
					(thickness 0.1524)
				)
				(justify mirror)
			)
		)
		(property "Device Type" "C0201H13"
			(at 2.8321 -3.2639 0)
			(unlocked yes)
			(layer "B.Fab")
			(hide yes)
			(effects
				(font
					(size 1.016 1.016)
					(thickness 0.1524)
				)
				(justify mirror)
			)
		)
		(duplicate_pad_numbers_are_jumpers no)
		(fp_rect
			(start 0.2794 0.6477)
			(end -0.2794 -0.6477)
			(stroke
				(width 0)
				(type default)
			)
			(fill no)
			(layer "B.CrtYd")
		)
		(fp_rect
			(start 0.2794 0.6477)
			(end -0.2794 -0.6477)
			(stroke
				(width 0)
				(type default)
			)
			(fill no)
			(layer "B.Fab")
		)
		(pad "1" smd custom
			(at 0 -0.2794 180)
			(size 0.0762 0.0762)
			(layers "B.Cu" "B.Mask" "B.Paste")
			(net "P1V8_E")
			(options
				(clearance outline)
				(anchor circle)
			)
			(primitives
				(gr_poly
					(pts
						(arc
							(start 0.1524 0.127)
							(mid 0.137521 0.162921)
							(end 0.1016 0.1778)
						)
						(arc
							(start -0.1016 0.1778)
							(mid -0.137521 0.162921)
							(end -0.1524 0.127)
						)
						(arc
							(start -0.1524 -0.127)
							(mid -0.137521 -0.162921)
							(end -0.1016 -0.1778)
						)
						(arc
							(start 0.1016 -0.1778)
							(mid 0.137521 -0.162921)
							(end 0.1524 -0.127)
						)
					)
					(width 0)
					(fill yes)
				)
			)
		)
		(pad "2" smd custom
			(at 0 0.2794 180)
			(size 0.0762 0.0762)
			(layers "B.Cu" "B.Mask" "B.Paste")
			(net "GND")
			(options
				(clearance outline)
				(anchor circle)
			)
			(primitives
				(gr_poly
					(pts
						(arc
							(start 0.1524 0.127)
							(mid 0.137521 0.162921)
							(end 0.1016 0.1778)
						)
						(arc
							(start -0.1016 0.1778)
							(mid -0.137521 0.162921)
							(end -0.1524 0.127)
						)
						(arc
							(start -0.1524 -0.127)
							(mid -0.137521 -0.162921)
							(end -0.1016 -0.1778)
						)
						(arc
							(start 0.1016 -0.1778)
							(mid 0.137521 -0.162921)
							(end 0.1524 -0.127)
						)
					)
					(width 0)
					(fill yes)
				)
			)
		)
	)
	(footprint ""
		(layer "B.Cu")
		(at 115.4557 -66.3575)
		(property "Reference" "C172"
			(at 0 0 0)
			(layer "B.SilkS")
			(hide yes)
			(effects
				(font
					(size 1.27 1.27)
				)
				(justify mirror)
			)
		)
		(property "Value" "SCD1U6D3V1KX-GP"
			(at 2.8321 -1.7399 0)
			(unlocked yes)
			(layer "B.Fab")
			(hide yes)
			(effects
				(font
					(size 1.016 1.016)
					(thickness 0.1524)
				)
				(justify mirror)
			)
		)
		(property "Device Type" "C0201H13"
			(at 2.8321 -3.2639 0)
			(unlocked yes)
			(layer "B.Fab")
			(hide yes)
			(effects
				(font
					(size 1.016 1.016)
					(thickness 0.1524)
				)
				(justify mirror)
			)
		)
		(duplicate_pad_numbers_are_jumpers no)
		(fp_rect
			(start 0.2794 0.6477)
			(end -0.2794 -0.6477)
			(stroke
				(width 0)
				(type default)
			)
			(fill no)
			(layer "B.CrtYd")
		)
		(fp_rect
			(start 0.2794 0.6477)
			(end -0.2794 -0.6477)
			(stroke
				(width 0)
				(type default)
			)
			(fill no)
			(layer "B.Fab")
		)
		(pad "1" smd custom
			(at 0 -0.2794 180)
			(size 0.0762 0.0762)
			(layers "B.Cu" "B.Mask" "B.Paste")
			(net "P0V9")
			(options
				(clearance outline)
				(anchor circle)
			)
			(primitives
				(gr_poly
					(pts
						(arc
							(start 0.1524 0.127)
							(mid 0.137521 0.162921)
							(end 0.1016 0.1778)
						)
						(arc
							(start -0.1016 0.1778)
							(mid -0.137521 0.162921)
							(end -0.1524 0.127)
						)
						(arc
							(start -0.1524 -0.127)
							(mid -0.137521 -0.162921)
							(end -0.1016 -0.1778)
						)
						(arc
							(start 0.1016 -0.1778)
							(mid 0.137521 -0.162921)
							(end 0.1524 -0.127)
						)
					)
					(width 0)
					(fill yes)
				)
			)
		)
		(pad "2" smd custom
			(at 0 0.2794 180)
			(size 0.0762 0.0762)
			(layers "B.Cu" "B.Mask" "B.Paste")
			(net "GND")
			(options
				(clearance outline)
				(anchor circle)
			)
			(primitives
				(gr_poly
					(pts
						(arc
							(start 0.1524 0.127)
							(mid 0.137521 0.162921)
							(end 0.1016 0.1778)
						)
						(arc
							(start -0.1016 0.1778)
							(mid -0.137521 0.162921)
							(end -0.1524 0.127)
						)
						(arc
							(start -0.1524 -0.127)
							(mid -0.137521 -0.162921)
							(end -0.1016 -0.1778)
						)
						(arc
							(start 0.1016 -0.1778)
							(mid 0.137521 -0.162921)
							(end 0.1524 -0.127)
						)
					)
					(width 0)
					(fill yes)
				)
			)
		)
	)
	(footprint ""
		(layer "B.Cu")
		(at 122.5804 -72.4408 -90)
		(property "Reference" "C287"
			(at 0 0 90)
			(layer "B.SilkS")
			(hide yes)
			(effects
				(font
					(size 1.27 1.27)
				)
				(justify mirror)
			)
		)
		(property "Value" "SC1U6D3V1MX-GP"
			(at -1.9177 2.0193 270)
			(unlocked yes)
			(layer "B.Fab")
			(hide yes)
			(effects
				(font
					(size 1.016 1.016)
					(thickness 0.1524)
				)
				(justify mirror)
			)
		)
		(property "Device Type" "C0201H14"
			(at -1.9177 0.4953 270)
			(unlocked yes)
			(layer "B.Fab")
			(hide yes)
			(effects
				(font
					(size 1.016 1.016)
					(thickness 0.1524)
				)
				(justify mirror)
			)
		)
		(duplicate_pad_numbers_are_jumpers no)
		(fp_rect
			(start 0.1524 0.3048)
			(end -0.1524 -0.3048)
			(stroke
				(width 0)
				(type default)
			)
			(fill no)
			(layer "B.CrtYd")
		)
		(fp_poly
			(pts
				(xy 0.2794 0.6477) (xy 0.2794 -0.6477) (xy -0.2794 -0.6477) (xy -0.2794 -0.1905) (xy -0.1524 -0.1905)
				(xy -0.1524 -0.3048) (xy 0.1524 -0.3048) (xy 0.1524 0.3048) (xy -0.1524 0.3048) (xy -0.1524 -0.1778)
				(xy -0.2794 -0.1778) (xy -0.2794 0.6477)
			)
			(stroke
				(width 0)
				(type default)
			)
			(fill no)
			(layer "B.CrtYd")
		)
		(fp_rect
			(start 0.2794 0.6477)
			(end -0.2794 -0.6477)
			(stroke
				(width 0)
				(type default)
			)
			(fill no)
			(layer "B.Fab")
		)
		(pad "1" smd custom
			(at 0 -0.2794 90)
			(size 0.0762 0.0762)
			(layers "B.Cu" "B.Mask" "B.Paste")
			(net "GB_VDDA")
			(options
				(clearance outline)
				(anchor circle)
			)
			(primitives
				(gr_poly
					(pts
						(arc
							(start 0.1524 0.127)
							(mid 0.137521 0.162921)
							(end 0.1016 0.1778)
						)
						(arc
							(start -0.1016 0.1778)
							(mid -0.137521 0.162921)
							(end -0.1524 0.127)
						)
						(arc
							(start -0.1524 -0.127)
							(mid -0.137521 -0.162921)
							(end -0.1016 -0.1778)
						)
						(arc
							(start 0.1016 -0.1778)
							(mid 0.137521 -0.162921)
							(end 0.1524 -0.127)
						)
					)
					(width 0)
					(fill yes)
				)
			)
		)
		(pad "2" smd custom
			(at 0 0.2794 90)
			(size 0.0762 0.0762)
			(layers "B.Cu" "B.Mask" "B.Paste")
			(net "GND")
			(options
				(clearance outline)
				(anchor circle)
			)
			(primitives
				(gr_poly
					(pts
						(arc
							(start 0.1524 0.127)
							(mid 0.137521 0.162921)
							(end 0.1016 0.1778)
						)
						(arc
							(start -0.1016 0.1778)
							(mid -0.137521 0.162921)
							(end -0.1524 0.127)
						)
						(arc
							(start -0.1524 -0.127)
							(mid -0.137521 -0.162921)
							(end -0.1016 -0.1778)
						)
						(arc
							(start 0.1016 -0.1778)
							(mid 0.137521 -0.162921)
							(end 0.1524 -0.127)
						)
					)
					(width 0)
					(fill yes)
				)
			)
		)
	)
	(footprint ""
		(layer "B.Cu")
		(at 73.66 -46.736)
		(property "Reference" "C298"
			(at 0 0 0)
			(layer "B.SilkS")
			(hide yes)
			(effects
				(font
					(size 1.27 1.27)
				)
				(justify mirror)
			)
		)
		(property "Value" "SC100U6D3V6MX-GP"
			(at 0.0762 -5.1308 0)
			(unlocked yes)
			(layer "B.Fab")
			(hide yes)
			(effects
				(font
					(size 1.016 1.016)
					(thickness 0.1524)
				)
				(justify mirror)
			)
		)
		(property "Device Type" "C1206H71"
			(at 0.127 -6.6548 0)
			(unlocked yes)
			(layer "B.Fab")
			(hide yes)
			(effects
				(font
					(size 1.016 1.016)
					(thickness 0.1524)
				)
				(justify mirror)
			)
		)
		(duplicate_pad_numbers_are_jumpers no)
		(fp_line
			(start -1.016 -2.2352)
			(end -1.016 -0.8382)
			(stroke
				(width 0.1524)
				(type default)
			)
			(layer "B.SilkS")
		)
		(fp_line
			(start -1.016 0.8382)
			(end -1.016 2.2352)
			(stroke
				(width 0.1524)
				(type default)
			)
			(layer "B.SilkS")
		)
		(fp_line
			(start -1.016 2.2352)
			(end 1.016 2.2352)
			(stroke
				(width 0.1524)
				(type default)
			)
			(layer "B.SilkS")
		)
		(fp_line
			(start 1.016 -2.2352)
			(end -1.016 -2.2352)
			(stroke
				(width 0.1524)
				(type default)
			)
			(layer "B.SilkS")
		)
		(fp_line
			(start 1.016 -0.8382)
			(end 1.016 -2.2352)
			(stroke
				(width 0.1524)
				(type default)
			)
			(layer "B.SilkS")
		)
		(fp_line
			(start 1.016 2.2352)
			(end 1.016 0.8382)
			(stroke
				(width 0.1524)
				(type default)
			)
			(layer "B.SilkS")
		)
		(fp_rect
			(start 1.0922 2.3114)
			(end -1.0922 -2.3114)
			(stroke
				(width 0)
				(type default)
			)
			(fill no)
			(layer "B.CrtYd")
		)
		(fp_poly
			(pts
				(xy -1.0922 -2.3114) (xy -1.0922 2.3114) (xy 1.0922 2.3114) (xy 1.0922 -2.3114)
			)
			(stroke
				(width 0)
				(type default)
			)
			(fill no)
			(layer "B.Fab")
		)
		(pad "1" smd rect
			(at 0 -1.397 180)
			(size 1.651 1.27)
			(layers "B.Cu" "B.Mask" "B.Paste")
			(net "GB_VDDA")
		)
		(pad "2" smd rect
			(at 0 1.397 180)
			(size 1.651 1.27)
			(layers "B.Cu" "B.Mask" "B.Paste")
			(net "GND")
		)
	)
	(footprint ""
		(layer "B.Cu")
		(at 119.2657 -57.4802)
		(property "Reference" "C268"
			(at 0 0 0)
			(layer "B.SilkS")
			(hide yes)
			(effects
				(font
					(size 1.27 1.27)
				)
				(justify mirror)
			)
		)
		(property "Value" "SCD1U6D3V1KX-GP"
			(at 2.8321 -1.7399 0)
			(unlocked yes)
			(layer "B.Fab")
			(hide yes)
			(effects
				(font
					(size 1.016 1.016)
					(thickness 0.1524)
				)
				(justify mirror)
			)
		)
		(property "Device Type" "C0201H13"
			(at 2.8321 -3.2639 0)
			(unlocked yes)
			(layer "B.Fab")
			(hide yes)
			(effects
				(font
					(size 1.016 1.016)
					(thickness 0.1524)
				)
				(justify mirror)
			)
		)
		(duplicate_pad_numbers_are_jumpers no)
		(fp_rect
			(start 0.2794 0.6477)
			(end -0.2794 -0.6477)
			(stroke
				(width 0)
				(type default)
			)
			(fill no)
			(layer "B.CrtYd")
		)
		(fp_rect
			(start 0.2794 0.6477)
			(end -0.2794 -0.6477)
			(stroke
				(width 0)
				(type default)
			)
			(fill no)
			(layer "B.Fab")
		)
		(pad "1" smd custom
			(at 0 -0.2794 180)
			(size 0.0762 0.0762)
			(layers "B.Cu" "B.Mask" "B.Paste")
			(net "GB_VDDA")
			(options
				(clearance outline)
				(anchor circle)
			)
			(primitives
				(gr_poly
					(pts
						(arc
							(start 0.1524 0.127)
							(mid 0.137521 0.162921)
							(end 0.1016 0.1778)
						)
						(arc
							(start -0.1016 0.1778)
							(mid -0.137521 0.162921)
							(end -0.1524 0.127)
						)
						(arc
							(start -0.1524 -0.127)
							(mid -0.137521 -0.162921)
							(end -0.1016 -0.1778)
						)
						(arc
							(start 0.1016 -0.1778)
							(mid 0.137521 -0.162921)
							(end 0.1524 -0.127)
						)
					)
					(width 0)
					(fill yes)
				)
			)
		)
		(pad "2" smd custom
			(at 0 0.2794 180)
			(size 0.0762 0.0762)
			(layers "B.Cu" "B.Mask" "B.Paste")
			(net "GND")
			(options
				(clearance outline)
				(anchor circle)
			)
			(primitives
				(gr_poly
					(pts
						(arc
							(start 0.1524 0.127)
							(mid 0.137521 0.162921)
							(end 0.1016 0.1778)
						)
						(arc
							(start -0.1016 0.1778)
							(mid -0.137521 0.162921)
							(end -0.1524 0.127)
						)
						(arc
							(start -0.1524 -0.127)
							(mid -0.137521 -0.162921)
							(end -0.1016 -0.1778)
						)
						(arc
							(start 0.1016 -0.1778)
							(mid 0.137521 -0.162921)
							(end 0.1524 -0.127)
						)
					)
					(width 0)
					(fill yes)
				)
			)
		)
	)
	(footprint ""
		(layer "B.Cu")
		(at 106.500168 -75.50023)
		(property "Reference" "TP163"
			(at 0 0 0)
			(layer "B.SilkS")
			(hide yes)
			(effects
				(font
					(size 1.27 1.27)
				)
				(justify mirror)
			)
		)
		(property "Value" "TPAD28-2-GP"
			(at 0.0127 -1.6637 0)
			(unlocked yes)
			(layer "B.Fab")
			(hide yes)
			(effects
				(font
					(size 1.016 1.016)
					(thickness 0.1524)
				)
				(justify mirror)
			)
		)
		(property "Device Type" "TPAD28"
			(at 0.0127 -3.1877 0)
			(unlocked yes)
			(layer "B.Fab")
			(hide yes)
			(effects
				(font
					(size 1.016 1.016)
					(thickness 0.1524)
				)
				(justify mirror)
			)
		)
		(duplicate_pad_numbers_are_jumpers no)
		(fp_poly
			(pts
				(arc
					(start 0.3556 0)
					(mid -0.3556 0)
					(end 0.3556 0)
				)
			)
			(stroke
				(width 0)
				(type default)
			)
			(fill no)
			(layer "B.CrtYd")
		)
		(fp_poly
			(pts
				(arc
					(start 0.6096 0)
					(mid -0.6096 0)
					(end 0.6096 0)
				)
			)
			(stroke
				(width 0)
				(type default)
			)
			(fill no)
			(layer "B.Fab")
		)
		(pad "1" smd circle
			(at 0 0 180)
			(size 0.7112 0.7112)
			(layers "B.Cu" "B.Mask" "B.Paste")
			(net "LED11")
		)
	)
	(footprint ""
		(layer "B.Cu")
		(at 109.2708 -57.4802)
		(property "Reference" "C579"
			(at 0 0 0)
			(layer "B.SilkS")
			(hide yes)
			(effects
				(font
					(size 1.27 1.27)
				)
				(justify mirror)
			)
		)
		(property "Value" "SCD1U6D3V1KX-GP"
			(at 2.8321 -1.7399 0)
			(unlocked yes)
			(layer "B.Fab")
			(hide yes)
			(effects
				(font
					(size 1.016 1.016)
					(thickness 0.1524)
				)
				(justify mirror)
			)
		)
		(property "Device Type" "C0201H13"
			(at 2.8321 -3.2639 0)
			(unlocked yes)
			(layer "B.Fab")
			(hide yes)
			(effects
				(font
					(size 1.016 1.016)
					(thickness 0.1524)
				)
				(justify mirror)
			)
		)
		(duplicate_pad_numbers_are_jumpers no)
		(fp_rect
			(start 0.2794 0.6477)
			(end -0.2794 -0.6477)
			(stroke
				(width 0)
				(type default)
			)
			(fill no)
			(layer "B.CrtYd")
		)
		(fp_rect
			(start 0.2794 0.6477)
			(end -0.2794 -0.6477)
			(stroke
				(width 0)
				(type default)
			)
			(fill no)
			(layer "B.Fab")
		)
		(pad "1" smd custom
			(at 0 -0.2794 180)
			(size 0.0762 0.0762)
			(layers "B.Cu" "B.Mask" "B.Paste")
			(net "GB_VDDA")
			(options
				(clearance outline)
				(anchor circle)
			)
			(primitives
				(gr_poly
					(pts
						(arc
							(start 0.1524 0.127)
							(mid 0.137521 0.162921)
							(end 0.1016 0.1778)
						)
						(arc
							(start -0.1016 0.1778)
							(mid -0.137521 0.162921)
							(end -0.1524 0.127)
						)
						(arc
							(start -0.1524 -0.127)
							(mid -0.137521 -0.162921)
							(end -0.1016 -0.1778)
						)
						(arc
							(start 0.1016 -0.1778)
							(mid 0.137521 -0.162921)
							(end 0.1524 -0.127)
						)
					)
					(width 0)
					(fill yes)
				)
			)
		)
		(pad "2" smd custom
			(at 0 0.2794 180)
			(size 0.0762 0.0762)
			(layers "B.Cu" "B.Mask" "B.Paste")
			(net "GND")
			(options
				(clearance outline)
				(anchor circle)
			)
			(primitives
				(gr_poly
					(pts
						(arc
							(start 0.1524 0.127)
							(mid 0.137521 0.162921)
							(end 0.1016 0.1778)
						)
						(arc
							(start -0.1016 0.1778)
							(mid -0.137521 0.162921)
							(end -0.1524 0.127)
						)
						(arc
							(start -0.1524 -0.127)
							(mid -0.137521 -0.162921)
							(end -0.1016 -0.1778)
						)
						(arc
							(start 0.1016 -0.1778)
							(mid 0.137521 -0.162921)
							(end 0.1524 -0.127)
						)
					)
					(width 0)
					(fill yes)
				)
			)
		)
	)
	(footprint ""
		(layer "B.Cu")
		(at 177.60823 -28.64485 180)
		(property "Reference" "C386"
			(at 0 0 0)
			(layer "B.SilkS")
			(hide yes)
			(effects
				(font
					(size 1.27 1.27)
				)
				(justify mirror)
			)
		)
		(property "Value" "SCD1U6D3V1KX-GP"
			(at 2.8321 -1.7399 180)
			(unlocked yes)
			(layer "B.Fab")
			(hide yes)
			(effects
				(font
					(size 1.016 1.016)
					(thickness 0.1524)
				)
				(justify mirror)
			)
		)
		(property "Device Type" "C0201H13"
			(at 2.8321 -3.2639 180)
			(unlocked yes)
			(layer "B.Fab")
			(hide yes)
			(effects
				(font
					(size 1.016 1.016)
					(thickness 0.1524)
				)
				(justify mirror)
			)
		)
		(duplicate_pad_numbers_are_jumpers no)
		(fp_rect
			(start 0.2794 0.6477)
			(end -0.2794 -0.6477)
			(stroke
				(width 0)
				(type default)
			)
			(fill no)
			(layer "B.CrtYd")
		)
		(fp_rect
			(start 0.2794 0.6477)
			(end -0.2794 -0.6477)
			(stroke
				(width 0)
				(type default)
			)
			(fill no)
			(layer "B.Fab")
		)
		(pad "1" smd custom
			(at 0 -0.2794)
			(size 0.0762 0.0762)
			(layers "B.Cu" "B.Mask" "B.Paste")
			(net "PCE_AVDD")
			(options
				(clearance outline)
				(anchor circle)
			)
			(primitives
				(gr_poly
					(pts
						(arc
							(start 0.1524 0.127)
							(mid 0.137521 0.162921)
							(end 0.1016 0.1778)
						)
						(arc
							(start -0.1016 0.1778)
							(mid -0.137521 0.162921)
							(end -0.1524 0.127)
						)
						(arc
							(start -0.1524 -0.127)
							(mid -0.137521 -0.162921)
							(end -0.1016 -0.1778)
						)
						(arc
							(start 0.1016 -0.1778)
							(mid 0.137521 -0.162921)
							(end 0.1524 -0.127)
						)
					)
					(width 0)
					(fill yes)
				)
			)
		)
		(pad "2" smd custom
			(at 0 0.2794)
			(size 0.0762 0.0762)
			(layers "B.Cu" "B.Mask" "B.Paste")
			(net "GND")
			(options
				(clearance outline)
				(anchor circle)
			)
			(primitives
				(gr_poly
					(pts
						(arc
							(start 0.1524 0.127)
							(mid 0.137521 0.162921)
							(end 0.1016 0.1778)
						)
						(arc
							(start -0.1016 0.1778)
							(mid -0.137521 0.162921)
							(end -0.1524 0.127)
						)
						(arc
							(start -0.1524 -0.127)
							(mid -0.137521 -0.162921)
							(end -0.1016 -0.1778)
						)
						(arc
							(start 0.1016 -0.1778)
							(mid 0.137521 -0.162921)
							(end 0.1524 -0.127)
						)
					)
					(width 0)
					(fill yes)
				)
			)
		)
	)
	(footprint ""
		(layer "B.Cu")
		(at 110.9218 -44.2214 180)
		(property "Reference" "C69"
			(at 0 0 0)
			(layer "B.SilkS")
			(hide yes)
			(effects
				(font
					(size 1.27 1.27)
				)
				(justify mirror)
			)
		)
		(property "Value" "SCD01U16V1KX-GP"
			(at 2.8321 -1.7399 180)
			(unlocked yes)
			(layer "B.Fab")
			(hide yes)
			(effects
				(font
					(size 1.016 1.016)
					(thickness 0.1524)
				)
				(justify mirror)
			)
		)
		(property "Device Type" "C0201H13"
			(at 2.8321 -3.2639 180)
			(unlocked yes)
			(layer "B.Fab")
			(hide yes)
			(effects
				(font
					(size 1.016 1.016)
					(thickness 0.1524)
				)
				(justify mirror)
			)
		)
		(duplicate_pad_numbers_are_jumpers no)
		(fp_rect
			(start 0.2794 0.6477)
			(end -0.2794 -0.6477)
			(stroke
				(width 0)
				(type default)
			)
			(fill no)
			(layer "B.CrtYd")
		)
		(fp_rect
			(start 0.2794 0.6477)
			(end -0.2794 -0.6477)
			(stroke
				(width 0)
				(type default)
			)
			(fill no)
			(layer "B.Fab")
		)
		(pad "1" smd custom
			(at 0 -0.2794)
			(size 0.0762 0.0762)
			(layers "B.Cu" "B.Mask" "B.Paste")
			(net "PHY_DPB_TO_SCC_25_DP")
			(options
				(clearance outline)
				(anchor circle)
			)
			(primitives
				(gr_poly
					(pts
						(arc
							(start 0.1524 0.127)
							(mid 0.137521 0.162921)
							(end 0.1016 0.1778)
						)
						(arc
							(start -0.1016 0.1778)
							(mid -0.137521 0.162921)
							(end -0.1524 0.127)
						)
						(arc
							(start -0.1524 -0.127)
							(mid -0.137521 -0.162921)
							(end -0.1016 -0.1778)
						)
						(arc
							(start 0.1016 -0.1778)
							(mid 0.137521 -0.162921)
							(end 0.1524 -0.127)
						)
					)
					(width 0)
					(fill yes)
				)
			)
		)
		(pad "2" smd custom
			(at 0 0.2794)
			(size 0.0762 0.0762)
			(layers "B.Cu" "B.Mask" "B.Paste")
			(net "PHY_DPB_TO_SCC_C_25_DP")
			(options
				(clearance outline)
				(anchor circle)
			)
			(primitives
				(gr_poly
					(pts
						(arc
							(start 0.1524 0.127)
							(mid 0.137521 0.162921)
							(end 0.1016 0.1778)
						)
						(arc
							(start -0.1016 0.1778)
							(mid -0.137521 0.162921)
							(end -0.1524 0.127)
						)
						(arc
							(start -0.1524 -0.127)
							(mid -0.137521 -0.162921)
							(end -0.1016 -0.1778)
						)
						(arc
							(start 0.1016 -0.1778)
							(mid 0.137521 -0.162921)
							(end 0.1524 -0.127)
						)
					)
					(width 0)
					(fill yes)
				)
			)
		)
	)
	(footprint ""
		(layer "B.Cu")
		(at 142.0622 -123.1646 90)
		(property "Reference" "Q10"
			(at 0 0 90)
			(layer "B.SilkS")
			(hide yes)
			(effects
				(font
					(size 1.27 1.27)
				)
				(justify mirror)
			)
		)
		(property "Value" "2N7002K-1-GP"
			(at -0.127 -8.9662 90)
			(unlocked yes)
			(layer "B.Fab")
			(hide yes)
			(effects
				(font
					(size 1.016 1.016)
					(thickness 0.1524)
				)
				(justify mirror)
			)
		)
		(property "Device Type" "SOT23DGS2D4H44"
			(at -0.127 -10.4902 90)
			(unlocked yes)
			(layer "B.Fab")
			(hide yes)
			(effects
				(font
					(size 1.016 1.016)
					(thickness 0.1524)
				)
				(justify mirror)
			)
		)
		(duplicate_pad_numbers_are_jumpers no)
		(fp_line
			(start 1.651 -1.778)
			(end 1.651 1.778)
			(stroke
				(width 0.1524)
				(type default)
			)
			(layer "B.SilkS")
		)
		(fp_line
			(start -1.651 -1.778)
			(end 1.651 -1.778)
			(stroke
				(width 0.1524)
				(type default)
			)
			(layer "B.SilkS")
		)
		(fp_line
			(start 1.651 1.778)
			(end -1.651 1.778)
			(stroke
				(width 0.1524)
				(type default)
			)
			(layer "B.SilkS")
		)
		(fp_line
			(start -1.651 1.778)
			(end -1.651 -1.778)
			(stroke
				(width 0.1524)
				(type default)
			)
			(layer "B.SilkS")
		)
		(fp_poly
			(pts
				(xy 1.778 1.8796) (xy 1.778 -1.8796) (xy -1.778 -1.8796) (xy -1.778 1.8796)
			)
			(stroke
				(width 0)
				(type default)
			)
			(fill no)
			(layer "B.CrtYd")
		)
		(fp_poly
			(pts
				(xy 1.778 1.8796) (xy 1.778 -1.8796) (xy -1.778 -1.8796) (xy -1.778 1.8796)
			)
			(stroke
				(width 0)
				(type default)
			)
			(fill no)
			(layer "B.Fab")
		)
		(pad "D" smd custom
			(at 0 -0.9525 270)
			(size 0.1905 0.1905)
			(layers "B.Cu" "B.Mask" "B.Paste")
			(net "P1V5_C_PG_R_1")
			(options
				(clearance outline)
				(anchor circle)
			)
			(primitives
				(gr_poly
					(pts
						(arc
							(start -0.1778 -0.5715)
							(mid -0.321484 -0.511984)
							(end -0.381 -0.3683)
						)
						(arc
							(start -0.381 0.3683)
							(mid -0.321484 0.511984)
							(end -0.1778 0.5715)
						)
						(arc
							(start 0.1778 0.5715)
							(mid 0.321484 0.511984)
							(end 0.381 0.3683)
						)
						(arc
							(start 0.381 -0.3683)
							(mid 0.321484 -0.511984)
							(end 0.1778 -0.5715)
						)
					)
					(width 0)
					(fill yes)
				)
			)
		)
		(pad "G" smd custom
			(at 0.98425 0.9525 270)
			(size 0.1905 0.1905)
			(layers "B.Cu" "B.Mask" "B.Paste")
			(net "P12V_STBY_Q10_G")
			(options
				(clearance outline)
				(anchor circle)
			)
			(primitives
				(gr_poly
					(pts
						(arc
							(start -0.1778 -0.5715)
							(mid -0.321484 -0.511984)
							(end -0.381 -0.3683)
						)
						(arc
							(start -0.381 0.3683)
							(mid -0.321484 0.511984)
							(end -0.1778 0.5715)
						)
						(arc
							(start 0.1778 0.5715)
							(mid 0.321484 0.511984)
							(end 0.381 0.3683)
						)
						(arc
							(start 0.381 -0.3683)
							(mid 0.321484 -0.511984)
							(end 0.1778 -0.5715)
						)
					)
					(width 0)
					(fill yes)
				)
			)
		)
		(pad "S" smd custom
			(at -0.98425 0.9525 270)
			(size 0.1905 0.1905)
			(layers "B.Cu" "B.Mask" "B.Paste")
			(net "GND")
			(options
				(clearance outline)
				(anchor circle)
			)
			(primitives
				(gr_poly
					(pts
						(arc
							(start -0.1778 -0.5715)
							(mid -0.321484 -0.511984)
							(end -0.381 -0.3683)
						)
						(arc
							(start -0.381 0.3683)
							(mid -0.321484 0.511984)
							(end -0.1778 0.5715)
						)
						(arc
							(start 0.1778 0.5715)
							(mid 0.321484 0.511984)
							(end 0.381 0.3683)
						)
						(arc
							(start 0.381 -0.3683)
							(mid 0.321484 -0.511984)
							(end 0.1778 -0.5715)
						)
					)
					(width 0)
					(fill yes)
				)
			)
		)
	)
	(footprint ""
		(layer "B.Cu")
		(at 122.0216 -39.4716 180)
		(property "Reference" "C55"
			(at 0 0 0)
			(layer "B.SilkS")
			(hide yes)
			(effects
				(font
					(size 1.27 1.27)
				)
				(justify mirror)
			)
		)
		(property "Value" "SCD01U16V1KX-GP"
			(at 2.8321 -1.7399 180)
			(unlocked yes)
			(layer "B.Fab")
			(hide yes)
			(effects
				(font
					(size 1.016 1.016)
					(thickness 0.1524)
				)
				(justify mirror)
			)
		)
		(property "Device Type" "C0201H13"
			(at 2.8321 -3.2639 180)
			(unlocked yes)
			(layer "B.Fab")
			(hide yes)
			(effects
				(font
					(size 1.016 1.016)
					(thickness 0.1524)
				)
				(justify mirror)
			)
		)
		(duplicate_pad_numbers_are_jumpers no)
		(fp_rect
			(start 0.2794 0.6477)
			(end -0.2794 -0.6477)
			(stroke
				(width 0)
				(type default)
			)
			(fill no)
			(layer "B.CrtYd")
		)
		(fp_rect
			(start 0.2794 0.6477)
			(end -0.2794 -0.6477)
			(stroke
				(width 0)
				(type default)
			)
			(fill no)
			(layer "B.Fab")
		)
		(pad "1" smd custom
			(at 0 -0.2794)
			(size 0.0762 0.0762)
			(layers "B.Cu" "B.Mask" "B.Paste")
			(net "PHY_DPB_TO_SCC_36_DP")
			(options
				(clearance outline)
				(anchor circle)
			)
			(primitives
				(gr_poly
					(pts
						(arc
							(start 0.1524 0.127)
							(mid 0.137521 0.162921)
							(end 0.1016 0.1778)
						)
						(arc
							(start -0.1016 0.1778)
							(mid -0.137521 0.162921)
							(end -0.1524 0.127)
						)
						(arc
							(start -0.1524 -0.127)
							(mid -0.137521 -0.162921)
							(end -0.1016 -0.1778)
						)
						(arc
							(start 0.1016 -0.1778)
							(mid 0.137521 -0.162921)
							(end 0.1524 -0.127)
						)
					)
					(width 0)
					(fill yes)
				)
			)
		)
		(pad "2" smd custom
			(at 0 0.2794)
			(size 0.0762 0.0762)
			(layers "B.Cu" "B.Mask" "B.Paste")
			(net "PHY_DPB_TO_SCC_C_36_DP")
			(options
				(clearance outline)
				(anchor circle)
			)
			(primitives
				(gr_poly
					(pts
						(arc
							(start 0.1524 0.127)
							(mid 0.137521 0.162921)
							(end 0.1016 0.1778)
						)
						(arc
							(start -0.1016 0.1778)
							(mid -0.137521 0.162921)
							(end -0.1524 0.127)
						)
						(arc
							(start -0.1524 -0.127)
							(mid -0.137521 -0.162921)
							(end -0.1016 -0.1778)
						)
						(arc
							(start 0.1016 -0.1778)
							(mid 0.137521 -0.162921)
							(end 0.1524 -0.127)
						)
					)
					(width 0)
					(fill yes)
				)
			)
		)
	)
	(footprint ""
		(layer "B.Cu")
		(at 186.931808 -40.72001 -90)
		(property "Reference" "R191"
			(at 0 0 90)
			(layer "B.SilkS")
			(hide yes)
			(effects
				(font
					(size 1.27 1.27)
				)
				(justify mirror)
			)
		)
		(property "Value" "2K2R2F-GP"
			(at -0.064008 -3.993896 270)
			(unlocked yes)
			(layer "B.Fab")
			(hide yes)
			(effects
				(font
					(size 1.016 1.016)
					(thickness 0.1524)
				)
				(justify mirror)
			)
		)
		(property "Device Type" "R402H16"
			(at -0.064008 -5.517896 270)
			(unlocked yes)
			(layer "B.Fab")
			(hide yes)
			(effects
				(font
					(size 1.016 1.016)
					(thickness 0.1524)
				)
				(justify mirror)
			)
		)
		(duplicate_pad_numbers_are_jumpers no)
		(fp_line
			(start -0.508 -0.9398)
			(end 0.508 -0.9398)
			(stroke
				(width 0.1524)
				(type default)
			)
			(layer "B.SilkS")
		)
		(fp_line
			(start 0.508 -0.9398)
			(end 0.508 0.9398)
			(stroke
				(width 0.1524)
				(type default)
			)
			(layer "B.SilkS")
		)
		(fp_rect
			(start 0.508 0.9398)
			(end -0.508 -0.9398)
			(stroke
				(width 0)
				(type default)
			)
			(fill no)
			(layer "B.CrtYd")
		)
		(fp_rect
			(start 0.508 0.9398)
			(end -0.508 -0.9398)
			(stroke
				(width 0)
				(type default)
			)
			(fill no)
			(layer "B.Fab")
		)
		(pad "1" smd custom
			(at 0 -0.4445 90)
			(size 0.1397 0.1397)
			(layers "B.Cu" "B.Mask" "B.Paste")
			(net "P1V8_C")
			(options
				(clearance outline)
				(anchor circle)
			)
			(primitives
				(gr_poly
					(pts
						(arc
							(start -0.1778 0.2794)
							(mid -0.249642 0.249642)
							(end -0.2794 0.1778)
						)
						(arc
							(start -0.2794 -0.1778)
							(mid -0.249642 -0.249642)
							(end -0.1778 -0.2794)
						)
						(arc
							(start 0.1778 -0.2794)
							(mid 0.249642 -0.249642)
							(end 0.2794 -0.1778)
						)
						(arc
							(start 0.2794 0.1778)
							(mid 0.249642 0.249642)
							(end 0.1778 0.2794)
						)
					)
					(width 0)
					(fill yes)
				)
			)
		)
		(pad "2" smd custom
			(at 0 0.4445 90)
			(size 0.1397 0.1397)
			(layers "B.Cu" "B.Mask" "B.Paste")
			(net "I2C_IOC_4_SDA")
			(options
				(clearance outline)
				(anchor circle)
			)
			(primitives
				(gr_poly
					(pts
						(arc
							(start -0.1778 0.2794)
							(mid -0.249642 0.249642)
							(end -0.2794 0.1778)
						)
						(arc
							(start -0.2794 -0.1778)
							(mid -0.249642 -0.249642)
							(end -0.1778 -0.2794)
						)
						(arc
							(start 0.1778 -0.2794)
							(mid 0.249642 -0.249642)
							(end 0.2794 -0.1778)
						)
						(arc
							(start 0.2794 0.1778)
							(mid 0.249642 0.249642)
							(end 0.1778 0.2794)
						)
					)
					(width 0)
					(fill yes)
				)
			)
		)
	)
	(footprint ""
		(layer "B.Cu")
		(at 163.3093 -34.2646 90)
		(property "Reference" "C375"
			(at 0 0 90)
			(layer "B.SilkS")
			(hide yes)
			(effects
				(font
					(size 1.27 1.27)
				)
				(justify mirror)
			)
		)
		(property "Value" "SCD1U16V2KX-3GP"
			(at -1.1811 -2.7051 90)
			(unlocked yes)
			(layer "B.Fab")
			(hide yes)
			(effects
				(font
					(size 1.016 1.016)
					(thickness 0.1524)
				)
				(justify mirror)
			)
		)
		(property "Device Type" "C402H22"
			(at -1.1811 -4.2291 90)
			(unlocked yes)
			(layer "B.Fab")
			(hide yes)
			(effects
				(font
					(size 1.016 1.016)
					(thickness 0.1524)
				)
				(justify mirror)
			)
		)
		(duplicate_pad_numbers_are_jumpers no)
		(fp_rect
			(start 0.4318 0.9525)
			(end -0.4318 -0.9525)
			(stroke
				(width 0)
				(type default)
			)
			(fill no)
			(layer "B.CrtYd")
		)
		(fp_rect
			(start 0.4318 0.9525)
			(end -0.4318 -0.9525)
			(stroke
				(width 0)
				(type default)
			)
			(fill no)
			(layer "B.Fab")
		)
		(pad "1" smd custom
			(at 0 -0.4445 270)
			(size 0.1524 0.1524)
			(layers "B.Cu" "B.Mask" "B.Paste")
			(net "SAS0_VDDH")
			(options
				(clearance outline)
				(anchor circle)
			)
			(primitives
				(gr_poly
					(pts
						(arc
							(start 0.3048 0.2032)
							(mid 0.275042 0.275042)
							(end 0.2032 0.3048)
						)
						(arc
							(start -0.2032 0.3048)
							(mid -0.275042 0.275042)
							(end -0.3048 0.2032)
						)
						(arc
							(start -0.3048 -0.2032)
							(mid -0.275042 -0.275042)
							(end -0.2032 -0.3048)
						)
						(arc
							(start 0.2032 -0.3048)
							(mid 0.275042 -0.275042)
							(end 0.3048 -0.2032)
						)
					)
					(width 0)
					(fill yes)
				)
			)
		)
		(pad "2" smd custom
			(at 0 0.4445 270)
			(size 0.1524 0.1524)
			(layers "B.Cu" "B.Mask" "B.Paste")
			(net "GND")
			(options
				(clearance outline)
				(anchor circle)
			)
			(primitives
				(gr_poly
					(pts
						(arc
							(start 0.3048 0.2032)
							(mid 0.275042 0.275042)
							(end 0.2032 0.3048)
						)
						(arc
							(start -0.2032 0.3048)
							(mid -0.275042 0.275042)
							(end -0.3048 0.2032)
						)
						(arc
							(start -0.3048 -0.2032)
							(mid -0.275042 -0.275042)
							(end -0.2032 -0.3048)
						)
						(arc
							(start 0.2032 -0.3048)
							(mid 0.275042 -0.275042)
							(end 0.3048 -0.2032)
						)
					)
					(width 0)
					(fill yes)
				)
			)
		)
	)
	(footprint ""
		(layer "B.Cu")
		(at 116.6241 -57.4802)
		(property "Reference" "C265"
			(at 0 0 0)
			(layer "B.SilkS")
			(hide yes)
			(effects
				(font
					(size 1.27 1.27)
				)
				(justify mirror)
			)
		)
		(property "Value" "SCD1U6D3V1KX-GP"
			(at 2.8321 -1.7399 0)
			(unlocked yes)
			(layer "B.Fab")
			(hide yes)
			(effects
				(font
					(size 1.016 1.016)
					(thickness 0.1524)
				)
				(justify mirror)
			)
		)
		(property "Device Type" "C0201H13"
			(at 2.8321 -3.2639 0)
			(unlocked yes)
			(layer "B.Fab")
			(hide yes)
			(effects
				(font
					(size 1.016 1.016)
					(thickness 0.1524)
				)
				(justify mirror)
			)
		)
		(duplicate_pad_numbers_are_jumpers no)
		(fp_rect
			(start 0.2794 0.6477)
			(end -0.2794 -0.6477)
			(stroke
				(width 0)
				(type default)
			)
			(fill no)
			(layer "B.CrtYd")
		)
		(fp_rect
			(start 0.2794 0.6477)
			(end -0.2794 -0.6477)
			(stroke
				(width 0)
				(type default)
			)
			(fill no)
			(layer "B.Fab")
		)
		(pad "1" smd custom
			(at 0 -0.2794 180)
			(size 0.0762 0.0762)
			(layers "B.Cu" "B.Mask" "B.Paste")
			(net "GB_VDDA")
			(options
				(clearance outline)
				(anchor circle)
			)
			(primitives
				(gr_poly
					(pts
						(arc
							(start 0.1524 0.127)
							(mid 0.137521 0.162921)
							(end 0.1016 0.1778)
						)
						(arc
							(start -0.1016 0.1778)
							(mid -0.137521 0.162921)
							(end -0.1524 0.127)
						)
						(arc
							(start -0.1524 -0.127)
							(mid -0.137521 -0.162921)
							(end -0.1016 -0.1778)
						)
						(arc
							(start 0.1016 -0.1778)
							(mid 0.137521 -0.162921)
							(end 0.1524 -0.127)
						)
					)
					(width 0)
					(fill yes)
				)
			)
		)
		(pad "2" smd custom
			(at 0 0.2794 180)
			(size 0.0762 0.0762)
			(layers "B.Cu" "B.Mask" "B.Paste")
			(net "GND")
			(options
				(clearance outline)
				(anchor circle)
			)
			(primitives
				(gr_poly
					(pts
						(arc
							(start 0.1524 0.127)
							(mid 0.137521 0.162921)
							(end 0.1016 0.1778)
						)
						(arc
							(start -0.1016 0.1778)
							(mid -0.137521 0.162921)
							(end -0.1524 0.127)
						)
						(arc
							(start -0.1524 -0.127)
							(mid -0.137521 -0.162921)
							(end -0.1016 -0.1778)
						)
						(arc
							(start 0.1016 -0.1778)
							(mid 0.137521 -0.162921)
							(end 0.1524 -0.127)
						)
					)
					(width 0)
					(fill yes)
				)
			)
		)
	)
	(footprint ""
		(layer "B.Cu")
		(at 93.30436 -64.04356)
		(property "Reference" "C193"
			(at 0 0 0)
			(layer "B.SilkS")
			(hide yes)
			(effects
				(font
					(size 1.27 1.27)
				)
				(justify mirror)
			)
		)
		(property "Value" "SC10U6D3V2MX-GP-U"
			(at 1.524 -1.905 0)
			(unlocked yes)
			(layer "B.Fab")
			(hide yes)
			(effects
				(font
					(size 1.016 1.016)
					(thickness 0.1524)
				)
				(justify mirror)
			)
		)
		(property "Device Type" "C402-TO0D2H28"
			(at 1.524 -3.429 0)
			(unlocked yes)
			(layer "B.Fab")
			(hide yes)
			(effects
				(font
					(size 1.016 1.016)
					(thickness 0.1524)
				)
				(justify mirror)
			)
		)
		(duplicate_pad_numbers_are_jumpers no)
		(fp_rect
			(start 0.4826 0.889)
			(end -0.4826 -0.889)
			(stroke
				(width 0)
				(type default)
			)
			(fill no)
			(layer "B.CrtYd")
		)
		(fp_rect
			(start 0.4826 0.889)
			(end -0.4826 -0.889)
			(stroke
				(width 0)
				(type default)
			)
			(fill no)
			(layer "B.Fab")
		)
		(pad "1" smd custom
			(at 0 -0.4572 180)
			(size 0.1524 0.1524)
			(layers "B.Cu" "B.Mask" "B.Paste")
			(net "XTAL_VDDA18")
			(options
				(clearance outline)
				(anchor circle)
			)
			(primitives
				(gr_poly
					(pts
						(arc
							(start -0.254 -0.3048)
							(mid -0.325842 -0.275042)
							(end -0.3556 -0.2032)
						)
						(arc
							(start -0.3556 0.2032)
							(mid -0.325842 0.275042)
							(end -0.254 0.3048)
						)
						(arc
							(start 0.254 0.3048)
							(mid 0.325842 0.275042)
							(end 0.3556 0.2032)
						)
						(arc
							(start 0.3556 -0.2032)
							(mid 0.325842 -0.275042)
							(end 0.254 -0.3048)
						)
					)
					(width 0)
					(fill yes)
				)
			)
		)
		(pad "2" smd custom
			(at 0 0.4572 180)
			(size 0.1524 0.1524)
			(layers "B.Cu" "B.Mask" "B.Paste")
			(net "GND")
			(options
				(clearance outline)
				(anchor circle)
			)
			(primitives
				(gr_poly
					(pts
						(arc
							(start -0.254 -0.3048)
							(mid -0.325842 -0.275042)
							(end -0.3556 -0.2032)
						)
						(arc
							(start -0.3556 0.2032)
							(mid -0.325842 0.275042)
							(end -0.254 0.3048)
						)
						(arc
							(start 0.254 0.3048)
							(mid 0.325842 0.275042)
							(end 0.3556 0.2032)
						)
						(arc
							(start 0.3556 -0.2032)
							(mid 0.325842 -0.275042)
							(end 0.254 -0.3048)
						)
					)
					(width 0)
					(fill yes)
				)
			)
		)
	)
	(footprint ""
		(layer "B.Cu")
		(at 154.108404 -59.677808 -90)
		(property "Reference" "C358"
			(at 0 0 90)
			(layer "B.SilkS")
			(hide yes)
			(effects
				(font
					(size 1.27 1.27)
				)
				(justify mirror)
			)
		)
		(property "Value" "SCD1U16V2KX-3GP"
			(at -1.1811 -2.7051 270)
			(unlocked yes)
			(layer "B.Fab")
			(hide yes)
			(effects
				(font
					(size 1.016 1.016)
					(thickness 0.1524)
				)
				(justify mirror)
			)
		)
		(property "Device Type" "C402H22"
			(at -1.1811 -4.2291 270)
			(unlocked yes)
			(layer "B.Fab")
			(hide yes)
			(effects
				(font
					(size 1.016 1.016)
					(thickness 0.1524)
				)
				(justify mirror)
			)
		)
		(duplicate_pad_numbers_are_jumpers no)
		(fp_rect
			(start 0.4318 0.9525)
			(end -0.4318 -0.9525)
			(stroke
				(width 0)
				(type default)
			)
			(fill no)
			(layer "B.CrtYd")
		)
		(fp_rect
			(start 0.4318 0.9525)
			(end -0.4318 -0.9525)
			(stroke
				(width 0)
				(type default)
			)
			(fill no)
			(layer "B.Fab")
		)
		(pad "1" smd custom
			(at 0 -0.4445 90)
			(size 0.1524 0.1524)
			(layers "B.Cu" "B.Mask" "B.Paste")
			(net "SYS_PLL_VDD")
			(options
				(clearance outline)
				(anchor circle)
			)
			(primitives
				(gr_poly
					(pts
						(arc
							(start 0.3048 0.2032)
							(mid 0.275042 0.275042)
							(end 0.2032 0.3048)
						)
						(arc
							(start -0.2032 0.3048)
							(mid -0.275042 0.275042)
							(end -0.3048 0.2032)
						)
						(arc
							(start -0.3048 -0.2032)
							(mid -0.275042 -0.275042)
							(end -0.2032 -0.3048)
						)
						(arc
							(start 0.2032 -0.3048)
							(mid 0.275042 -0.275042)
							(end 0.3048 -0.2032)
						)
					)
					(width 0)
					(fill yes)
				)
			)
		)
		(pad "2" smd custom
			(at 0 0.4445 90)
			(size 0.1524 0.1524)
			(layers "B.Cu" "B.Mask" "B.Paste")
			(net "GND")
			(options
				(clearance outline)
				(anchor circle)
			)
			(primitives
				(gr_poly
					(pts
						(arc
							(start 0.3048 0.2032)
							(mid 0.275042 0.275042)
							(end 0.2032 0.3048)
						)
						(arc
							(start -0.2032 0.3048)
							(mid -0.275042 0.275042)
							(end -0.3048 0.2032)
						)
						(arc
							(start -0.3048 -0.2032)
							(mid -0.275042 -0.275042)
							(end -0.2032 -0.3048)
						)
						(arc
							(start 0.2032 -0.3048)
							(mid 0.275042 -0.275042)
							(end 0.3048 -0.2032)
						)
					)
					(width 0)
					(fill yes)
				)
			)
		)
	)
	(footprint ""
		(layer "B.Cu")
		(at 197.231 -24.257 180)
		(property "Reference" "LED1"
			(at 0 0 0)
			(layer "B.SilkS")
			(hide yes)
			(effects
				(font
					(size 1.27 1.27)
				)
				(justify mirror)
			)
		)
		(property "Value" "LED-YG-51-GP"
			(at 2.6924 -1.4224 180)
			(unlocked yes)
			(layer "B.Fab")
			(hide yes)
			(effects
				(font
					(size 1.016 1.016)
					(thickness 0.1524)
				)
				(justify mirror)
			)
		)
		(property "Device Type" "LED1608AKH40"
			(at 2.6924 -2.9464 180)
			(unlocked yes)
			(layer "B.Fab")
			(hide yes)
			(effects
				(font
					(size 1.016 1.016)
					(thickness 0.1524)
				)
				(justify mirror)
			)
		)
		(duplicate_pad_numbers_are_jumpers no)
		(fp_line
			(start 0.7493 1.651)
			(end 0.7493 1.1811)
			(stroke
				(width 0.3302)
				(type default)
			)
			(layer "B.SilkS")
		)
		(fp_line
			(start 0.6604 1.3716)
			(end 0.6604 -1.3716)
			(stroke
				(width 0.1524)
				(type default)
			)
			(layer "B.SilkS")
		)
		(fp_line
			(start 0.6604 -1.3716)
			(end -0.6604 -1.3716)
			(stroke
				(width 0.1524)
				(type default)
			)
			(layer "B.SilkS")
		)
		(fp_line
			(start 0.5969 1.5494)
			(end -0.5842 1.5494)
			(stroke
				(width 0.508)
				(type default)
			)
			(layer "B.SilkS")
		)
		(fp_line
			(start -0.6604 1.3716)
			(end 0.6604 1.3716)
			(stroke
				(width 0.1524)
				(type default)
			)
			(layer "B.SilkS")
		)
		(fp_line
			(start -0.6604 -1.3716)
			(end -0.6604 1.3716)
			(stroke
				(width 0.1524)
				(type default)
			)
			(layer "B.SilkS")
		)
		(fp_line
			(start -0.7493 1.651)
			(end -0.7493 1.1811)
			(stroke
				(width 0.3302)
				(type default)
			)
			(layer "B.SilkS")
		)
		(fp_rect
			(start 0.6223 1.3335)
			(end -0.6223 -1.3335)
			(stroke
				(width 0)
				(type default)
			)
			(fill no)
			(layer "B.CrtYd")
		)
		(fp_rect
			(start 0.6223 1.3335)
			(end -0.6223 -1.3335)
			(stroke
				(width 0)
				(type default)
			)
			(fill no)
			(layer "B.Fab")
		)
		(pad "A" smd custom
			(at 0 -0.762)
			(size 0.2159 0.2159)
			(layers "B.Cu" "B.Mask" "B.Paste")
			(net "SYS_HB_LED_R")
			(options
				(clearance outline)
				(anchor circle)
			)
			(primitives
				(gr_poly
					(pts
						(arc
							(start -0.3302 0.4318)
							(mid -0.402042 0.402042)
							(end -0.4318 0.3302)
						)
						(arc
							(start -0.4318 -0.3302)
							(mid -0.402042 -0.402042)
							(end -0.3302 -0.4318)
						)
						(arc
							(start 0.3302 -0.4318)
							(mid 0.402042 -0.402042)
							(end 0.4318 -0.3302)
						)
						(arc
							(start 0.4318 0.3302)
							(mid 0.402042 0.402042)
							(end 0.3302 0.4318)
						)
					)
					(width 0)
					(fill yes)
				)
			)
		)
		(pad "K" smd custom
			(at 0 0.762)
			(size 0.2159 0.2159)
			(layers "B.Cu" "B.Mask" "B.Paste")
			(net "SYS_HB_LED_D")
			(options
				(clearance outline)
				(anchor circle)
			)
			(primitives
				(gr_poly
					(pts
						(arc
							(start -0.3302 0.4318)
							(mid -0.402042 0.402042)
							(end -0.4318 0.3302)
						)
						(arc
							(start -0.4318 -0.3302)
							(mid -0.402042 -0.402042)
							(end -0.3302 -0.4318)
						)
						(arc
							(start 0.3302 -0.4318)
							(mid 0.402042 -0.402042)
							(end 0.4318 -0.3302)
						)
						(arc
							(start 0.4318 0.3302)
							(mid 0.402042 0.402042)
							(end 0.3302 0.4318)
						)
					)
					(width 0)
					(fill yes)
				)
			)
		)
	)
	(footprint ""
		(layer "B.Cu")
		(at 163.068 -64.008 -90)
		(property "Reference" "C367"
			(at 0 0 90)
			(layer "B.SilkS")
			(hide yes)
			(effects
				(font
					(size 1.27 1.27)
				)
				(justify mirror)
			)
		)
		(property "Value" "SC22U6D3V3MX-9-GP-U"
			(at 0 -2.8194 270)
			(unlocked yes)
			(layer "B.Fab")
			(hide yes)
			(effects
				(font
					(size 1.016 1.016)
					(thickness 0.1524)
				)
				(justify mirror)
			)
		)
		(property "Device Type" "C603H40"
			(at 0 -4.3434 270)
			(unlocked yes)
			(layer "B.Fab")
			(hide yes)
			(effects
				(font
					(size 1.016 1.016)
					(thickness 0.1524)
				)
				(justify mirror)
			)
		)
		(duplicate_pad_numbers_are_jumpers no)
		(fp_line
			(start -0.508 0)
			(end 0.508 0)
			(stroke
				(width 0.2032)
				(type default)
			)
			(layer "B.SilkS")
		)
		(fp_rect
			(start 0.5842 1.3335)
			(end -0.5842 -1.3335)
			(stroke
				(width 0)
				(type default)
			)
			(fill no)
			(layer "B.CrtYd")
		)
		(fp_rect
			(start 0.5842 1.3335)
			(end -0.5842 -1.3335)
			(stroke
				(width 0)
				(type default)
			)
			(fill no)
			(layer "B.Fab")
		)
		(pad "1" smd custom
			(at 0 -0.762 90)
			(size 0.2159 0.2159)
			(layers "B.Cu" "B.Mask" "B.Paste")
			(net "VDDA_SAS_REF_CLK")
			(options
				(clearance outline)
				(anchor circle)
			)
			(primitives
				(gr_poly
					(pts
						(arc
							(start -0.3302 0.4318)
							(mid -0.402042 0.402042)
							(end -0.4318 0.3302)
						)
						(arc
							(start -0.4318 -0.3302)
							(mid -0.402042 -0.402042)
							(end -0.3302 -0.4318)
						)
						(arc
							(start 0.3302 -0.4318)
							(mid 0.402042 -0.402042)
							(end 0.4318 -0.3302)
						)
						(arc
							(start 0.4318 0.3302)
							(mid 0.402042 0.402042)
							(end 0.3302 0.4318)
						)
					)
					(width 0)
					(fill yes)
				)
			)
		)
		(pad "2" smd custom
			(at 0 0.762 90)
			(size 0.2159 0.2159)
			(layers "B.Cu" "B.Mask" "B.Paste")
			(net "GND")
			(options
				(clearance outline)
				(anchor circle)
			)
			(primitives
				(gr_poly
					(pts
						(arc
							(start -0.3302 0.4318)
							(mid -0.402042 0.402042)
							(end -0.4318 0.3302)
						)
						(arc
							(start -0.4318 -0.3302)
							(mid -0.402042 -0.402042)
							(end -0.3302 -0.4318)
						)
						(arc
							(start 0.3302 -0.4318)
							(mid 0.402042 -0.402042)
							(end 0.4318 -0.3302)
						)
						(arc
							(start 0.4318 0.3302)
							(mid 0.402042 0.402042)
							(end 0.3302 0.4318)
						)
					)
					(width 0)
					(fill yes)
				)
			)
		)
	)
	(footprint ""
		(layer "B.Cu")
		(at 122.4788 -65.4812 -90)
		(property "Reference" "C285"
			(at 0 0 90)
			(layer "B.SilkS")
			(hide yes)
			(effects
				(font
					(size 1.27 1.27)
				)
				(justify mirror)
			)
		)
		(property "Value" "SCD1U6D3V1KX-GP"
			(at 2.8321 -1.7399 270)
			(unlocked yes)
			(layer "B.Fab")
			(hide yes)
			(effects
				(font
					(size 1.016 1.016)
					(thickness 0.1524)
				)
				(justify mirror)
			)
		)
		(property "Device Type" "C0201H13"
			(at 2.8321 -3.2639 270)
			(unlocked yes)
			(layer "B.Fab")
			(hide yes)
			(effects
				(font
					(size 1.016 1.016)
					(thickness 0.1524)
				)
				(justify mirror)
			)
		)
		(duplicate_pad_numbers_are_jumpers no)
		(fp_rect
			(start 0.2794 0.6477)
			(end -0.2794 -0.6477)
			(stroke
				(width 0)
				(type default)
			)
			(fill no)
			(layer "B.CrtYd")
		)
		(fp_rect
			(start 0.2794 0.6477)
			(end -0.2794 -0.6477)
			(stroke
				(width 0)
				(type default)
			)
			(fill no)
			(layer "B.Fab")
		)
		(pad "1" smd custom
			(at 0 -0.2794 90)
			(size 0.0762 0.0762)
			(layers "B.Cu" "B.Mask" "B.Paste")
			(net "GB_VDDA")
			(options
				(clearance outline)
				(anchor circle)
			)
			(primitives
				(gr_poly
					(pts
						(arc
							(start 0.1524 0.127)
							(mid 0.137521 0.162921)
							(end 0.1016 0.1778)
						)
						(arc
							(start -0.1016 0.1778)
							(mid -0.137521 0.162921)
							(end -0.1524 0.127)
						)
						(arc
							(start -0.1524 -0.127)
							(mid -0.137521 -0.162921)
							(end -0.1016 -0.1778)
						)
						(arc
							(start 0.1016 -0.1778)
							(mid 0.137521 -0.162921)
							(end 0.1524 -0.127)
						)
					)
					(width 0)
					(fill yes)
				)
			)
		)
		(pad "2" smd custom
			(at 0 0.2794 90)
			(size 0.0762 0.0762)
			(layers "B.Cu" "B.Mask" "B.Paste")
			(net "GND")
			(options
				(clearance outline)
				(anchor circle)
			)
			(primitives
				(gr_poly
					(pts
						(arc
							(start 0.1524 0.127)
							(mid 0.137521 0.162921)
							(end 0.1016 0.1778)
						)
						(arc
							(start -0.1016 0.1778)
							(mid -0.137521 0.162921)
							(end -0.1524 0.127)
						)
						(arc
							(start -0.1524 -0.127)
							(mid -0.137521 -0.162921)
							(end -0.1016 -0.1778)
						)
						(arc
							(start 0.1016 -0.1778)
							(mid 0.137521 -0.162921)
							(end 0.1524 -0.127)
						)
					)
					(width 0)
					(fill yes)
				)
			)
		)
	)
	(footprint ""
		(layer "B.Cu")
		(at 101.58222 -84.18322 -90)
		(property "Reference" "R566"
			(at 0 0 90)
			(layer "B.SilkS")
			(hide yes)
			(effects
				(font
					(size 1.27 1.27)
				)
				(justify mirror)
			)
		)
		(property "Value" "10KR2F-2-GP"
			(at -0.064008 -3.993896 270)
			(unlocked yes)
			(layer "B.Fab")
			(hide yes)
			(effects
				(font
					(size 1.016 1.016)
					(thickness 0.1524)
				)
				(justify mirror)
			)
		)
		(property "Device Type" "R402H16"
			(at -0.064008 -5.517896 270)
			(unlocked yes)
			(layer "B.Fab")
			(hide yes)
			(effects
				(font
					(size 1.016 1.016)
					(thickness 0.1524)
				)
				(justify mirror)
			)
		)
		(duplicate_pad_numbers_are_jumpers no)
		(fp_line
			(start -0.508 -0.9398)
			(end 0.508 -0.9398)
			(stroke
				(width 0.1524)
				(type default)
			)
			(layer "B.SilkS")
		)
		(fp_line
			(start 0.508 -0.9398)
			(end 0.508 0.9398)
			(stroke
				(width 0.1524)
				(type default)
			)
			(layer "B.SilkS")
		)
		(fp_rect
			(start 0.508 0.9398)
			(end -0.508 -0.9398)
			(stroke
				(width 0)
				(type default)
			)
			(fill no)
			(layer "B.CrtYd")
		)
		(fp_rect
			(start 0.508 0.9398)
			(end -0.508 -0.9398)
			(stroke
				(width 0)
				(type default)
			)
			(fill no)
			(layer "B.Fab")
		)
		(pad "1" smd custom
			(at 0 -0.4445 90)
			(size 0.1397 0.1397)
			(layers "B.Cu" "B.Mask" "B.Paste")
			(net "ENCL_FAULT_LED_LS")
			(options
				(clearance outline)
				(anchor circle)
			)
			(primitives
				(gr_poly
					(pts
						(arc
							(start -0.1778 0.2794)
							(mid -0.249642 0.249642)
							(end -0.2794 0.1778)
						)
						(arc
							(start -0.2794 -0.1778)
							(mid -0.249642 -0.249642)
							(end -0.1778 -0.2794)
						)
						(arc
							(start 0.1778 -0.2794)
							(mid 0.249642 -0.249642)
							(end 0.2794 -0.1778)
						)
						(arc
							(start 0.2794 0.1778)
							(mid 0.249642 0.249642)
							(end 0.1778 0.2794)
						)
					)
					(width 0)
					(fill yes)
				)
			)
		)
		(pad "2" smd custom
			(at 0 0.4445 90)
			(size 0.1397 0.1397)
			(layers "B.Cu" "B.Mask" "B.Paste")
			(net "GND")
			(options
				(clearance outline)
				(anchor circle)
			)
			(primitives
				(gr_poly
					(pts
						(arc
							(start -0.1778 0.2794)
							(mid -0.249642 0.249642)
							(end -0.2794 0.1778)
						)
						(arc
							(start -0.2794 -0.1778)
							(mid -0.249642 -0.249642)
							(end -0.1778 -0.2794)
						)
						(arc
							(start 0.1778 -0.2794)
							(mid 0.249642 -0.249642)
							(end 0.2794 -0.1778)
						)
						(arc
							(start 0.2794 0.1778)
							(mid 0.249642 0.249642)
							(end 0.1778 0.2794)
						)
					)
					(width 0)
					(fill yes)
				)
			)
		)
	)
	(footprint ""
		(layer "B.Cu")
		(at 109.496606 -67.87896 90)
		(property "Reference" "R476"
			(at 0 0 90)
			(layer "B.SilkS")
			(hide yes)
			(effects
				(font
					(size 1.27 1.27)
				)
				(justify mirror)
			)
		)
		(property "Value" "0R2F-1-GP"
			(at -0.064008 -3.993896 90)
			(unlocked yes)
			(layer "B.Fab")
			(hide yes)
			(effects
				(font
					(size 1.016 1.016)
					(thickness 0.1524)
				)
				(justify mirror)
			)
		)
		(property "Device Type" "R402H16"
			(at -0.064008 -5.517896 90)
			(unlocked yes)
			(layer "B.Fab")
			(hide yes)
			(effects
				(font
					(size 1.016 1.016)
					(thickness 0.1524)
				)
				(justify mirror)
			)
		)
		(duplicate_pad_numbers_are_jumpers no)
		(fp_line
			(start 0.508 -0.9398)
			(end 0.508 0.9398)
			(stroke
				(width 0.1524)
				(type default)
			)
			(layer "B.SilkS")
		)
		(fp_line
			(start -0.508 -0.9398)
			(end 0.508 -0.9398)
			(stroke
				(width 0.1524)
				(type default)
			)
			(layer "B.SilkS")
		)
		(fp_rect
			(start 0.508 0.9398)
			(end -0.508 -0.9398)
			(stroke
				(width 0)
				(type default)
			)
			(fill no)
			(layer "B.CrtYd")
		)
		(fp_rect
			(start 0.508 0.9398)
			(end -0.508 -0.9398)
			(stroke
				(width 0)
				(type default)
			)
			(fill no)
			(layer "B.Fab")
		)
		(pad "1" smd custom
			(at 0 -0.4445 270)
			(size 0.1397 0.1397)
			(layers "B.Cu" "B.Mask" "B.Paste")
			(net "P0V9_VFB")
			(options
				(clearance outline)
				(anchor circle)
			)
			(primitives
				(gr_poly
					(pts
						(arc
							(start -0.1778 0.2794)
							(mid -0.249642 0.249642)
							(end -0.2794 0.1778)
						)
						(arc
							(start -0.2794 -0.1778)
							(mid -0.249642 -0.249642)
							(end -0.1778 -0.2794)
						)
						(arc
							(start 0.1778 -0.2794)
							(mid 0.249642 -0.249642)
							(end 0.2794 -0.1778)
						)
						(arc
							(start 0.2794 0.1778)
							(mid 0.249642 0.249642)
							(end 0.1778 0.2794)
						)
					)
					(width 0)
					(fill yes)
				)
			)
		)
		(pad "2" smd custom
			(at 0 0.4445 270)
			(size 0.1397 0.1397)
			(layers "B.Cu" "B.Mask" "B.Paste")
			(net "P0V9")
			(options
				(clearance outline)
				(anchor circle)
			)
			(primitives
				(gr_poly
					(pts
						(arc
							(start -0.1778 0.2794)
							(mid -0.249642 0.249642)
							(end -0.2794 0.1778)
						)
						(arc
							(start -0.2794 -0.1778)
							(mid -0.249642 -0.249642)
							(end -0.1778 -0.2794)
						)
						(arc
							(start 0.1778 -0.2794)
							(mid 0.249642 -0.249642)
							(end 0.2794 -0.1778)
						)
						(arc
							(start 0.2794 0.1778)
							(mid 0.249642 0.249642)
							(end 0.1778 0.2794)
						)
					)
					(width 0)
					(fill yes)
				)
			)
		)
	)
	(footprint ""
		(layer "B.Cu")
		(at 136.1694 -75.5904 -90)
		(property "Reference" "C7"
			(at 0 0 90)
			(layer "B.SilkS")
			(hide yes)
			(effects
				(font
					(size 1.27 1.27)
				)
				(justify mirror)
			)
		)
		(property "Value" "SCD01U16V1KX-GP"
			(at 2.8321 -1.7399 270)
			(unlocked yes)
			(layer "B.Fab")
			(hide yes)
			(effects
				(font
					(size 1.016 1.016)
					(thickness 0.1524)
				)
				(justify mirror)
			)
		)
		(property "Device Type" "C0201H13"
			(at 2.8321 -3.2639 270)
			(unlocked yes)
			(layer "B.Fab")
			(hide yes)
			(effects
				(font
					(size 1.016 1.016)
					(thickness 0.1524)
				)
				(justify mirror)
			)
		)
		(duplicate_pad_numbers_are_jumpers no)
		(fp_rect
			(start 0.2794 0.6477)
			(end -0.2794 -0.6477)
			(stroke
				(width 0)
				(type default)
			)
			(fill no)
			(layer "B.CrtYd")
		)
		(fp_rect
			(start 0.2794 0.6477)
			(end -0.2794 -0.6477)
			(stroke
				(width 0)
				(type default)
			)
			(fill no)
			(layer "B.Fab")
		)
		(pad "1" smd custom
			(at 0 -0.2794 90)
			(size 0.0762 0.0762)
			(layers "B.Cu" "B.Mask" "B.Paste")
			(net "PHY_CONN_TO_EXP_8_DP")
			(options
				(clearance outline)
				(anchor circle)
			)
			(primitives
				(gr_poly
					(pts
						(arc
							(start 0.1524 0.127)
							(mid 0.137521 0.162921)
							(end 0.1016 0.1778)
						)
						(arc
							(start -0.1016 0.1778)
							(mid -0.137521 0.162921)
							(end -0.1524 0.127)
						)
						(arc
							(start -0.1524 -0.127)
							(mid -0.137521 -0.162921)
							(end -0.1016 -0.1778)
						)
						(arc
							(start 0.1016 -0.1778)
							(mid 0.137521 -0.162921)
							(end 0.1524 -0.127)
						)
					)
					(width 0)
					(fill yes)
				)
			)
		)
		(pad "2" smd custom
			(at 0 0.2794 90)
			(size 0.0762 0.0762)
			(layers "B.Cu" "B.Mask" "B.Paste")
			(net "PHY_CONN_TO_EXP_C_8_DP")
			(options
				(clearance outline)
				(anchor circle)
			)
			(primitives
				(gr_poly
					(pts
						(arc
							(start 0.1524 0.127)
							(mid 0.137521 0.162921)
							(end 0.1016 0.1778)
						)
						(arc
							(start -0.1016 0.1778)
							(mid -0.137521 0.162921)
							(end -0.1524 0.127)
						)
						(arc
							(start -0.1524 -0.127)
							(mid -0.137521 -0.162921)
							(end -0.1016 -0.1778)
						)
						(arc
							(start 0.1016 -0.1778)
							(mid 0.137521 -0.162921)
							(end 0.1524 -0.127)
						)
					)
					(width 0)
					(fill yes)
				)
			)
		)
	)
	(footprint ""
		(layer "B.Cu")
		(at 121.568972 -86.650068)
		(property "Reference" "R74"
			(at 0 0 0)
			(layer "B.SilkS")
			(hide yes)
			(effects
				(font
					(size 1.27 1.27)
				)
				(justify mirror)
			)
		)
		(property "Value" "4K7R2F-GP"
			(at -0.064008 -3.993896 0)
			(unlocked yes)
			(layer "B.Fab")
			(hide yes)
			(effects
				(font
					(size 1.016 1.016)
					(thickness 0.1524)
				)
				(justify mirror)
			)
		)
		(property "Device Type" "R402H16"
			(at -0.064008 -5.517896 0)
			(unlocked yes)
			(layer "B.Fab")
			(hide yes)
			(effects
				(font
					(size 1.016 1.016)
					(thickness 0.1524)
				)
				(justify mirror)
			)
		)
		(duplicate_pad_numbers_are_jumpers no)
		(fp_line
			(start -0.508 -0.9398)
			(end 0.508 -0.9398)
			(stroke
				(width 0.1524)
				(type default)
			)
			(layer "B.SilkS")
		)
		(fp_line
			(start 0.508 -0.9398)
			(end 0.508 0.9398)
			(stroke
				(width 0.1524)
				(type default)
			)
			(layer "B.SilkS")
		)
		(fp_rect
			(start 0.508 0.9398)
			(end -0.508 -0.9398)
			(stroke
				(width 0)
				(type default)
			)
			(fill no)
			(layer "B.CrtYd")
		)
		(fp_rect
			(start 0.508 0.9398)
			(end -0.508 -0.9398)
			(stroke
				(width 0)
				(type default)
			)
			(fill no)
			(layer "B.Fab")
		)
		(pad "1" smd custom
			(at 0 -0.4445 180)
			(size 0.1397 0.1397)
			(layers "B.Cu" "B.Mask" "B.Paste")
			(net "P1V8_E")
			(options
				(clearance outline)
				(anchor circle)
			)
			(primitives
				(gr_poly
					(pts
						(arc
							(start -0.1778 0.2794)
							(mid -0.249642 0.249642)
							(end -0.2794 0.1778)
						)
						(arc
							(start -0.2794 -0.1778)
							(mid -0.249642 -0.249642)
							(end -0.1778 -0.2794)
						)
						(arc
							(start 0.1778 -0.2794)
							(mid 0.249642 -0.249642)
							(end 0.2794 -0.1778)
						)
						(arc
							(start 0.2794 0.1778)
							(mid 0.249642 0.249642)
							(end 0.1778 0.2794)
						)
					)
					(width 0)
					(fill yes)
				)
			)
		)
		(pad "2" smd custom
			(at 0 0.4445 180)
			(size 0.1397 0.1397)
			(layers "B.Cu" "B.Mask" "B.Paste")
			(net "SCC_TYPE_2_LS")
			(options
				(clearance outline)
				(anchor circle)
			)
			(primitives
				(gr_poly
					(pts
						(arc
							(start -0.1778 0.2794)
							(mid -0.249642 0.249642)
							(end -0.2794 0.1778)
						)
						(arc
							(start -0.2794 -0.1778)
							(mid -0.249642 -0.249642)
							(end -0.1778 -0.2794)
						)
						(arc
							(start 0.1778 -0.2794)
							(mid 0.249642 -0.249642)
							(end 0.2794 -0.1778)
						)
						(arc
							(start 0.2794 0.1778)
							(mid 0.249642 0.249642)
							(end 0.1778 0.2794)
						)
					)
					(width 0)
					(fill yes)
				)
			)
		)
	)
	(footprint ""
		(layer "B.Cu")
		(at 179.37353 -46.090332 180)
		(property "Reference" "C407"
			(at 0 0 0)
			(layer "B.SilkS")
			(hide yes)
			(effects
				(font
					(size 1.27 1.27)
				)
				(justify mirror)
			)
		)
		(property "Value" "SC10U6D3V5KX-4GP"
			(at 0.0762 -6.1214 180)
			(unlocked yes)
			(layer "B.Fab")
			(hide yes)
			(effects
				(font
					(size 1.016 1.016)
					(thickness 0.1524)
				)
				(justify mirror)
			)
		)
		(property "Device Type" "C805H58"
			(at 0.0762 -8.1534 180)
			(unlocked yes)
			(layer "B.Fab")
			(hide yes)
			(effects
				(font
					(size 1.016 1.016)
					(thickness 0.1524)
				)
				(justify mirror)
			)
		)
		(duplicate_pad_numbers_are_jumpers no)
		(fp_line
			(start -0.635 0)
			(end 0.635 0)
			(stroke
				(width 0.508)
				(type default)
			)
			(layer "B.SilkS")
		)
		(fp_rect
			(start 0.9652 1.778)
			(end -0.9652 -1.778)
			(stroke
				(width 0)
				(type default)
			)
			(fill no)
			(layer "B.CrtYd")
		)
		(fp_poly
			(pts
				(xy 0.9652 -1.778) (xy -0.9652 -1.778) (xy -0.9652 1.778) (xy 0.9652 1.778)
			)
			(stroke
				(width 0)
				(type default)
			)
			(fill no)
			(layer "B.Fab")
		)
		(pad "1" smd rect
			(at 0 -0.9652)
			(size 1.397 1.143)
			(layers "B.Cu" "B.Mask" "B.Paste")
			(net "P0V975")
		)
		(pad "2" smd rect
			(at 0 0.9652)
			(size 1.397 1.143)
			(layers "B.Cu" "B.Mask" "B.Paste")
			(net "GND")
		)
	)
	(footprint ""
		(layer "B.Cu")
		(at 105.791 -44.2214 180)
		(property "Reference" "C76"
			(at 0 0 0)
			(layer "B.SilkS")
			(hide yes)
			(effects
				(font
					(size 1.27 1.27)
				)
				(justify mirror)
			)
		)
		(property "Value" "SCD01U16V1KX-GP"
			(at 2.8321 -1.7399 180)
			(unlocked yes)
			(layer "B.Fab")
			(hide yes)
			(effects
				(font
					(size 1.016 1.016)
					(thickness 0.1524)
				)
				(justify mirror)
			)
		)
		(property "Device Type" "C0201H13"
			(at 2.8321 -3.2639 180)
			(unlocked yes)
			(layer "B.Fab")
			(hide yes)
			(effects
				(font
					(size 1.016 1.016)
					(thickness 0.1524)
				)
				(justify mirror)
			)
		)
		(duplicate_pad_numbers_are_jumpers no)
		(fp_rect
			(start 0.2794 0.6477)
			(end -0.2794 -0.6477)
			(stroke
				(width 0)
				(type default)
			)
			(fill no)
			(layer "B.CrtYd")
		)
		(fp_rect
			(start 0.2794 0.6477)
			(end -0.2794 -0.6477)
			(stroke
				(width 0)
				(type default)
			)
			(fill no)
			(layer "B.Fab")
		)
		(pad "1" smd custom
			(at 0 -0.2794)
			(size 0.0762 0.0762)
			(layers "B.Cu" "B.Mask" "B.Paste")
			(net "PHY_DPB_TO_SCC_22_DN")
			(options
				(clearance outline)
				(anchor circle)
			)
			(primitives
				(gr_poly
					(pts
						(arc
							(start 0.1524 0.127)
							(mid 0.137521 0.162921)
							(end 0.1016 0.1778)
						)
						(arc
							(start -0.1016 0.1778)
							(mid -0.137521 0.162921)
							(end -0.1524 0.127)
						)
						(arc
							(start -0.1524 -0.127)
							(mid -0.137521 -0.162921)
							(end -0.1016 -0.1778)
						)
						(arc
							(start 0.1016 -0.1778)
							(mid 0.137521 -0.162921)
							(end 0.1524 -0.127)
						)
					)
					(width 0)
					(fill yes)
				)
			)
		)
		(pad "2" smd custom
			(at 0 0.2794)
			(size 0.0762 0.0762)
			(layers "B.Cu" "B.Mask" "B.Paste")
			(net "PHY_DPB_TO_SCC_C_22_DN")
			(options
				(clearance outline)
				(anchor circle)
			)
			(primitives
				(gr_poly
					(pts
						(arc
							(start 0.1524 0.127)
							(mid 0.137521 0.162921)
							(end 0.1016 0.1778)
						)
						(arc
							(start -0.1016 0.1778)
							(mid -0.137521 0.162921)
							(end -0.1524 0.127)
						)
						(arc
							(start -0.1524 -0.127)
							(mid -0.137521 -0.162921)
							(end -0.1016 -0.1778)
						)
						(arc
							(start 0.1016 -0.1778)
							(mid 0.137521 -0.162921)
							(end 0.1524 -0.127)
						)
					)
					(width 0)
					(fill yes)
				)
			)
		)
	)
	(footprint ""
		(layer "B.Cu")
		(at 123.2535 -57.4802)
		(property "Reference" "C260"
			(at 0 0 0)
			(layer "B.SilkS")
			(hide yes)
			(effects
				(font
					(size 1.27 1.27)
				)
				(justify mirror)
			)
		)
		(property "Value" "SCD1U6D3V1KX-GP"
			(at 2.8321 -1.7399 0)
			(unlocked yes)
			(layer "B.Fab")
			(hide yes)
			(effects
				(font
					(size 1.016 1.016)
					(thickness 0.1524)
				)
				(justify mirror)
			)
		)
		(property "Device Type" "C0201H13"
			(at 2.8321 -3.2639 0)
			(unlocked yes)
			(layer "B.Fab")
			(hide yes)
			(effects
				(font
					(size 1.016 1.016)
					(thickness 0.1524)
				)
				(justify mirror)
			)
		)
		(duplicate_pad_numbers_are_jumpers no)
		(fp_rect
			(start 0.2794 0.6477)
			(end -0.2794 -0.6477)
			(stroke
				(width 0)
				(type default)
			)
			(fill no)
			(layer "B.CrtYd")
		)
		(fp_rect
			(start 0.2794 0.6477)
			(end -0.2794 -0.6477)
			(stroke
				(width 0)
				(type default)
			)
			(fill no)
			(layer "B.Fab")
		)
		(pad "1" smd custom
			(at 0 -0.2794 180)
			(size 0.0762 0.0762)
			(layers "B.Cu" "B.Mask" "B.Paste")
			(net "GB_VDDA")
			(options
				(clearance outline)
				(anchor circle)
			)
			(primitives
				(gr_poly
					(pts
						(arc
							(start 0.1524 0.127)
							(mid 0.137521 0.162921)
							(end 0.1016 0.1778)
						)
						(arc
							(start -0.1016 0.1778)
							(mid -0.137521 0.162921)
							(end -0.1524 0.127)
						)
						(arc
							(start -0.1524 -0.127)
							(mid -0.137521 -0.162921)
							(end -0.1016 -0.1778)
						)
						(arc
							(start 0.1016 -0.1778)
							(mid 0.137521 -0.162921)
							(end 0.1524 -0.127)
						)
					)
					(width 0)
					(fill yes)
				)
			)
		)
		(pad "2" smd custom
			(at 0 0.2794 180)
			(size 0.0762 0.0762)
			(layers "B.Cu" "B.Mask" "B.Paste")
			(net "GND")
			(options
				(clearance outline)
				(anchor circle)
			)
			(primitives
				(gr_poly
					(pts
						(arc
							(start 0.1524 0.127)
							(mid 0.137521 0.162921)
							(end 0.1016 0.1778)
						)
						(arc
							(start -0.1016 0.1778)
							(mid -0.137521 0.162921)
							(end -0.1524 0.127)
						)
						(arc
							(start -0.1524 -0.127)
							(mid -0.137521 -0.162921)
							(end -0.1016 -0.1778)
						)
						(arc
							(start 0.1016 -0.1778)
							(mid 0.137521 -0.162921)
							(end 0.1524 -0.127)
						)
					)
					(width 0)
					(fill yes)
				)
			)
		)
	)
	(footprint ""
		(layer "B.Cu")
		(at 110.278418 -69.431662 -90)
		(property "Reference" "C190"
			(at 0 0 90)
			(layer "B.SilkS")
			(hide yes)
			(effects
				(font
					(size 1.27 1.27)
				)
				(justify mirror)
			)
		)
		(property "Value" "SC1KP25V1KX-GP"
			(at 2.8321 -1.7399 270)
			(unlocked yes)
			(layer "B.Fab")
			(hide yes)
			(effects
				(font
					(size 1.016 1.016)
					(thickness 0.1524)
				)
				(justify mirror)
			)
		)
		(property "Device Type" "C0201H13"
			(at 2.8321 -3.2639 270)
			(unlocked yes)
			(layer "B.Fab")
			(hide yes)
			(effects
				(font
					(size 1.016 1.016)
					(thickness 0.1524)
				)
				(justify mirror)
			)
		)
		(duplicate_pad_numbers_are_jumpers no)
		(fp_rect
			(start 0.2794 0.6477)
			(end -0.2794 -0.6477)
			(stroke
				(width 0)
				(type default)
			)
			(fill no)
			(layer "B.CrtYd")
		)
		(fp_rect
			(start 0.2794 0.6477)
			(end -0.2794 -0.6477)
			(stroke
				(width 0)
				(type default)
			)
			(fill no)
			(layer "B.Fab")
		)
		(pad "1" smd custom
			(at 0 -0.2794 90)
			(size 0.0762 0.0762)
			(layers "B.Cu" "B.Mask" "B.Paste")
			(net "P0V9")
			(options
				(clearance outline)
				(anchor circle)
			)
			(primitives
				(gr_poly
					(pts
						(arc
							(start 0.1524 0.127)
							(mid 0.137521 0.162921)
							(end 0.1016 0.1778)
						)
						(arc
							(start -0.1016 0.1778)
							(mid -0.137521 0.162921)
							(end -0.1524 0.127)
						)
						(arc
							(start -0.1524 -0.127)
							(mid -0.137521 -0.162921)
							(end -0.1016 -0.1778)
						)
						(arc
							(start 0.1016 -0.1778)
							(mid 0.137521 -0.162921)
							(end 0.1524 -0.127)
						)
					)
					(width 0)
					(fill yes)
				)
			)
		)
		(pad "2" smd custom
			(at 0 0.2794 90)
			(size 0.0762 0.0762)
			(layers "B.Cu" "B.Mask" "B.Paste")
			(net "GND")
			(options
				(clearance outline)
				(anchor circle)
			)
			(primitives
				(gr_poly
					(pts
						(arc
							(start 0.1524 0.127)
							(mid 0.137521 0.162921)
							(end 0.1016 0.1778)
						)
						(arc
							(start -0.1016 0.1778)
							(mid -0.137521 0.162921)
							(end -0.1524 0.127)
						)
						(arc
							(start -0.1524 -0.127)
							(mid -0.137521 -0.162921)
							(end -0.1016 -0.1778)
						)
						(arc
							(start 0.1016 -0.1778)
							(mid 0.137521 -0.162921)
							(end 0.1524 -0.127)
						)
					)
					(width 0)
					(fill yes)
				)
			)
		)
	)
	(footprint ""
		(layer "B.Cu")
		(at 89.462356 -78.171548)
		(property "Reference" "L5"
			(at 0 0 0)
			(layer "B.SilkS")
			(hide yes)
			(effects
				(font
					(size 1.27 1.27)
				)
				(justify mirror)
			)
		)
		(property "Value" "MPZ2012S601AT-GP"
			(at 0 -4.2418 0)
			(unlocked yes)
			(layer "B.Fab")
			(hide yes)
			(effects
				(font
					(size 1.016 1.016)
					(thickness 0.1524)
				)
				(justify mirror)
			)
		)
		(property "Device Type" "L805H42"
			(at 0 -5.7912 0)
			(unlocked yes)
			(layer "B.Fab")
			(hide yes)
			(effects
				(font
					(size 1.016 1.016)
					(thickness 0.1524)
				)
				(justify mirror)
			)
		)
		(duplicate_pad_numbers_are_jumpers no)
		(fp_line
			(start -0.889 -1.7018)
			(end -0.889 1.7018)
			(stroke
				(width 0.1524)
				(type default)
			)
			(layer "B.SilkS")
		)
		(fp_line
			(start -0.889 1.7018)
			(end 0.889 1.7018)
			(stroke
				(width 0.1524)
				(type default)
			)
			(layer "B.SilkS")
		)
		(fp_line
			(start 0.889 -1.7018)
			(end -0.889 -1.7018)
			(stroke
				(width 0.1524)
				(type default)
			)
			(layer "B.SilkS")
		)
		(fp_line
			(start 0.889 1.7018)
			(end 0.889 -1.7018)
			(stroke
				(width 0.1524)
				(type default)
			)
			(layer "B.SilkS")
		)
		(fp_rect
			(start 0.9652 1.778)
			(end -0.9652 -1.778)
			(stroke
				(width 0)
				(type default)
			)
			(fill no)
			(layer "B.CrtYd")
		)
		(fp_rect
			(start 0.9652 1.778)
			(end -0.9652 -1.778)
			(stroke
				(width 0)
				(type default)
			)
			(fill no)
			(layer "B.Fab")
		)
		(pad "1" smd rect
			(at 0 -0.9652 180)
			(size 1.397 1.143)
			(layers "B.Cu" "B.Mask" "B.Paste")
			(net "SYSPLL_VDDA09")
		)
		(pad "2" smd rect
			(at 0 0.9652 180)
			(size 1.397 1.143)
			(layers "B.Cu" "B.Mask" "B.Paste")
			(net "P0V9")
		)
	)
	(footprint ""
		(layer "B.Cu")
		(at 181.229 -34.7853)
		(property "Reference" "R251"
			(at 0 0 0)
			(layer "B.SilkS")
			(hide yes)
			(effects
				(font
					(size 1.27 1.27)
				)
				(justify mirror)
			)
		)
		(property "Value" "10KR2F-2-GP"
			(at -0.064008 -3.993896 0)
			(unlocked yes)
			(layer "B.Fab")
			(hide yes)
			(effects
				(font
					(size 1.016 1.016)
					(thickness 0.1524)
				)
				(justify mirror)
			)
		)
		(property "Device Type" "R402H16"
			(at -0.064008 -5.517896 0)
			(unlocked yes)
			(layer "B.Fab")
			(hide yes)
			(effects
				(font
					(size 1.016 1.016)
					(thickness 0.1524)
				)
				(justify mirror)
			)
		)
		(duplicate_pad_numbers_are_jumpers no)
		(fp_line
			(start -0.508 -0.9398)
			(end 0.508 -0.9398)
			(stroke
				(width 0.1524)
				(type default)
			)
			(layer "B.SilkS")
		)
		(fp_line
			(start 0.508 -0.9398)
			(end 0.508 0.9398)
			(stroke
				(width 0.1524)
				(type default)
			)
			(layer "B.SilkS")
		)
		(fp_rect
			(start 0.508 0.9398)
			(end -0.508 -0.9398)
			(stroke
				(width 0)
				(type default)
			)
			(fill no)
			(layer "B.CrtYd")
		)
		(fp_rect
			(start 0.508 0.9398)
			(end -0.508 -0.9398)
			(stroke
				(width 0)
				(type default)
			)
			(fill no)
			(layer "B.Fab")
		)
		(pad "1" smd custom
			(at 0 -0.4445 180)
			(size 0.1397 0.1397)
			(layers "B.Cu" "B.Mask" "B.Paste")
			(net "P1V8_C")
			(options
				(clearance outline)
				(anchor circle)
			)
			(primitives
				(gr_poly
					(pts
						(arc
							(start -0.1778 0.2794)
							(mid -0.249642 0.249642)
							(end -0.2794 0.1778)
						)
						(arc
							(start -0.2794 -0.1778)
							(mid -0.249642 -0.249642)
							(end -0.1778 -0.2794)
						)
						(arc
							(start 0.1778 -0.2794)
							(mid 0.249642 -0.249642)
							(end 0.2794 -0.1778)
						)
						(arc
							(start 0.2794 0.1778)
							(mid 0.249642 0.249642)
							(end 0.1778 0.2794)
						)
					)
					(width 0)
					(fill yes)
				)
			)
		)
		(pad "2" smd custom
			(at 0 0.4445 180)
			(size 0.1397 0.1397)
			(layers "B.Cu" "B.Mask" "B.Paste")
			(net "SYS_DBMODE0")
			(options
				(clearance outline)
				(anchor circle)
			)
			(primitives
				(gr_poly
					(pts
						(arc
							(start -0.1778 0.2794)
							(mid -0.249642 0.249642)
							(end -0.2794 0.1778)
						)
						(arc
							(start -0.2794 -0.1778)
							(mid -0.249642 -0.249642)
							(end -0.1778 -0.2794)
						)
						(arc
							(start 0.1778 -0.2794)
							(mid 0.249642 -0.249642)
							(end 0.2794 -0.1778)
						)
						(arc
							(start 0.2794 0.1778)
							(mid 0.249642 0.249642)
							(end 0.1778 0.2794)
						)
					)
					(width 0)
					(fill yes)
				)
			)
		)
	)
	(footprint ""
		(layer "B.Cu")
		(at 183.668416 -89.671652 90)
		(property "Reference" "C628"
			(at 0 0 90)
			(layer "B.SilkS")
			(hide yes)
			(effects
				(font
					(size 1.27 1.27)
				)
				(justify mirror)
			)
		)
		(property "Value" "SC10U6D3V5KX-4GP"
			(at 0.0762 -6.1214 90)
			(unlocked yes)
			(layer "B.Fab")
			(hide yes)
			(effects
				(font
					(size 1.016 1.016)
					(thickness 0.1524)
				)
				(justify mirror)
			)
		)
		(property "Device Type" "C805H58"
			(at 0.0762 -8.1534 90)
			(unlocked yes)
			(layer "B.Fab")
			(hide yes)
			(effects
				(font
					(size 1.016 1.016)
					(thickness 0.1524)
				)
				(justify mirror)
			)
		)
		(duplicate_pad_numbers_are_jumpers no)
		(fp_line
			(start -0.635 0)
			(end 0.635 0)
			(stroke
				(width 0.508)
				(type default)
			)
			(layer "B.SilkS")
		)
		(fp_rect
			(start 0.9652 1.778)
			(end -0.9652 -1.778)
			(stroke
				(width 0)
				(type default)
			)
			(fill no)
			(layer "B.CrtYd")
		)
		(fp_poly
			(pts
				(xy 0.9652 -1.778) (xy -0.9652 -1.778) (xy -0.9652 1.778) (xy 0.9652 1.778)
			)
			(stroke
				(width 0)
				(type default)
			)
			(fill no)
			(layer "B.Fab")
		)
		(pad "1" smd rect
			(at 0 -0.9652 270)
			(size 1.397 1.143)
			(layers "B.Cu" "B.Mask" "B.Paste")
			(net "P0V975")
		)
		(pad "2" smd rect
			(at 0 0.9652 270)
			(size 1.397 1.143)
			(layers "B.Cu" "B.Mask" "B.Paste")
			(net "GND")
		)
	)
	(footprint ""
		(layer "B.Cu")
		(at 177.811176 -40.269922 90)
		(property "Reference" "C435"
			(at 0 0 90)
			(layer "B.SilkS")
			(hide yes)
			(effects
				(font
					(size 1.27 1.27)
				)
				(justify mirror)
			)
		)
		(property "Value" "SCD1U6D3V1KX-GP"
			(at 2.8321 -1.7399 90)
			(unlocked yes)
			(layer "B.Fab")
			(hide yes)
			(effects
				(font
					(size 1.016 1.016)
					(thickness 0.1524)
				)
				(justify mirror)
			)
		)
		(property "Device Type" "C0201H13"
			(at 2.8321 -3.2639 90)
			(unlocked yes)
			(layer "B.Fab")
			(hide yes)
			(effects
				(font
					(size 1.016 1.016)
					(thickness 0.1524)
				)
				(justify mirror)
			)
		)
		(duplicate_pad_numbers_are_jumpers no)
		(fp_rect
			(start 0.2794 0.6477)
			(end -0.2794 -0.6477)
			(stroke
				(width 0)
				(type default)
			)
			(fill no)
			(layer "B.CrtYd")
		)
		(fp_rect
			(start 0.2794 0.6477)
			(end -0.2794 -0.6477)
			(stroke
				(width 0)
				(type default)
			)
			(fill no)
			(layer "B.Fab")
		)
		(pad "1" smd custom
			(at 0 -0.2794 270)
			(size 0.0762 0.0762)
			(layers "B.Cu" "B.Mask" "B.Paste")
			(net "P0V975")
			(options
				(clearance outline)
				(anchor circle)
			)
			(primitives
				(gr_poly
					(pts
						(arc
							(start 0.1524 0.127)
							(mid 0.137521 0.162921)
							(end 0.1016 0.1778)
						)
						(arc
							(start -0.1016 0.1778)
							(mid -0.137521 0.162921)
							(end -0.1524 0.127)
						)
						(arc
							(start -0.1524 -0.127)
							(mid -0.137521 -0.162921)
							(end -0.1016 -0.1778)
						)
						(arc
							(start 0.1016 -0.1778)
							(mid 0.137521 -0.162921)
							(end 0.1524 -0.127)
						)
					)
					(width 0)
					(fill yes)
				)
			)
		)
		(pad "2" smd custom
			(at 0 0.2794 270)
			(size 0.0762 0.0762)
			(layers "B.Cu" "B.Mask" "B.Paste")
			(net "GND")
			(options
				(clearance outline)
				(anchor circle)
			)
			(primitives
				(gr_poly
					(pts
						(arc
							(start 0.1524 0.127)
							(mid 0.137521 0.162921)
							(end 0.1016 0.1778)
						)
						(arc
							(start -0.1016 0.1778)
							(mid -0.137521 0.162921)
							(end -0.1524 0.127)
						)
						(arc
							(start -0.1524 -0.127)
							(mid -0.137521 -0.162921)
							(end -0.1016 -0.1778)
						)
						(arc
							(start 0.1016 -0.1778)
							(mid 0.137521 -0.162921)
							(end 0.1524 -0.127)
						)
					)
					(width 0)
					(fill yes)
				)
			)
		)
	)
	(footprint ""
		(layer "B.Cu")
		(at 117.2591 -57.4802)
		(property "Reference" "C585"
			(at 0 0 0)
			(layer "B.SilkS")
			(hide yes)
			(effects
				(font
					(size 1.27 1.27)
				)
				(justify mirror)
			)
		)
		(property "Value" "SCD1U6D3V1KX-GP"
			(at 2.8321 -1.7399 0)
			(unlocked yes)
			(layer "B.Fab")
			(hide yes)
			(effects
				(font
					(size 1.016 1.016)
					(thickness 0.1524)
				)
				(justify mirror)
			)
		)
		(property "Device Type" "C0201H13"
			(at 2.8321 -3.2639 0)
			(unlocked yes)
			(layer "B.Fab")
			(hide yes)
			(effects
				(font
					(size 1.016 1.016)
					(thickness 0.1524)
				)
				(justify mirror)
			)
		)
		(duplicate_pad_numbers_are_jumpers no)
		(fp_rect
			(start 0.2794 0.6477)
			(end -0.2794 -0.6477)
			(stroke
				(width 0)
				(type default)
			)
			(fill no)
			(layer "B.CrtYd")
		)
		(fp_rect
			(start 0.2794 0.6477)
			(end -0.2794 -0.6477)
			(stroke
				(width 0)
				(type default)
			)
			(fill no)
			(layer "B.Fab")
		)
		(pad "1" smd custom
			(at 0 -0.2794 180)
			(size 0.0762 0.0762)
			(layers "B.Cu" "B.Mask" "B.Paste")
			(net "GB_VDDA")
			(options
				(clearance outline)
				(anchor circle)
			)
			(primitives
				(gr_poly
					(pts
						(arc
							(start 0.1524 0.127)
							(mid 0.137521 0.162921)
							(end 0.1016 0.1778)
						)
						(arc
							(start -0.1016 0.1778)
							(mid -0.137521 0.162921)
							(end -0.1524 0.127)
						)
						(arc
							(start -0.1524 -0.127)
							(mid -0.137521 -0.162921)
							(end -0.1016 -0.1778)
						)
						(arc
							(start 0.1016 -0.1778)
							(mid 0.137521 -0.162921)
							(end 0.1524 -0.127)
						)
					)
					(width 0)
					(fill yes)
				)
			)
		)
		(pad "2" smd custom
			(at 0 0.2794 180)
			(size 0.0762 0.0762)
			(layers "B.Cu" "B.Mask" "B.Paste")
			(net "GND")
			(options
				(clearance outline)
				(anchor circle)
			)
			(primitives
				(gr_poly
					(pts
						(arc
							(start 0.1524 0.127)
							(mid 0.137521 0.162921)
							(end 0.1016 0.1778)
						)
						(arc
							(start -0.1016 0.1778)
							(mid -0.137521 0.162921)
							(end -0.1524 0.127)
						)
						(arc
							(start -0.1524 -0.127)
							(mid -0.137521 -0.162921)
							(end -0.1016 -0.1778)
						)
						(arc
							(start 0.1016 -0.1778)
							(mid 0.137521 -0.162921)
							(end 0.1524 -0.127)
						)
					)
					(width 0)
					(fill yes)
				)
			)
		)
	)
	(footprint ""
		(layer "B.Cu")
		(at 114.7191 -57.4802)
		(property "Reference" "C254"
			(at 0 0 0)
			(layer "B.SilkS")
			(hide yes)
			(effects
				(font
					(size 1.27 1.27)
				)
				(justify mirror)
			)
		)
		(property "Value" "SCD1U6D3V1KX-GP"
			(at 2.8321 -1.7399 0)
			(unlocked yes)
			(layer "B.Fab")
			(hide yes)
			(effects
				(font
					(size 1.016 1.016)
					(thickness 0.1524)
				)
				(justify mirror)
			)
		)
		(property "Device Type" "C0201H13"
			(at 2.8321 -3.2639 0)
			(unlocked yes)
			(layer "B.Fab")
			(hide yes)
			(effects
				(font
					(size 1.016 1.016)
					(thickness 0.1524)
				)
				(justify mirror)
			)
		)
		(duplicate_pad_numbers_are_jumpers no)
		(fp_rect
			(start 0.2794 0.6477)
			(end -0.2794 -0.6477)
			(stroke
				(width 0)
				(type default)
			)
			(fill no)
			(layer "B.CrtYd")
		)
		(fp_rect
			(start 0.2794 0.6477)
			(end -0.2794 -0.6477)
			(stroke
				(width 0)
				(type default)
			)
			(fill no)
			(layer "B.Fab")
		)
		(pad "1" smd custom
			(at 0 -0.2794 180)
			(size 0.0762 0.0762)
			(layers "B.Cu" "B.Mask" "B.Paste")
			(net "GB_VDDA")
			(options
				(clearance outline)
				(anchor circle)
			)
			(primitives
				(gr_poly
					(pts
						(arc
							(start 0.1524 0.127)
							(mid 0.137521 0.162921)
							(end 0.1016 0.1778)
						)
						(arc
							(start -0.1016 0.1778)
							(mid -0.137521 0.162921)
							(end -0.1524 0.127)
						)
						(arc
							(start -0.1524 -0.127)
							(mid -0.137521 -0.162921)
							(end -0.1016 -0.1778)
						)
						(arc
							(start 0.1016 -0.1778)
							(mid 0.137521 -0.162921)
							(end 0.1524 -0.127)
						)
					)
					(width 0)
					(fill yes)
				)
			)
		)
		(pad "2" smd custom
			(at 0 0.2794 180)
			(size 0.0762 0.0762)
			(layers "B.Cu" "B.Mask" "B.Paste")
			(net "GND")
			(options
				(clearance outline)
				(anchor circle)
			)
			(primitives
				(gr_poly
					(pts
						(arc
							(start 0.1524 0.127)
							(mid 0.137521 0.162921)
							(end 0.1016 0.1778)
						)
						(arc
							(start -0.1016 0.1778)
							(mid -0.137521 0.162921)
							(end -0.1524 0.127)
						)
						(arc
							(start -0.1524 -0.127)
							(mid -0.137521 -0.162921)
							(end -0.1016 -0.1778)
						)
						(arc
							(start 0.1016 -0.1778)
							(mid 0.137521 -0.162921)
							(end 0.1524 -0.127)
						)
					)
					(width 0)
					(fill yes)
				)
			)
		)
	)
	(footprint ""
		(layer "B.Cu")
		(at 184.465468 -43.19651 90)
		(property "Reference" "C458"
			(at 0 0 90)
			(layer "B.SilkS")
			(hide yes)
			(effects
				(font
					(size 1.27 1.27)
				)
				(justify mirror)
			)
		)
		(property "Value" "SCD1U6D3V1KX-GP"
			(at 2.8321 -1.7399 90)
			(unlocked yes)
			(layer "B.Fab")
			(hide yes)
			(effects
				(font
					(size 1.016 1.016)
					(thickness 0.1524)
				)
				(justify mirror)
			)
		)
		(property "Device Type" "C0201H13"
			(at 2.8321 -3.2639 90)
			(unlocked yes)
			(layer "B.Fab")
			(hide yes)
			(effects
				(font
					(size 1.016 1.016)
					(thickness 0.1524)
				)
				(justify mirror)
			)
		)
		(duplicate_pad_numbers_are_jumpers no)
		(fp_rect
			(start 0.2794 0.6477)
			(end -0.2794 -0.6477)
			(stroke
				(width 0)
				(type default)
			)
			(fill no)
			(layer "B.CrtYd")
		)
		(fp_rect
			(start 0.2794 0.6477)
			(end -0.2794 -0.6477)
			(stroke
				(width 0)
				(type default)
			)
			(fill no)
			(layer "B.Fab")
		)
		(pad "1" smd custom
			(at 0 -0.2794 270)
			(size 0.0762 0.0762)
			(layers "B.Cu" "B.Mask" "B.Paste")
			(net "P1V8_C")
			(options
				(clearance outline)
				(anchor circle)
			)
			(primitives
				(gr_poly
					(pts
						(arc
							(start 0.1524 0.127)
							(mid 0.137521 0.162921)
							(end 0.1016 0.1778)
						)
						(arc
							(start -0.1016 0.1778)
							(mid -0.137521 0.162921)
							(end -0.1524 0.127)
						)
						(arc
							(start -0.1524 -0.127)
							(mid -0.137521 -0.162921)
							(end -0.1016 -0.1778)
						)
						(arc
							(start 0.1016 -0.1778)
							(mid 0.137521 -0.162921)
							(end 0.1524 -0.127)
						)
					)
					(width 0)
					(fill yes)
				)
			)
		)
		(pad "2" smd custom
			(at 0 0.2794 270)
			(size 0.0762 0.0762)
			(layers "B.Cu" "B.Mask" "B.Paste")
			(net "GND")
			(options
				(clearance outline)
				(anchor circle)
			)
			(primitives
				(gr_poly
					(pts
						(arc
							(start 0.1524 0.127)
							(mid 0.137521 0.162921)
							(end 0.1016 0.1778)
						)
						(arc
							(start -0.1016 0.1778)
							(mid -0.137521 0.162921)
							(end -0.1524 0.127)
						)
						(arc
							(start -0.1524 -0.127)
							(mid -0.137521 -0.162921)
							(end -0.1016 -0.1778)
						)
						(arc
							(start 0.1016 -0.1778)
							(mid 0.137521 -0.162921)
							(end 0.1524 -0.127)
						)
					)
					(width 0)
					(fill yes)
				)
			)
		)
	)
	(footprint ""
		(layer "B.Cu")
		(at 124.2822 -64.4906 -90)
		(property "Reference" "C304"
			(at 0 0 90)
			(layer "B.SilkS")
			(hide yes)
			(effects
				(font
					(size 1.27 1.27)
				)
				(justify mirror)
			)
		)
		(property "Value" "SCD1U6D3V1KX-GP"
			(at 2.8321 -1.7399 270)
			(unlocked yes)
			(layer "B.Fab")
			(hide yes)
			(effects
				(font
					(size 1.016 1.016)
					(thickness 0.1524)
				)
				(justify mirror)
			)
		)
		(property "Device Type" "C0201H13"
			(at 2.8321 -3.2639 270)
			(unlocked yes)
			(layer "B.Fab")
			(hide yes)
			(effects
				(font
					(size 1.016 1.016)
					(thickness 0.1524)
				)
				(justify mirror)
			)
		)
		(duplicate_pad_numbers_are_jumpers no)
		(fp_rect
			(start 0.2794 0.6477)
			(end -0.2794 -0.6477)
			(stroke
				(width 0)
				(type default)
			)
			(fill no)
			(layer "B.CrtYd")
		)
		(fp_rect
			(start 0.2794 0.6477)
			(end -0.2794 -0.6477)
			(stroke
				(width 0)
				(type default)
			)
			(fill no)
			(layer "B.Fab")
		)
		(pad "1" smd custom
			(at 0 -0.2794 90)
			(size 0.0762 0.0762)
			(layers "B.Cu" "B.Mask" "B.Paste")
			(net "GB_VDDA")
			(options
				(clearance outline)
				(anchor circle)
			)
			(primitives
				(gr_poly
					(pts
						(arc
							(start 0.1524 0.127)
							(mid 0.137521 0.162921)
							(end 0.1016 0.1778)
						)
						(arc
							(start -0.1016 0.1778)
							(mid -0.137521 0.162921)
							(end -0.1524 0.127)
						)
						(arc
							(start -0.1524 -0.127)
							(mid -0.137521 -0.162921)
							(end -0.1016 -0.1778)
						)
						(arc
							(start 0.1016 -0.1778)
							(mid 0.137521 -0.162921)
							(end 0.1524 -0.127)
						)
					)
					(width 0)
					(fill yes)
				)
			)
		)
		(pad "2" smd custom
			(at 0 0.2794 90)
			(size 0.0762 0.0762)
			(layers "B.Cu" "B.Mask" "B.Paste")
			(net "GND")
			(options
				(clearance outline)
				(anchor circle)
			)
			(primitives
				(gr_poly
					(pts
						(arc
							(start 0.1524 0.127)
							(mid 0.137521 0.162921)
							(end 0.1016 0.1778)
						)
						(arc
							(start -0.1016 0.1778)
							(mid -0.137521 0.162921)
							(end -0.1524 0.127)
						)
						(arc
							(start -0.1524 -0.127)
							(mid -0.137521 -0.162921)
							(end -0.1016 -0.1778)
						)
						(arc
							(start 0.1016 -0.1778)
							(mid 0.137521 -0.162921)
							(end 0.1524 -0.127)
						)
					)
					(width 0)
					(fill yes)
				)
			)
		)
	)
	(footprint ""
		(layer "B.Cu")
		(at 114.76736 -59.4487)
		(property "Reference" "C237"
			(at 0 0 0)
			(layer "B.SilkS")
			(hide yes)
			(effects
				(font
					(size 1.27 1.27)
				)
				(justify mirror)
			)
		)
		(property "Value" "SCD1U6D3V1KX-GP"
			(at 2.8321 -1.7399 0)
			(unlocked yes)
			(layer "B.Fab")
			(hide yes)
			(effects
				(font
					(size 1.016 1.016)
					(thickness 0.1524)
				)
				(justify mirror)
			)
		)
		(property "Device Type" "C0201H13"
			(at 2.8321 -3.2639 0)
			(unlocked yes)
			(layer "B.Fab")
			(hide yes)
			(effects
				(font
					(size 1.016 1.016)
					(thickness 0.1524)
				)
				(justify mirror)
			)
		)
		(duplicate_pad_numbers_are_jumpers no)
		(fp_rect
			(start 0.2794 0.6477)
			(end -0.2794 -0.6477)
			(stroke
				(width 0)
				(type default)
			)
			(fill no)
			(layer "B.CrtYd")
		)
		(fp_rect
			(start 0.2794 0.6477)
			(end -0.2794 -0.6477)
			(stroke
				(width 0)
				(type default)
			)
			(fill no)
			(layer "B.Fab")
		)
		(pad "1" smd custom
			(at 0 -0.2794 180)
			(size 0.0762 0.0762)
			(layers "B.Cu" "B.Mask" "B.Paste")
			(net "GB_VDDA")
			(options
				(clearance outline)
				(anchor circle)
			)
			(primitives
				(gr_poly
					(pts
						(arc
							(start 0.1524 0.127)
							(mid 0.137521 0.162921)
							(end 0.1016 0.1778)
						)
						(arc
							(start -0.1016 0.1778)
							(mid -0.137521 0.162921)
							(end -0.1524 0.127)
						)
						(arc
							(start -0.1524 -0.127)
							(mid -0.137521 -0.162921)
							(end -0.1016 -0.1778)
						)
						(arc
							(start 0.1016 -0.1778)
							(mid 0.137521 -0.162921)
							(end 0.1524 -0.127)
						)
					)
					(width 0)
					(fill yes)
				)
			)
		)
		(pad "2" smd custom
			(at 0 0.2794 180)
			(size 0.0762 0.0762)
			(layers "B.Cu" "B.Mask" "B.Paste")
			(net "GND")
			(options
				(clearance outline)
				(anchor circle)
			)
			(primitives
				(gr_poly
					(pts
						(arc
							(start 0.1524 0.127)
							(mid 0.137521 0.162921)
							(end 0.1016 0.1778)
						)
						(arc
							(start -0.1016 0.1778)
							(mid -0.137521 0.162921)
							(end -0.1524 0.127)
						)
						(arc
							(start -0.1524 -0.127)
							(mid -0.137521 -0.162921)
							(end -0.1016 -0.1778)
						)
						(arc
							(start 0.1016 -0.1778)
							(mid 0.137521 -0.162921)
							(end 0.1524 -0.127)
						)
					)
					(width 0)
					(fill yes)
				)
			)
		)
	)
	(footprint ""
		(layer "B.Cu")
		(at 182.626 -28.6258 90)
		(property "Reference" "TP57"
			(at 0 0 90)
			(layer "B.SilkS")
			(hide yes)
			(effects
				(font
					(size 1.27 1.27)
				)
				(justify mirror)
			)
		)
		(property "Value" "TPAD28-2-GP"
			(at 0.0127 -1.6637 90)
			(unlocked yes)
			(layer "B.Fab")
			(hide yes)
			(effects
				(font
					(size 1.016 1.016)
					(thickness 0.1524)
				)
				(justify mirror)
			)
		)
		(property "Device Type" "TPAD28"
			(at 0.0127 -3.1877 90)
			(unlocked yes)
			(layer "B.Fab")
			(hide yes)
			(effects
				(font
					(size 1.016 1.016)
					(thickness 0.1524)
				)
				(justify mirror)
			)
		)
		(duplicate_pad_numbers_are_jumpers no)
		(fp_poly
			(pts
				(arc
					(start 0 0.3556)
					(mid 0 -0.3556)
					(end 0 0.3556)
				)
			)
			(stroke
				(width 0)
				(type default)
			)
			(fill no)
			(layer "B.CrtYd")
		)
		(fp_poly
			(pts
				(arc
					(start 0 0.6096)
					(mid 0 -0.6096)
					(end 0 0.6096)
				)
			)
			(stroke
				(width 0)
				(type default)
			)
			(fill no)
			(layer "B.Fab")
		)
		(pad "1" smd circle
			(at 0 0 270)
			(size 0.7112 0.7112)
			(layers "B.Cu" "B.Mask" "B.Paste")
			(net "IOC_GPIO_5")
		)
	)
	(footprint ""
		(layer "B.Cu")
		(at 174.1932 -118.5418 90)
		(property "Reference" "C707"
			(at 0 0 90)
			(layer "B.SilkS")
			(hide yes)
			(effects
				(font
					(size 1.27 1.27)
				)
				(justify mirror)
			)
		)
		(property "Value" "SC10U6D3V5KX-4GP"
			(at 0.0762 -6.1214 90)
			(unlocked yes)
			(layer "B.Fab")
			(hide yes)
			(effects
				(font
					(size 1.016 1.016)
					(thickness 0.1524)
				)
				(justify mirror)
			)
		)
		(property "Device Type" "C805H58"
			(at 0.0762 -8.1534 90)
			(unlocked yes)
			(layer "B.Fab")
			(hide yes)
			(effects
				(font
					(size 1.016 1.016)
					(thickness 0.1524)
				)
				(justify mirror)
			)
		)
		(duplicate_pad_numbers_are_jumpers no)
		(fp_line
			(start -0.635 0)
			(end 0.635 0)
			(stroke
				(width 0.508)
				(type default)
			)
			(layer "B.SilkS")
		)
		(fp_rect
			(start 0.9652 1.778)
			(end -0.9652 -1.778)
			(stroke
				(width 0)
				(type default)
			)
			(fill no)
			(layer "B.CrtYd")
		)
		(fp_poly
			(pts
				(xy 0.9652 -1.778) (xy -0.9652 -1.778) (xy -0.9652 1.778) (xy 0.9652 1.778)
			)
			(stroke
				(width 0)
				(type default)
			)
			(fill no)
			(layer "B.Fab")
		)
		(pad "1" smd rect
			(at 0 -0.9652 270)
			(size 1.397 1.143)
			(layers "B.Cu" "B.Mask" "B.Paste")
			(net "P3V3")
		)
		(pad "2" smd rect
			(at 0 0.9652 270)
			(size 1.397 1.143)
			(layers "B.Cu" "B.Mask" "B.Paste")
			(net "GND")
		)
	)
	(footprint ""
		(layer "B.Cu")
		(at 186.446922 -47.556674 -90)
		(property "Reference" "TP106"
			(at 0 0 90)
			(layer "B.SilkS")
			(hide yes)
			(effects
				(font
					(size 1.27 1.27)
				)
				(justify mirror)
			)
		)
		(property "Value" "TPAD28-2-GP"
			(at 0.0127 -1.6637 270)
			(unlocked yes)
			(layer "B.Fab")
			(hide yes)
			(effects
				(font
					(size 1.016 1.016)
					(thickness 0.1524)
				)
				(justify mirror)
			)
		)
		(property "Device Type" "TPAD28"
			(at 0.0127 -3.1877 270)
			(unlocked yes)
			(layer "B.Fab")
			(hide yes)
			(effects
				(font
					(size 1.016 1.016)
					(thickness 0.1524)
				)
				(justify mirror)
			)
		)
		(duplicate_pad_numbers_are_jumpers no)
		(fp_poly
			(pts
				(arc
					(start 0 -0.3556)
					(mid 0 0.3556)
					(end 0 -0.3556)
				)
			)
			(stroke
				(width 0)
				(type default)
			)
			(fill no)
			(layer "B.CrtYd")
		)
		(fp_poly
			(pts
				(arc
					(start 0 -0.6096)
					(mid 0 0.6096)
					(end 0 -0.6096)
				)
			)
			(stroke
				(width 0)
				(type default)
			)
			(fill no)
			(layer "B.Fab")
		)
		(pad "1" smd circle
			(at 0 0 90)
			(size 0.7112 0.7112)
			(layers "B.Cu" "B.Mask" "B.Paste")
			(net "XM_ADDR_19")
		)
	)
	(footprint ""
		(layer "B.Cu")
		(at 128.799844 -73.517252 -90)
		(property "Reference" "C308"
			(at 0 0 90)
			(layer "B.SilkS")
			(hide yes)
			(effects
				(font
					(size 1.27 1.27)
				)
				(justify mirror)
			)
		)
		(property "Value" "SCD1U6D3V1KX-GP"
			(at 2.8321 -1.7399 270)
			(unlocked yes)
			(layer "B.Fab")
			(hide yes)
			(effects
				(font
					(size 1.016 1.016)
					(thickness 0.1524)
				)
				(justify mirror)
			)
		)
		(property "Device Type" "C0201H13"
			(at 2.8321 -3.2639 270)
			(unlocked yes)
			(layer "B.Fab")
			(hide yes)
			(effects
				(font
					(size 1.016 1.016)
					(thickness 0.1524)
				)
				(justify mirror)
			)
		)
		(duplicate_pad_numbers_are_jumpers no)
		(fp_rect
			(start 0.2794 0.6477)
			(end -0.2794 -0.6477)
			(stroke
				(width 0)
				(type default)
			)
			(fill no)
			(layer "B.CrtYd")
		)
		(fp_rect
			(start 0.2794 0.6477)
			(end -0.2794 -0.6477)
			(stroke
				(width 0)
				(type default)
			)
			(fill no)
			(layer "B.Fab")
		)
		(pad "1" smd custom
			(at 0 -0.2794 90)
			(size 0.0762 0.0762)
			(layers "B.Cu" "B.Mask" "B.Paste")
			(net "GB_VDDA")
			(options
				(clearance outline)
				(anchor circle)
			)
			(primitives
				(gr_poly
					(pts
						(arc
							(start 0.1524 0.127)
							(mid 0.137521 0.162921)
							(end 0.1016 0.1778)
						)
						(arc
							(start -0.1016 0.1778)
							(mid -0.137521 0.162921)
							(end -0.1524 0.127)
						)
						(arc
							(start -0.1524 -0.127)
							(mid -0.137521 -0.162921)
							(end -0.1016 -0.1778)
						)
						(arc
							(start 0.1016 -0.1778)
							(mid 0.137521 -0.162921)
							(end 0.1524 -0.127)
						)
					)
					(width 0)
					(fill yes)
				)
			)
		)
		(pad "2" smd custom
			(at 0 0.2794 90)
			(size 0.0762 0.0762)
			(layers "B.Cu" "B.Mask" "B.Paste")
			(net "GND")
			(options
				(clearance outline)
				(anchor circle)
			)
			(primitives
				(gr_poly
					(pts
						(arc
							(start 0.1524 0.127)
							(mid 0.137521 0.162921)
							(end 0.1016 0.1778)
						)
						(arc
							(start -0.1016 0.1778)
							(mid -0.137521 0.162921)
							(end -0.1524 0.127)
						)
						(arc
							(start -0.1524 -0.127)
							(mid -0.137521 -0.162921)
							(end -0.1016 -0.1778)
						)
						(arc
							(start 0.1016 -0.1778)
							(mid 0.137521 -0.162921)
							(end 0.1524 -0.127)
						)
					)
					(width 0)
					(fill yes)
				)
			)
		)
	)
	(footprint ""
		(layer "B.Cu")
		(at 164.852858 -48.381158)
		(property "Reference" "C456"
			(at 0 0 0)
			(layer "B.SilkS")
			(hide yes)
			(effects
				(font
					(size 1.27 1.27)
				)
				(justify mirror)
			)
		)
		(property "Value" "SCD1U6D3V1KX-GP"
			(at 2.8321 -1.7399 0)
			(unlocked yes)
			(layer "B.Fab")
			(hide yes)
			(effects
				(font
					(size 1.016 1.016)
					(thickness 0.1524)
				)
				(justify mirror)
			)
		)
		(property "Device Type" "C0201H13"
			(at 2.8321 -3.2639 0)
			(unlocked yes)
			(layer "B.Fab")
			(hide yes)
			(effects
				(font
					(size 1.016 1.016)
					(thickness 0.1524)
				)
				(justify mirror)
			)
		)
		(duplicate_pad_numbers_are_jumpers no)
		(fp_rect
			(start 0.2794 0.6477)
			(end -0.2794 -0.6477)
			(stroke
				(width 0)
				(type default)
			)
			(fill no)
			(layer "B.CrtYd")
		)
		(fp_rect
			(start 0.2794 0.6477)
			(end -0.2794 -0.6477)
			(stroke
				(width 0)
				(type default)
			)
			(fill no)
			(layer "B.Fab")
		)
		(pad "1" smd custom
			(at 0 -0.2794 180)
			(size 0.0762 0.0762)
			(layers "B.Cu" "B.Mask" "B.Paste")
			(net "P1V8_C")
			(options
				(clearance outline)
				(anchor circle)
			)
			(primitives
				(gr_poly
					(pts
						(arc
							(start 0.1524 0.127)
							(mid 0.137521 0.162921)
							(end 0.1016 0.1778)
						)
						(arc
							(start -0.1016 0.1778)
							(mid -0.137521 0.162921)
							(end -0.1524 0.127)
						)
						(arc
							(start -0.1524 -0.127)
							(mid -0.137521 -0.162921)
							(end -0.1016 -0.1778)
						)
						(arc
							(start 0.1016 -0.1778)
							(mid 0.137521 -0.162921)
							(end 0.1524 -0.127)
						)
					)
					(width 0)
					(fill yes)
				)
			)
		)
		(pad "2" smd custom
			(at 0 0.2794 180)
			(size 0.0762 0.0762)
			(layers "B.Cu" "B.Mask" "B.Paste")
			(net "GND")
			(options
				(clearance outline)
				(anchor circle)
			)
			(primitives
				(gr_poly
					(pts
						(arc
							(start 0.1524 0.127)
							(mid 0.137521 0.162921)
							(end 0.1016 0.1778)
						)
						(arc
							(start -0.1016 0.1778)
							(mid -0.137521 0.162921)
							(end -0.1524 0.127)
						)
						(arc
							(start -0.1524 -0.127)
							(mid -0.137521 -0.162921)
							(end -0.1016 -0.1778)
						)
						(arc
							(start 0.1016 -0.1778)
							(mid 0.137521 -0.162921)
							(end 0.1524 -0.127)
						)
					)
					(width 0)
					(fill yes)
				)
			)
		)
	)
	(footprint ""
		(layer "B.Cu")
		(at 103.6066 -63.7286 -90)
		(property "Reference" "C154"
			(at 0 0 90)
			(layer "B.SilkS")
			(hide yes)
			(effects
				(font
					(size 1.27 1.27)
				)
				(justify mirror)
			)
		)
		(property "Value" "SCD1U6D3V1KX-GP"
			(at 2.8321 -1.7399 270)
			(unlocked yes)
			(layer "B.Fab")
			(hide yes)
			(effects
				(font
					(size 1.016 1.016)
					(thickness 0.1524)
				)
				(justify mirror)
			)
		)
		(property "Device Type" "C0201H13"
			(at 2.8321 -3.2639 270)
			(unlocked yes)
			(layer "B.Fab")
			(hide yes)
			(effects
				(font
					(size 1.016 1.016)
					(thickness 0.1524)
				)
				(justify mirror)
			)
		)
		(duplicate_pad_numbers_are_jumpers no)
		(fp_rect
			(start 0.2794 0.6477)
			(end -0.2794 -0.6477)
			(stroke
				(width 0)
				(type default)
			)
			(fill no)
			(layer "B.CrtYd")
		)
		(fp_rect
			(start 0.2794 0.6477)
			(end -0.2794 -0.6477)
			(stroke
				(width 0)
				(type default)
			)
			(fill no)
			(layer "B.Fab")
		)
		(pad "1" smd custom
			(at 0 -0.2794 90)
			(size 0.0762 0.0762)
			(layers "B.Cu" "B.Mask" "B.Paste")
			(net "P1V8_E")
			(options
				(clearance outline)
				(anchor circle)
			)
			(primitives
				(gr_poly
					(pts
						(arc
							(start 0.1524 0.127)
							(mid 0.137521 0.162921)
							(end 0.1016 0.1778)
						)
						(arc
							(start -0.1016 0.1778)
							(mid -0.137521 0.162921)
							(end -0.1524 0.127)
						)
						(arc
							(start -0.1524 -0.127)
							(mid -0.137521 -0.162921)
							(end -0.1016 -0.1778)
						)
						(arc
							(start 0.1016 -0.1778)
							(mid 0.137521 -0.162921)
							(end 0.1524 -0.127)
						)
					)
					(width 0)
					(fill yes)
				)
			)
		)
		(pad "2" smd custom
			(at 0 0.2794 90)
			(size 0.0762 0.0762)
			(layers "B.Cu" "B.Mask" "B.Paste")
			(net "GND")
			(options
				(clearance outline)
				(anchor circle)
			)
			(primitives
				(gr_poly
					(pts
						(arc
							(start 0.1524 0.127)
							(mid 0.137521 0.162921)
							(end 0.1016 0.1778)
						)
						(arc
							(start -0.1016 0.1778)
							(mid -0.137521 0.162921)
							(end -0.1524 0.127)
						)
						(arc
							(start -0.1524 -0.127)
							(mid -0.137521 -0.162921)
							(end -0.1016 -0.1778)
						)
						(arc
							(start 0.1016 -0.1778)
							(mid 0.137521 -0.162921)
							(end 0.1524 -0.127)
						)
					)
					(width 0)
					(fill yes)
				)
			)
		)
	)
	(footprint ""
		(layer "B.Cu")
		(at 115.189 -71.882)
		(property "Reference" "C133"
			(at 0 0 0)
			(layer "B.SilkS")
			(hide yes)
			(effects
				(font
					(size 1.27 1.27)
				)
				(justify mirror)
			)
		)
		(property "Value" "SCD1U6D3V1KX-GP"
			(at 2.8321 -1.7399 0)
			(unlocked yes)
			(layer "B.Fab")
			(hide yes)
			(effects
				(font
					(size 1.016 1.016)
					(thickness 0.1524)
				)
				(justify mirror)
			)
		)
		(property "Device Type" "C0201H13"
			(at 2.8321 -3.2639 0)
			(unlocked yes)
			(layer "B.Fab")
			(hide yes)
			(effects
				(font
					(size 1.016 1.016)
					(thickness 0.1524)
				)
				(justify mirror)
			)
		)
		(duplicate_pad_numbers_are_jumpers no)
		(fp_rect
			(start 0.2794 0.6477)
			(end -0.2794 -0.6477)
			(stroke
				(width 0)
				(type default)
			)
			(fill no)
			(layer "B.CrtYd")
		)
		(fp_rect
			(start 0.2794 0.6477)
			(end -0.2794 -0.6477)
			(stroke
				(width 0)
				(type default)
			)
			(fill no)
			(layer "B.Fab")
		)
		(pad "1" smd custom
			(at 0 -0.2794 180)
			(size 0.0762 0.0762)
			(layers "B.Cu" "B.Mask" "B.Paste")
			(net "P1V8_E")
			(options
				(clearance outline)
				(anchor circle)
			)
			(primitives
				(gr_poly
					(pts
						(arc
							(start 0.1524 0.127)
							(mid 0.137521 0.162921)
							(end 0.1016 0.1778)
						)
						(arc
							(start -0.1016 0.1778)
							(mid -0.137521 0.162921)
							(end -0.1524 0.127)
						)
						(arc
							(start -0.1524 -0.127)
							(mid -0.137521 -0.162921)
							(end -0.1016 -0.1778)
						)
						(arc
							(start 0.1016 -0.1778)
							(mid 0.137521 -0.162921)
							(end 0.1524 -0.127)
						)
					)
					(width 0)
					(fill yes)
				)
			)
		)
		(pad "2" smd custom
			(at 0 0.2794 180)
			(size 0.0762 0.0762)
			(layers "B.Cu" "B.Mask" "B.Paste")
			(net "GND")
			(options
				(clearance outline)
				(anchor circle)
			)
			(primitives
				(gr_poly
					(pts
						(arc
							(start 0.1524 0.127)
							(mid 0.137521 0.162921)
							(end 0.1016 0.1778)
						)
						(arc
							(start -0.1016 0.1778)
							(mid -0.137521 0.162921)
							(end -0.1524 0.127)
						)
						(arc
							(start -0.1524 -0.127)
							(mid -0.137521 -0.162921)
							(end -0.1016 -0.1778)
						)
						(arc
							(start 0.1016 -0.1778)
							(mid 0.137521 -0.162921)
							(end 0.1524 -0.127)
						)
					)
					(width 0)
					(fill yes)
				)
			)
		)
	)
	(footprint ""
		(layer "B.Cu")
		(at 122.4788 -69.4944 -90)
		(property "Reference" "C589"
			(at 0 0 90)
			(layer "B.SilkS")
			(hide yes)
			(effects
				(font
					(size 1.27 1.27)
				)
				(justify mirror)
			)
		)
		(property "Value" "SCD1U6D3V1KX-GP"
			(at 2.8321 -1.7399 270)
			(unlocked yes)
			(layer "B.Fab")
			(hide yes)
			(effects
				(font
					(size 1.016 1.016)
					(thickness 0.1524)
				)
				(justify mirror)
			)
		)
		(property "Device Type" "C0201H13"
			(at 2.8321 -3.2639 270)
			(unlocked yes)
			(layer "B.Fab")
			(hide yes)
			(effects
				(font
					(size 1.016 1.016)
					(thickness 0.1524)
				)
				(justify mirror)
			)
		)
		(duplicate_pad_numbers_are_jumpers no)
		(fp_rect
			(start 0.2794 0.6477)
			(end -0.2794 -0.6477)
			(stroke
				(width 0)
				(type default)
			)
			(fill no)
			(layer "B.CrtYd")
		)
		(fp_rect
			(start 0.2794 0.6477)
			(end -0.2794 -0.6477)
			(stroke
				(width 0)
				(type default)
			)
			(fill no)
			(layer "B.Fab")
		)
		(pad "1" smd custom
			(at 0 -0.2794 90)
			(size 0.0762 0.0762)
			(layers "B.Cu" "B.Mask" "B.Paste")
			(net "GB_VDDA")
			(options
				(clearance outline)
				(anchor circle)
			)
			(primitives
				(gr_poly
					(pts
						(arc
							(start 0.1524 0.127)
							(mid 0.137521 0.162921)
							(end 0.1016 0.1778)
						)
						(arc
							(start -0.1016 0.1778)
							(mid -0.137521 0.162921)
							(end -0.1524 0.127)
						)
						(arc
							(start -0.1524 -0.127)
							(mid -0.137521 -0.162921)
							(end -0.1016 -0.1778)
						)
						(arc
							(start 0.1016 -0.1778)
							(mid 0.137521 -0.162921)
							(end 0.1524 -0.127)
						)
					)
					(width 0)
					(fill yes)
				)
			)
		)
		(pad "2" smd custom
			(at 0 0.2794 90)
			(size 0.0762 0.0762)
			(layers "B.Cu" "B.Mask" "B.Paste")
			(net "GND")
			(options
				(clearance outline)
				(anchor circle)
			)
			(primitives
				(gr_poly
					(pts
						(arc
							(start 0.1524 0.127)
							(mid 0.137521 0.162921)
							(end 0.1016 0.1778)
						)
						(arc
							(start -0.1016 0.1778)
							(mid -0.137521 0.162921)
							(end -0.1524 0.127)
						)
						(arc
							(start -0.1524 -0.127)
							(mid -0.137521 -0.162921)
							(end -0.1016 -0.1778)
						)
						(arc
							(start 0.1016 -0.1778)
							(mid 0.137521 -0.162921)
							(end 0.1524 -0.127)
						)
					)
					(width 0)
					(fill yes)
				)
			)
		)
	)
	(footprint ""
		(layer "B.Cu")
		(at 118.49989 -77.499972)
		(property "Reference" "TP25"
			(at 0 0 0)
			(layer "B.SilkS")
			(hide yes)
			(effects
				(font
					(size 1.27 1.27)
				)
				(justify mirror)
			)
		)
		(property "Value" "TPAD28-2-GP"
			(at 0.0127 -1.6637 0)
			(unlocked yes)
			(layer "B.Fab")
			(hide yes)
			(effects
				(font
					(size 1.016 1.016)
					(thickness 0.1524)
				)
				(justify mirror)
			)
		)
		(property "Device Type" "TPAD28"
			(at 0.0127 -3.1877 0)
			(unlocked yes)
			(layer "B.Fab")
			(hide yes)
			(effects
				(font
					(size 1.016 1.016)
					(thickness 0.1524)
				)
				(justify mirror)
			)
		)
		(duplicate_pad_numbers_are_jumpers no)
		(fp_poly
			(pts
				(arc
					(start 0.3556 0)
					(mid -0.3556 0)
					(end 0.3556 0)
				)
			)
			(stroke
				(width 0)
				(type default)
			)
			(fill no)
			(layer "B.CrtYd")
		)
		(fp_poly
			(pts
				(arc
					(start 0.6096 0)
					(mid -0.6096 0)
					(end 0.6096 0)
				)
			)
			(stroke
				(width 0)
				(type default)
			)
			(fill no)
			(layer "B.Fab")
		)
		(pad "1" smd circle
			(at 0 0 180)
			(size 0.7112 0.7112)
			(layers "B.Cu" "B.Mask" "B.Paste")
			(net "EXP_GPIO1")
		)
	)
	(footprint ""
		(layer "B.Cu")
		(at 73.66 -57.277)
		(property "Reference" "C248"
			(at 0 0 0)
			(layer "B.SilkS")
			(hide yes)
			(effects
				(font
					(size 1.27 1.27)
				)
				(justify mirror)
			)
		)
		(property "Value" "SC100U6D3V6MX-GP"
			(at 0.0762 -5.1308 0)
			(unlocked yes)
			(layer "B.Fab")
			(hide yes)
			(effects
				(font
					(size 1.016 1.016)
					(thickness 0.1524)
				)
				(justify mirror)
			)
		)
		(property "Device Type" "C1206H71"
			(at 0.127 -6.6548 0)
			(unlocked yes)
			(layer "B.Fab")
			(hide yes)
			(effects
				(font
					(size 1.016 1.016)
					(thickness 0.1524)
				)
				(justify mirror)
			)
		)
		(duplicate_pad_numbers_are_jumpers no)
		(fp_line
			(start -1.016 -2.2352)
			(end -1.016 -0.8382)
			(stroke
				(width 0.1524)
				(type default)
			)
			(layer "B.SilkS")
		)
		(fp_line
			(start -1.016 0.8382)
			(end -1.016 2.2352)
			(stroke
				(width 0.1524)
				(type default)
			)
			(layer "B.SilkS")
		)
		(fp_line
			(start -1.016 2.2352)
			(end 1.016 2.2352)
			(stroke
				(width 0.1524)
				(type default)
			)
			(layer "B.SilkS")
		)
		(fp_line
			(start 1.016 -2.2352)
			(end -1.016 -2.2352)
			(stroke
				(width 0.1524)
				(type default)
			)
			(layer "B.SilkS")
		)
		(fp_line
			(start 1.016 -0.8382)
			(end 1.016 -2.2352)
			(stroke
				(width 0.1524)
				(type default)
			)
			(layer "B.SilkS")
		)
		(fp_line
			(start 1.016 2.2352)
			(end 1.016 0.8382)
			(stroke
				(width 0.1524)
				(type default)
			)
			(layer "B.SilkS")
		)
		(fp_rect
			(start 1.0922 2.3114)
			(end -1.0922 -2.3114)
			(stroke
				(width 0)
				(type default)
			)
			(fill no)
			(layer "B.CrtYd")
		)
		(fp_poly
			(pts
				(xy -1.0922 -2.3114) (xy -1.0922 2.3114) (xy 1.0922 2.3114) (xy 1.0922 -2.3114)
			)
			(stroke
				(width 0)
				(type default)
			)
			(fill no)
			(layer "B.Fab")
		)
		(pad "1" smd rect
			(at 0 -1.397 180)
			(size 1.651 1.27)
			(layers "B.Cu" "B.Mask" "B.Paste")
			(net "GB_VDDA")
		)
		(pad "2" smd rect
			(at 0 1.397 180)
			(size 1.651 1.27)
			(layers "B.Cu" "B.Mask" "B.Paste")
			(net "GND")
		)
	)
	(footprint ""
		(layer "B.Cu")
		(at 175.2854 -35.56)
		(property "Reference" "C419"
			(at 0 0 0)
			(layer "B.SilkS")
			(hide yes)
			(effects
				(font
					(size 1.27 1.27)
				)
				(justify mirror)
			)
		)
		(property "Value" "SCD1U6D3V1KX-GP"
			(at 2.8321 -1.7399 0)
			(unlocked yes)
			(layer "B.Fab")
			(hide yes)
			(effects
				(font
					(size 1.016 1.016)
					(thickness 0.1524)
				)
				(justify mirror)
			)
		)
		(property "Device Type" "C0201H13"
			(at 2.8321 -3.2639 0)
			(unlocked yes)
			(layer "B.Fab")
			(hide yes)
			(effects
				(font
					(size 1.016 1.016)
					(thickness 0.1524)
				)
				(justify mirror)
			)
		)
		(duplicate_pad_numbers_are_jumpers no)
		(fp_rect
			(start 0.2794 0.6477)
			(end -0.2794 -0.6477)
			(stroke
				(width 0)
				(type default)
			)
			(fill no)
			(layer "B.CrtYd")
		)
		(fp_rect
			(start 0.2794 0.6477)
			(end -0.2794 -0.6477)
			(stroke
				(width 0)
				(type default)
			)
			(fill no)
			(layer "B.Fab")
		)
		(pad "1" smd custom
			(at 0 -0.2794 180)
			(size 0.0762 0.0762)
			(layers "B.Cu" "B.Mask" "B.Paste")
			(net "P0V975")
			(options
				(clearance outline)
				(anchor circle)
			)
			(primitives
				(gr_poly
					(pts
						(arc
							(start 0.1524 0.127)
							(mid 0.137521 0.162921)
							(end 0.1016 0.1778)
						)
						(arc
							(start -0.1016 0.1778)
							(mid -0.137521 0.162921)
							(end -0.1524 0.127)
						)
						(arc
							(start -0.1524 -0.127)
							(mid -0.137521 -0.162921)
							(end -0.1016 -0.1778)
						)
						(arc
							(start 0.1016 -0.1778)
							(mid 0.137521 -0.162921)
							(end 0.1524 -0.127)
						)
					)
					(width 0)
					(fill yes)
				)
			)
		)
		(pad "2" smd custom
			(at 0 0.2794 180)
			(size 0.0762 0.0762)
			(layers "B.Cu" "B.Mask" "B.Paste")
			(net "GND")
			(options
				(clearance outline)
				(anchor circle)
			)
			(primitives
				(gr_poly
					(pts
						(arc
							(start 0.1524 0.127)
							(mid 0.137521 0.162921)
							(end 0.1016 0.1778)
						)
						(arc
							(start -0.1016 0.1778)
							(mid -0.137521 0.162921)
							(end -0.1524 0.127)
						)
						(arc
							(start -0.1524 -0.127)
							(mid -0.137521 -0.162921)
							(end -0.1016 -0.1778)
						)
						(arc
							(start 0.1016 -0.1778)
							(mid 0.137521 -0.162921)
							(end 0.1524 -0.127)
						)
					)
					(width 0)
					(fill yes)
				)
			)
		)
	)
	(footprint ""
		(layer "B.Cu")
		(at 98.171 -44.2214 180)
		(property "Reference" "C86"
			(at 0 0 0)
			(layer "B.SilkS")
			(hide yes)
			(effects
				(font
					(size 1.27 1.27)
				)
				(justify mirror)
			)
		)
		(property "Value" "SCD01U16V1KX-GP"
			(at 2.8321 -1.7399 180)
			(unlocked yes)
			(layer "B.Fab")
			(hide yes)
			(effects
				(font
					(size 1.016 1.016)
					(thickness 0.1524)
				)
				(justify mirror)
			)
		)
		(property "Device Type" "C0201H13"
			(at 2.8321 -3.2639 180)
			(unlocked yes)
			(layer "B.Fab")
			(hide yes)
			(effects
				(font
					(size 1.016 1.016)
					(thickness 0.1524)
				)
				(justify mirror)
			)
		)
		(duplicate_pad_numbers_are_jumpers no)
		(fp_rect
			(start 0.2794 0.6477)
			(end -0.2794 -0.6477)
			(stroke
				(width 0)
				(type default)
			)
			(fill no)
			(layer "B.CrtYd")
		)
		(fp_rect
			(start 0.2794 0.6477)
			(end -0.2794 -0.6477)
			(stroke
				(width 0)
				(type default)
			)
			(fill no)
			(layer "B.Fab")
		)
		(pad "1" smd custom
			(at 0 -0.2794)
			(size 0.0762 0.0762)
			(layers "B.Cu" "B.Mask" "B.Paste")
			(net "PHY_DPB_TO_SCC_17_DN")
			(options
				(clearance outline)
				(anchor circle)
			)
			(primitives
				(gr_poly
					(pts
						(arc
							(start 0.1524 0.127)
							(mid 0.137521 0.162921)
							(end 0.1016 0.1778)
						)
						(arc
							(start -0.1016 0.1778)
							(mid -0.137521 0.162921)
							(end -0.1524 0.127)
						)
						(arc
							(start -0.1524 -0.127)
							(mid -0.137521 -0.162921)
							(end -0.1016 -0.1778)
						)
						(arc
							(start 0.1016 -0.1778)
							(mid 0.137521 -0.162921)
							(end 0.1524 -0.127)
						)
					)
					(width 0)
					(fill yes)
				)
			)
		)
		(pad "2" smd custom
			(at 0 0.2794)
			(size 0.0762 0.0762)
			(layers "B.Cu" "B.Mask" "B.Paste")
			(net "PHY_DPB_TO_SCC_C_17_DN")
			(options
				(clearance outline)
				(anchor circle)
			)
			(primitives
				(gr_poly
					(pts
						(arc
							(start 0.1524 0.127)
							(mid 0.137521 0.162921)
							(end 0.1016 0.1778)
						)
						(arc
							(start -0.1016 0.1778)
							(mid -0.137521 0.162921)
							(end -0.1524 0.127)
						)
						(arc
							(start -0.1524 -0.127)
							(mid -0.137521 -0.162921)
							(end -0.1016 -0.1778)
						)
						(arc
							(start 0.1016 -0.1778)
							(mid 0.137521 -0.162921)
							(end 0.1524 -0.127)
						)
					)
					(width 0)
					(fill yes)
				)
			)
		)
	)
	(footprint ""
		(layer "B.Cu")
		(at 124.5108 -58.3946 90)
		(property "Reference" "C293"
			(at 0 0 90)
			(layer "B.SilkS")
			(hide yes)
			(effects
				(font
					(size 1.27 1.27)
				)
				(justify mirror)
			)
		)
		(property "Value" "SCD1U6D3V1KX-GP"
			(at 2.8321 -1.7399 90)
			(unlocked yes)
			(layer "B.Fab")
			(hide yes)
			(effects
				(font
					(size 1.016 1.016)
					(thickness 0.1524)
				)
				(justify mirror)
			)
		)
		(property "Device Type" "C0201H13"
			(at 2.8321 -3.2639 90)
			(unlocked yes)
			(layer "B.Fab")
			(hide yes)
			(effects
				(font
					(size 1.016 1.016)
					(thickness 0.1524)
				)
				(justify mirror)
			)
		)
		(duplicate_pad_numbers_are_jumpers no)
		(fp_rect
			(start 0.2794 0.6477)
			(end -0.2794 -0.6477)
			(stroke
				(width 0)
				(type default)
			)
			(fill no)
			(layer "B.CrtYd")
		)
		(fp_rect
			(start 0.2794 0.6477)
			(end -0.2794 -0.6477)
			(stroke
				(width 0)
				(type default)
			)
			(fill no)
			(layer "B.Fab")
		)
		(pad "1" smd custom
			(at 0 -0.2794 270)
			(size 0.0762 0.0762)
			(layers "B.Cu" "B.Mask" "B.Paste")
			(net "GB_VDDA")
			(options
				(clearance outline)
				(anchor circle)
			)
			(primitives
				(gr_poly
					(pts
						(arc
							(start 0.1524 0.127)
							(mid 0.137521 0.162921)
							(end 0.1016 0.1778)
						)
						(arc
							(start -0.1016 0.1778)
							(mid -0.137521 0.162921)
							(end -0.1524 0.127)
						)
						(arc
							(start -0.1524 -0.127)
							(mid -0.137521 -0.162921)
							(end -0.1016 -0.1778)
						)
						(arc
							(start 0.1016 -0.1778)
							(mid 0.137521 -0.162921)
							(end 0.1524 -0.127)
						)
					)
					(width 0)
					(fill yes)
				)
			)
		)
		(pad "2" smd custom
			(at 0 0.2794 270)
			(size 0.0762 0.0762)
			(layers "B.Cu" "B.Mask" "B.Paste")
			(net "GND")
			(options
				(clearance outline)
				(anchor circle)
			)
			(primitives
				(gr_poly
					(pts
						(arc
							(start 0.1524 0.127)
							(mid 0.137521 0.162921)
							(end 0.1016 0.1778)
						)
						(arc
							(start -0.1016 0.1778)
							(mid -0.137521 0.162921)
							(end -0.1524 0.127)
						)
						(arc
							(start -0.1524 -0.127)
							(mid -0.137521 -0.162921)
							(end -0.1016 -0.1778)
						)
						(arc
							(start 0.1016 -0.1778)
							(mid 0.137521 -0.162921)
							(end 0.1524 -0.127)
						)
					)
					(width 0)
					(fill yes)
				)
			)
		)
	)
	(footprint ""
		(layer "B.Cu")
		(at 181.87416 -44.785788)
		(property "Reference" "TP150"
			(at 0 0 0)
			(layer "B.SilkS")
			(hide yes)
			(effects
				(font
					(size 1.27 1.27)
				)
				(justify mirror)
			)
		)
		(property "Value" "TPAD28-2-GP"
			(at 0.0127 -1.6637 0)
			(unlocked yes)
			(layer "B.Fab")
			(hide yes)
			(effects
				(font
					(size 1.016 1.016)
					(thickness 0.1524)
				)
				(justify mirror)
			)
		)
		(property "Device Type" "TPAD28"
			(at 0.0127 -3.1877 0)
			(unlocked yes)
			(layer "B.Fab")
			(hide yes)
			(effects
				(font
					(size 1.016 1.016)
					(thickness 0.1524)
				)
				(justify mirror)
			)
		)
		(duplicate_pad_numbers_are_jumpers no)
		(fp_poly
			(pts
				(arc
					(start 0.3556 0)
					(mid -0.3556 0)
					(end 0.3556 0)
				)
			)
			(stroke
				(width 0)
				(type default)
			)
			(fill no)
			(layer "B.CrtYd")
		)
		(fp_poly
			(pts
				(arc
					(start 0.6096 0)
					(mid -0.6096 0)
					(end 0.6096 0)
				)
			)
			(stroke
				(width 0)
				(type default)
			)
			(fill no)
			(layer "B.Fab")
		)
		(pad "1" smd circle
			(at 0 0 180)
			(size 0.7112 0.7112)
			(layers "B.Cu" "B.Mask" "B.Paste")
			(net "VDDIO_15")
		)
	)
	(footprint ""
		(layer "B.Cu")
		(at 160.4518 -50.419)
		(property "Reference" "TP88"
			(at 0 0 0)
			(layer "B.SilkS")
			(hide yes)
			(effects
				(font
					(size 1.27 1.27)
				)
				(justify mirror)
			)
		)
		(property "Value" "TPAD28-2-GP"
			(at 0.0127 -1.6637 0)
			(unlocked yes)
			(layer "B.Fab")
			(hide yes)
			(effects
				(font
					(size 1.016 1.016)
					(thickness 0.1524)
				)
				(justify mirror)
			)
		)
		(property "Device Type" "TPAD28"
			(at 0.0127 -3.1877 0)
			(unlocked yes)
			(layer "B.Fab")
			(hide yes)
			(effects
				(font
					(size 1.016 1.016)
					(thickness 0.1524)
				)
				(justify mirror)
			)
		)
		(duplicate_pad_numbers_are_jumpers no)
		(fp_poly
			(pts
				(arc
					(start 0.3556 0)
					(mid -0.3556 0)
					(end 0.3556 0)
				)
			)
			(stroke
				(width 0)
				(type default)
			)
			(fill no)
			(layer "B.CrtYd")
		)
		(fp_poly
			(pts
				(arc
					(start 0.6096 0)
					(mid -0.6096 0)
					(end 0.6096 0)
				)
			)
			(stroke
				(width 0)
				(type default)
			)
			(fill no)
			(layer "B.Fab")
		)
		(pad "1" smd circle
			(at 0 0 180)
			(size 0.7112 0.7112)
			(layers "B.Cu" "B.Mask" "B.Paste")
			(net "SIO_CLK_1")
		)
	)
	(footprint ""
		(layer "B.Cu")
		(at 111.375444 -89.240614 90)
		(property "Reference" "R109"
			(at 0 0 90)
			(layer "B.SilkS")
			(hide yes)
			(effects
				(font
					(size 1.27 1.27)
				)
				(justify mirror)
			)
		)
		(property "Value" "4K75R2F-1-GP"
			(at -0.064008 -3.993896 90)
			(unlocked yes)
			(layer "B.Fab")
			(hide yes)
			(effects
				(font
					(size 1.016 1.016)
					(thickness 0.1524)
				)
				(justify mirror)
			)
		)
		(property "Device Type" "R402H16"
			(at -0.064008 -5.517896 90)
			(unlocked yes)
			(layer "B.Fab")
			(hide yes)
			(effects
				(font
					(size 1.016 1.016)
					(thickness 0.1524)
				)
				(justify mirror)
			)
		)
		(duplicate_pad_numbers_are_jumpers no)
		(fp_line
			(start 0.508 -0.9398)
			(end 0.508 0.9398)
			(stroke
				(width 0.1524)
				(type default)
			)
			(layer "B.SilkS")
		)
		(fp_line
			(start -0.508 -0.9398)
			(end 0.508 -0.9398)
			(stroke
				(width 0.1524)
				(type default)
			)
			(layer "B.SilkS")
		)
		(fp_rect
			(start 0.508 0.9398)
			(end -0.508 -0.9398)
			(stroke
				(width 0)
				(type default)
			)
			(fill no)
			(layer "B.CrtYd")
		)
		(fp_rect
			(start 0.508 0.9398)
			(end -0.508 -0.9398)
			(stroke
				(width 0)
				(type default)
			)
			(fill no)
			(layer "B.Fab")
		)
		(pad "1" smd custom
			(at 0 -0.4445 270)
			(size 0.1397 0.1397)
			(layers "B.Cu" "B.Mask" "B.Paste")
			(net "EXP_IDDT")
			(options
				(clearance outline)
				(anchor circle)
			)
			(primitives
				(gr_poly
					(pts
						(arc
							(start -0.1778 0.2794)
							(mid -0.249642 0.249642)
							(end -0.2794 0.1778)
						)
						(arc
							(start -0.2794 -0.1778)
							(mid -0.249642 -0.249642)
							(end -0.1778 -0.2794)
						)
						(arc
							(start 0.1778 -0.2794)
							(mid 0.249642 -0.249642)
							(end 0.2794 -0.1778)
						)
						(arc
							(start 0.2794 0.1778)
							(mid 0.249642 0.249642)
							(end 0.1778 0.2794)
						)
					)
					(width 0)
					(fill yes)
				)
			)
		)
		(pad "2" smd custom
			(at 0 0.4445 270)
			(size 0.1397 0.1397)
			(layers "B.Cu" "B.Mask" "B.Paste")
			(net "GND")
			(options
				(clearance outline)
				(anchor circle)
			)
			(primitives
				(gr_poly
					(pts
						(arc
							(start -0.1778 0.2794)
							(mid -0.249642 0.249642)
							(end -0.2794 0.1778)
						)
						(arc
							(start -0.2794 -0.1778)
							(mid -0.249642 -0.249642)
							(end -0.1778 -0.2794)
						)
						(arc
							(start 0.1778 -0.2794)
							(mid 0.249642 -0.249642)
							(end 0.2794 -0.1778)
						)
						(arc
							(start 0.2794 0.1778)
							(mid 0.249642 0.249642)
							(end 0.1778 0.2794)
						)
					)
					(width 0)
					(fill yes)
				)
			)
		)
	)
	(footprint ""
		(layer "B.Cu")
		(at 187.599066 -39.598346 90)
		(property "Reference" "R172"
			(at 0 0 90)
			(layer "B.SilkS")
			(hide yes)
			(effects
				(font
					(size 1.27 1.27)
				)
				(justify mirror)
			)
		)
		(property "Value" "10KR2F-2-GP"
			(at -0.064008 -3.993896 90)
			(unlocked yes)
			(layer "B.Fab")
			(hide yes)
			(effects
				(font
					(size 1.016 1.016)
					(thickness 0.1524)
				)
				(justify mirror)
			)
		)
		(property "Device Type" "R402H16"
			(at -0.064008 -5.517896 90)
			(unlocked yes)
			(layer "B.Fab")
			(hide yes)
			(effects
				(font
					(size 1.016 1.016)
					(thickness 0.1524)
				)
				(justify mirror)
			)
		)
		(duplicate_pad_numbers_are_jumpers no)
		(fp_line
			(start 0.508 -0.9398)
			(end 0.508 0.9398)
			(stroke
				(width 0.1524)
				(type default)
			)
			(layer "B.SilkS")
		)
		(fp_line
			(start -0.508 -0.9398)
			(end 0.508 -0.9398)
			(stroke
				(width 0.1524)
				(type default)
			)
			(layer "B.SilkS")
		)
		(fp_rect
			(start 0.508 0.9398)
			(end -0.508 -0.9398)
			(stroke
				(width 0)
				(type default)
			)
			(fill no)
			(layer "B.CrtYd")
		)
		(fp_rect
			(start 0.508 0.9398)
			(end -0.508 -0.9398)
			(stroke
				(width 0)
				(type default)
			)
			(fill no)
			(layer "B.Fab")
		)
		(pad "1" smd custom
			(at 0 -0.4445 270)
			(size 0.1397 0.1397)
			(layers "B.Cu" "B.Mask" "B.Paste")
			(net "IOC_CLK_SEL1")
			(options
				(clearance outline)
				(anchor circle)
			)
			(primitives
				(gr_poly
					(pts
						(arc
							(start -0.1778 0.2794)
							(mid -0.249642 0.249642)
							(end -0.2794 0.1778)
						)
						(arc
							(start -0.2794 -0.1778)
							(mid -0.249642 -0.249642)
							(end -0.1778 -0.2794)
						)
						(arc
							(start 0.1778 -0.2794)
							(mid 0.249642 -0.249642)
							(end 0.2794 -0.1778)
						)
						(arc
							(start 0.2794 0.1778)
							(mid 0.249642 0.249642)
							(end 0.1778 0.2794)
						)
					)
					(width 0)
					(fill yes)
				)
			)
		)
		(pad "2" smd custom
			(at 0 0.4445 270)
			(size 0.1397 0.1397)
			(layers "B.Cu" "B.Mask" "B.Paste")
			(net "P1V8_C")
			(options
				(clearance outline)
				(anchor circle)
			)
			(primitives
				(gr_poly
					(pts
						(arc
							(start -0.1778 0.2794)
							(mid -0.249642 0.249642)
							(end -0.2794 0.1778)
						)
						(arc
							(start -0.2794 -0.1778)
							(mid -0.249642 -0.249642)
							(end -0.1778 -0.2794)
						)
						(arc
							(start 0.1778 -0.2794)
							(mid 0.249642 -0.249642)
							(end 0.2794 -0.1778)
						)
						(arc
							(start 0.2794 0.1778)
							(mid 0.249642 0.249642)
							(end 0.1778 0.2794)
						)
					)
					(width 0)
					(fill yes)
				)
			)
		)
	)
	(footprint ""
		(layer "B.Cu")
		(at 42.910252 -109.94898 -90)
		(property "Reference" "C348"
			(at 0 0 90)
			(layer "B.SilkS")
			(hide yes)
			(effects
				(font
					(size 1.27 1.27)
				)
				(justify mirror)
			)
		)
		(property "Value" "SC1U16V3KX-5GP"
			(at 0 -2.8194 270)
			(unlocked yes)
			(layer "B.Fab")
			(hide yes)
			(effects
				(font
					(size 1.016 1.016)
					(thickness 0.1524)
				)
				(justify mirror)
			)
		)
		(property "Device Type" "C603H36"
			(at 0 -4.3434 270)
			(unlocked yes)
			(layer "B.Fab")
			(hide yes)
			(effects
				(font
					(size 1.016 1.016)
					(thickness 0.1524)
				)
				(justify mirror)
			)
		)
		(duplicate_pad_numbers_are_jumpers no)
		(fp_line
			(start -0.508 0)
			(end 0.508 0)
			(stroke
				(width 0.2032)
				(type default)
			)
			(layer "B.SilkS")
		)
		(fp_rect
			(start 0.5842 1.3335)
			(end -0.5842 -1.3335)
			(stroke
				(width 0)
				(type default)
			)
			(fill no)
			(layer "B.CrtYd")
		)
		(fp_rect
			(start 0.5842 1.3335)
			(end -0.5842 -1.3335)
			(stroke
				(width 0)
				(type default)
			)
			(fill no)
			(layer "B.Fab")
		)
		(pad "1" smd custom
			(at 0 -0.762 90)
			(size 0.2159 0.2159)
			(layers "B.Cu" "B.Mask" "B.Paste")
			(net "P12V_STBY_SCC")
			(options
				(clearance outline)
				(anchor circle)
			)
			(primitives
				(gr_poly
					(pts
						(arc
							(start -0.3302 0.4318)
							(mid -0.402042 0.402042)
							(end -0.4318 0.3302)
						)
						(arc
							(start -0.4318 -0.3302)
							(mid -0.402042 -0.402042)
							(end -0.3302 -0.4318)
						)
						(arc
							(start 0.3302 -0.4318)
							(mid 0.402042 -0.402042)
							(end 0.4318 -0.3302)
						)
						(arc
							(start 0.4318 0.3302)
							(mid 0.402042 0.402042)
							(end 0.3302 0.4318)
						)
					)
					(width 0)
					(fill yes)
				)
			)
		)
		(pad "2" smd custom
			(at 0 0.762 90)
			(size 0.2159 0.2159)
			(layers "B.Cu" "B.Mask" "B.Paste")
			(net "GND")
			(options
				(clearance outline)
				(anchor circle)
			)
			(primitives
				(gr_poly
					(pts
						(arc
							(start -0.3302 0.4318)
							(mid -0.402042 0.402042)
							(end -0.4318 0.3302)
						)
						(arc
							(start -0.4318 -0.3302)
							(mid -0.402042 -0.402042)
							(end -0.3302 -0.4318)
						)
						(arc
							(start 0.3302 -0.4318)
							(mid 0.402042 -0.402042)
							(end 0.4318 -0.3302)
						)
						(arc
							(start 0.4318 0.3302)
							(mid 0.402042 0.402042)
							(end 0.3302 0.4318)
						)
					)
					(width 0)
					(fill yes)
				)
			)
		)
	)
	(footprint ""
		(layer "B.Cu")
		(at 173.8376 -38.3794 -90)
		(property "Reference" "C445"
			(at 0 0 90)
			(layer "B.SilkS")
			(hide yes)
			(effects
				(font
					(size 1.27 1.27)
				)
				(justify mirror)
			)
		)
		(property "Value" "SC1KP50V2KX-1GP"
			(at -1.1811 -2.7051 270)
			(unlocked yes)
			(layer "B.Fab")
			(hide yes)
			(effects
				(font
					(size 1.016 1.016)
					(thickness 0.1524)
				)
				(justify mirror)
			)
		)
		(property "Device Type" "C402H22"
			(at -1.1811 -4.2291 270)
			(unlocked yes)
			(layer "B.Fab")
			(hide yes)
			(effects
				(font
					(size 1.016 1.016)
					(thickness 0.1524)
				)
				(justify mirror)
			)
		)
		(duplicate_pad_numbers_are_jumpers no)
		(fp_rect
			(start 0.4318 0.9525)
			(end -0.4318 -0.9525)
			(stroke
				(width 0)
				(type default)
			)
			(fill no)
			(layer "B.CrtYd")
		)
		(fp_rect
			(start 0.4318 0.9525)
			(end -0.4318 -0.9525)
			(stroke
				(width 0)
				(type default)
			)
			(fill no)
			(layer "B.Fab")
		)
		(pad "1" smd custom
			(at 0 -0.4445 90)
			(size 0.1524 0.1524)
			(layers "B.Cu" "B.Mask" "B.Paste")
			(net "P0V975")
			(options
				(clearance outline)
				(anchor circle)
			)
			(primitives
				(gr_poly
					(pts
						(arc
							(start 0.3048 0.2032)
							(mid 0.275042 0.275042)
							(end 0.2032 0.3048)
						)
						(arc
							(start -0.2032 0.3048)
							(mid -0.275042 0.275042)
							(end -0.3048 0.2032)
						)
						(arc
							(start -0.3048 -0.2032)
							(mid -0.275042 -0.275042)
							(end -0.2032 -0.3048)
						)
						(arc
							(start 0.2032 -0.3048)
							(mid 0.275042 -0.275042)
							(end 0.3048 -0.2032)
						)
					)
					(width 0)
					(fill yes)
				)
			)
		)
		(pad "2" smd custom
			(at 0 0.4445 90)
			(size 0.1524 0.1524)
			(layers "B.Cu" "B.Mask" "B.Paste")
			(net "GND")
			(options
				(clearance outline)
				(anchor circle)
			)
			(primitives
				(gr_poly
					(pts
						(arc
							(start 0.3048 0.2032)
							(mid 0.275042 0.275042)
							(end 0.2032 0.3048)
						)
						(arc
							(start -0.2032 0.3048)
							(mid -0.275042 0.275042)
							(end -0.3048 0.2032)
						)
						(arc
							(start -0.3048 -0.2032)
							(mid -0.275042 -0.275042)
							(end -0.2032 -0.3048)
						)
						(arc
							(start 0.2032 -0.3048)
							(mid 0.275042 -0.275042)
							(end 0.3048 -0.2032)
						)
					)
					(width 0)
					(fill yes)
				)
			)
		)
	)
	(footprint ""
		(layer "B.Cu")
		(at 170.4848 -73.152 90)
		(property "Reference" "R303"
			(at 0 0 90)
			(layer "B.SilkS")
			(hide yes)
			(effects
				(font
					(size 1.27 1.27)
				)
				(justify mirror)
			)
		)
		(property "Value" "10KR2F-2-GP"
			(at -0.064008 -3.993896 90)
			(unlocked yes)
			(layer "B.Fab")
			(hide yes)
			(effects
				(font
					(size 1.016 1.016)
					(thickness 0.1524)
				)
				(justify mirror)
			)
		)
		(property "Device Type" "R402H16"
			(at -0.064008 -5.517896 90)
			(unlocked yes)
			(layer "B.Fab")
			(hide yes)
			(effects
				(font
					(size 1.016 1.016)
					(thickness 0.1524)
				)
				(justify mirror)
			)
		)
		(duplicate_pad_numbers_are_jumpers no)
		(fp_line
			(start 0.508 -0.9398)
			(end 0.508 0.9398)
			(stroke
				(width 0.1524)
				(type default)
			)
			(layer "B.SilkS")
		)
		(fp_line
			(start -0.508 -0.9398)
			(end 0.508 -0.9398)
			(stroke
				(width 0.1524)
				(type default)
			)
			(layer "B.SilkS")
		)
		(fp_rect
			(start 0.508 0.9398)
			(end -0.508 -0.9398)
			(stroke
				(width 0)
				(type default)
			)
			(fill no)
			(layer "B.CrtYd")
		)
		(fp_rect
			(start 0.508 0.9398)
			(end -0.508 -0.9398)
			(stroke
				(width 0)
				(type default)
			)
			(fill no)
			(layer "B.Fab")
		)
		(pad "1" smd custom
			(at 0 -0.4445 270)
			(size 0.1397 0.1397)
			(layers "B.Cu" "B.Mask" "B.Paste")
			(net "P12V_STBY_SCC")
			(options
				(clearance outline)
				(anchor circle)
			)
			(primitives
				(gr_poly
					(pts
						(arc
							(start -0.1778 0.2794)
							(mid -0.249642 0.249642)
							(end -0.2794 0.1778)
						)
						(arc
							(start -0.2794 -0.1778)
							(mid -0.249642 -0.249642)
							(end -0.1778 -0.2794)
						)
						(arc
							(start 0.1778 -0.2794)
							(mid 0.249642 -0.249642)
							(end 0.2794 -0.1778)
						)
						(arc
							(start 0.2794 0.1778)
							(mid 0.249642 0.249642)
							(end 0.1778 0.2794)
						)
					)
					(width 0)
					(fill yes)
				)
			)
		)
		(pad "2" smd custom
			(at 0 0.4445 270)
			(size 0.1397 0.1397)
			(layers "B.Cu" "B.Mask" "B.Paste")
			(net "P3V3_STBY_Q15_R")
			(options
				(clearance outline)
				(anchor circle)
			)
			(primitives
				(gr_poly
					(pts
						(arc
							(start -0.1778 0.2794)
							(mid -0.249642 0.249642)
							(end -0.2794 0.1778)
						)
						(arc
							(start -0.2794 -0.1778)
							(mid -0.249642 -0.249642)
							(end -0.1778 -0.2794)
						)
						(arc
							(start 0.1778 -0.2794)
							(mid 0.249642 -0.249642)
							(end 0.2794 -0.1778)
						)
						(arc
							(start 0.2794 0.1778)
							(mid 0.249642 0.249642)
							(end 0.1778 0.2794)
						)
					)
					(width 0)
					(fill yes)
				)
			)
		)
	)
	(footprint ""
		(layer "B.Cu")
		(at 174.323248 -121.976134 90)
		(property "Reference" "C600"
			(at 0 0 90)
			(layer "B.SilkS")
			(hide yes)
			(effects
				(font
					(size 1.27 1.27)
				)
				(justify mirror)
			)
		)
		(property "Value" "SCD1U16V2KX-3GP"
			(at -1.1811 -2.7051 90)
			(unlocked yes)
			(layer "B.Fab")
			(hide yes)
			(effects
				(font
					(size 1.016 1.016)
					(thickness 0.1524)
				)
				(justify mirror)
			)
		)
		(property "Device Type" "C402H22"
			(at -1.1811 -4.2291 90)
			(unlocked yes)
			(layer "B.Fab")
			(hide yes)
			(effects
				(font
					(size 1.016 1.016)
					(thickness 0.1524)
				)
				(justify mirror)
			)
		)
		(duplicate_pad_numbers_are_jumpers no)
		(fp_rect
			(start 0.4318 0.9525)
			(end -0.4318 -0.9525)
			(stroke
				(width 0)
				(type default)
			)
			(fill no)
			(layer "B.CrtYd")
		)
		(fp_rect
			(start 0.4318 0.9525)
			(end -0.4318 -0.9525)
			(stroke
				(width 0)
				(type default)
			)
			(fill no)
			(layer "B.Fab")
		)
		(pad "1" smd custom
			(at 0 -0.4445 270)
			(size 0.1524 0.1524)
			(layers "B.Cu" "B.Mask" "B.Paste")
			(net "P3V3")
			(options
				(clearance outline)
				(anchor circle)
			)
			(primitives
				(gr_poly
					(pts
						(arc
							(start 0.3048 0.2032)
							(mid 0.275042 0.275042)
							(end 0.2032 0.3048)
						)
						(arc
							(start -0.2032 0.3048)
							(mid -0.275042 0.275042)
							(end -0.3048 0.2032)
						)
						(arc
							(start -0.3048 -0.2032)
							(mid -0.275042 -0.275042)
							(end -0.2032 -0.3048)
						)
						(arc
							(start 0.2032 -0.3048)
							(mid 0.275042 -0.275042)
							(end 0.3048 -0.2032)
						)
					)
					(width 0)
					(fill yes)
				)
			)
		)
		(pad "2" smd custom
			(at 0 0.4445 270)
			(size 0.1524 0.1524)
			(layers "B.Cu" "B.Mask" "B.Paste")
			(net "GND")
			(options
				(clearance outline)
				(anchor circle)
			)
			(primitives
				(gr_poly
					(pts
						(arc
							(start 0.3048 0.2032)
							(mid 0.275042 0.275042)
							(end 0.2032 0.3048)
						)
						(arc
							(start -0.2032 0.3048)
							(mid -0.275042 0.275042)
							(end -0.3048 0.2032)
						)
						(arc
							(start -0.3048 -0.2032)
							(mid -0.275042 -0.275042)
							(end -0.2032 -0.3048)
						)
						(arc
							(start 0.2032 -0.3048)
							(mid 0.275042 -0.275042)
							(end 0.3048 -0.2032)
						)
					)
					(width 0)
					(fill yes)
				)
			)
		)
	)
	(footprint ""
		(layer "B.Cu")
		(at 118.753636 -64.516)
		(property "Reference" "C186"
			(at 0 0 0)
			(layer "B.SilkS")
			(hide yes)
			(effects
				(font
					(size 1.27 1.27)
				)
				(justify mirror)
			)
		)
		(property "Value" "SC10U6D3V2MX-GP-U"
			(at 1.524 -1.905 0)
			(unlocked yes)
			(layer "B.Fab")
			(hide yes)
			(effects
				(font
					(size 1.016 1.016)
					(thickness 0.1524)
				)
				(justify mirror)
			)
		)
		(property "Device Type" "C402-TO0D2H28"
			(at 1.524 -3.429 0)
			(unlocked yes)
			(layer "B.Fab")
			(hide yes)
			(effects
				(font
					(size 1.016 1.016)
					(thickness 0.1524)
				)
				(justify mirror)
			)
		)
		(duplicate_pad_numbers_are_jumpers no)
		(fp_rect
			(start 0.4826 0.889)
			(end -0.4826 -0.889)
			(stroke
				(width 0)
				(type default)
			)
			(fill no)
			(layer "B.CrtYd")
		)
		(fp_rect
			(start 0.4826 0.889)
			(end -0.4826 -0.889)
			(stroke
				(width 0)
				(type default)
			)
			(fill no)
			(layer "B.Fab")
		)
		(pad "1" smd custom
			(at 0 -0.4572 180)
			(size 0.1524 0.1524)
			(layers "B.Cu" "B.Mask" "B.Paste")
			(net "P0V9")
			(options
				(clearance outline)
				(anchor circle)
			)
			(primitives
				(gr_poly
					(pts
						(arc
							(start -0.254 -0.3048)
							(mid -0.325842 -0.275042)
							(end -0.3556 -0.2032)
						)
						(arc
							(start -0.3556 0.2032)
							(mid -0.325842 0.275042)
							(end -0.254 0.3048)
						)
						(arc
							(start 0.254 0.3048)
							(mid 0.325842 0.275042)
							(end 0.3556 0.2032)
						)
						(arc
							(start 0.3556 -0.2032)
							(mid 0.325842 -0.275042)
							(end 0.254 -0.3048)
						)
					)
					(width 0)
					(fill yes)
				)
			)
		)
		(pad "2" smd custom
			(at 0 0.4572 180)
			(size 0.1524 0.1524)
			(layers "B.Cu" "B.Mask" "B.Paste")
			(net "GND")
			(options
				(clearance outline)
				(anchor circle)
			)
			(primitives
				(gr_poly
					(pts
						(arc
							(start -0.254 -0.3048)
							(mid -0.325842 -0.275042)
							(end -0.3556 -0.2032)
						)
						(arc
							(start -0.3556 0.2032)
							(mid -0.325842 0.275042)
							(end -0.254 0.3048)
						)
						(arc
							(start 0.254 0.3048)
							(mid 0.325842 0.275042)
							(end 0.3556 0.2032)
						)
						(arc
							(start 0.3556 -0.2032)
							(mid 0.325842 -0.275042)
							(end 0.254 -0.3048)
						)
					)
					(width 0)
					(fill yes)
				)
			)
		)
	)
	(footprint ""
		(layer "B.Cu")
		(at 96.647 -44.2214 180)
		(property "Reference" "C89"
			(at 0 0 0)
			(layer "B.SilkS")
			(hide yes)
			(effects
				(font
					(size 1.27 1.27)
				)
				(justify mirror)
			)
		)
		(property "Value" "SCD01U16V1KX-GP"
			(at 2.8321 -1.7399 180)
			(unlocked yes)
			(layer "B.Fab")
			(hide yes)
			(effects
				(font
					(size 1.016 1.016)
					(thickness 0.1524)
				)
				(justify mirror)
			)
		)
		(property "Device Type" "C0201H13"
			(at 2.8321 -3.2639 180)
			(unlocked yes)
			(layer "B.Fab")
			(hide yes)
			(effects
				(font
					(size 1.016 1.016)
					(thickness 0.1524)
				)
				(justify mirror)
			)
		)
		(duplicate_pad_numbers_are_jumpers no)
		(fp_rect
			(start 0.2794 0.6477)
			(end -0.2794 -0.6477)
			(stroke
				(width 0)
				(type default)
			)
			(fill no)
			(layer "B.CrtYd")
		)
		(fp_rect
			(start 0.2794 0.6477)
			(end -0.2794 -0.6477)
			(stroke
				(width 0)
				(type default)
			)
			(fill no)
			(layer "B.Fab")
		)
		(pad "1" smd custom
			(at 0 -0.2794)
			(size 0.0762 0.0762)
			(layers "B.Cu" "B.Mask" "B.Paste")
			(net "PHY_DPB_TO_SCC_16_DN")
			(options
				(clearance outline)
				(anchor circle)
			)
			(primitives
				(gr_poly
					(pts
						(arc
							(start 0.1524 0.127)
							(mid 0.137521 0.162921)
							(end 0.1016 0.1778)
						)
						(arc
							(start -0.1016 0.1778)
							(mid -0.137521 0.162921)
							(end -0.1524 0.127)
						)
						(arc
							(start -0.1524 -0.127)
							(mid -0.137521 -0.162921)
							(end -0.1016 -0.1778)
						)
						(arc
							(start 0.1016 -0.1778)
							(mid 0.137521 -0.162921)
							(end 0.1524 -0.127)
						)
					)
					(width 0)
					(fill yes)
				)
			)
		)
		(pad "2" smd custom
			(at 0 0.2794)
			(size 0.0762 0.0762)
			(layers "B.Cu" "B.Mask" "B.Paste")
			(net "PHY_DPB_TO_SCC_C_16_DN")
			(options
				(clearance outline)
				(anchor circle)
			)
			(primitives
				(gr_poly
					(pts
						(arc
							(start 0.1524 0.127)
							(mid 0.137521 0.162921)
							(end 0.1016 0.1778)
						)
						(arc
							(start -0.1016 0.1778)
							(mid -0.137521 0.162921)
							(end -0.1524 0.127)
						)
						(arc
							(start -0.1524 -0.127)
							(mid -0.137521 -0.162921)
							(end -0.1016 -0.1778)
						)
						(arc
							(start 0.1016 -0.1778)
							(mid 0.137521 -0.162921)
							(end 0.1524 -0.127)
						)
					)
					(width 0)
					(fill yes)
				)
			)
		)
	)
	(footprint ""
		(layer "B.Cu")
		(at 173.659292 -35.56127)
		(property "Reference" "C438"
			(at 0 0 0)
			(layer "B.SilkS")
			(hide yes)
			(effects
				(font
					(size 1.27 1.27)
				)
				(justify mirror)
			)
		)
		(property "Value" "SCD1U6D3V1KX-GP"
			(at 2.8321 -1.7399 0)
			(unlocked yes)
			(layer "B.Fab")
			(hide yes)
			(effects
				(font
					(size 1.016 1.016)
					(thickness 0.1524)
				)
				(justify mirror)
			)
		)
		(property "Device Type" "C0201H13"
			(at 2.8321 -3.2639 0)
			(unlocked yes)
			(layer "B.Fab")
			(hide yes)
			(effects
				(font
					(size 1.016 1.016)
					(thickness 0.1524)
				)
				(justify mirror)
			)
		)
		(duplicate_pad_numbers_are_jumpers no)
		(fp_rect
			(start 0.2794 0.6477)
			(end -0.2794 -0.6477)
			(stroke
				(width 0)
				(type default)
			)
			(fill no)
			(layer "B.CrtYd")
		)
		(fp_rect
			(start 0.2794 0.6477)
			(end -0.2794 -0.6477)
			(stroke
				(width 0)
				(type default)
			)
			(fill no)
			(layer "B.Fab")
		)
		(pad "1" smd custom
			(at 0 -0.2794 180)
			(size 0.0762 0.0762)
			(layers "B.Cu" "B.Mask" "B.Paste")
			(net "P0V975")
			(options
				(clearance outline)
				(anchor circle)
			)
			(primitives
				(gr_poly
					(pts
						(arc
							(start 0.1524 0.127)
							(mid 0.137521 0.162921)
							(end 0.1016 0.1778)
						)
						(arc
							(start -0.1016 0.1778)
							(mid -0.137521 0.162921)
							(end -0.1524 0.127)
						)
						(arc
							(start -0.1524 -0.127)
							(mid -0.137521 -0.162921)
							(end -0.1016 -0.1778)
						)
						(arc
							(start 0.1016 -0.1778)
							(mid 0.137521 -0.162921)
							(end 0.1524 -0.127)
						)
					)
					(width 0)
					(fill yes)
				)
			)
		)
		(pad "2" smd custom
			(at 0 0.2794 180)
			(size 0.0762 0.0762)
			(layers "B.Cu" "B.Mask" "B.Paste")
			(net "GND")
			(options
				(clearance outline)
				(anchor circle)
			)
			(primitives
				(gr_poly
					(pts
						(arc
							(start 0.1524 0.127)
							(mid 0.137521 0.162921)
							(end 0.1016 0.1778)
						)
						(arc
							(start -0.1016 0.1778)
							(mid -0.137521 0.162921)
							(end -0.1524 0.127)
						)
						(arc
							(start -0.1524 -0.127)
							(mid -0.137521 -0.162921)
							(end -0.1016 -0.1778)
						)
						(arc
							(start 0.1016 -0.1778)
							(mid 0.137521 -0.162921)
							(end 0.1524 -0.127)
						)
					)
					(width 0)
					(fill yes)
				)
			)
		)
	)
	(footprint ""
		(layer "B.Cu")
		(at 112.7506 -59.4487)
		(property "Reference" "C247"
			(at 0 0 0)
			(layer "B.SilkS")
			(hide yes)
			(effects
				(font
					(size 1.27 1.27)
				)
				(justify mirror)
			)
		)
		(property "Value" "SCD1U6D3V1KX-GP"
			(at 2.8321 -1.7399 0)
			(unlocked yes)
			(layer "B.Fab")
			(hide yes)
			(effects
				(font
					(size 1.016 1.016)
					(thickness 0.1524)
				)
				(justify mirror)
			)
		)
		(property "Device Type" "C0201H13"
			(at 2.8321 -3.2639 0)
			(unlocked yes)
			(layer "B.Fab")
			(hide yes)
			(effects
				(font
					(size 1.016 1.016)
					(thickness 0.1524)
				)
				(justify mirror)
			)
		)
		(duplicate_pad_numbers_are_jumpers no)
		(fp_rect
			(start 0.2794 0.6477)
			(end -0.2794 -0.6477)
			(stroke
				(width 0)
				(type default)
			)
			(fill no)
			(layer "B.CrtYd")
		)
		(fp_rect
			(start 0.2794 0.6477)
			(end -0.2794 -0.6477)
			(stroke
				(width 0)
				(type default)
			)
			(fill no)
			(layer "B.Fab")
		)
		(pad "1" smd custom
			(at 0 -0.2794 180)
			(size 0.0762 0.0762)
			(layers "B.Cu" "B.Mask" "B.Paste")
			(net "GB_VDDA")
			(options
				(clearance outline)
				(anchor circle)
			)
			(primitives
				(gr_poly
					(pts
						(arc
							(start 0.1524 0.127)
							(mid 0.137521 0.162921)
							(end 0.1016 0.1778)
						)
						(arc
							(start -0.1016 0.1778)
							(mid -0.137521 0.162921)
							(end -0.1524 0.127)
						)
						(arc
							(start -0.1524 -0.127)
							(mid -0.137521 -0.162921)
							(end -0.1016 -0.1778)
						)
						(arc
							(start 0.1016 -0.1778)
							(mid 0.137521 -0.162921)
							(end 0.1524 -0.127)
						)
					)
					(width 0)
					(fill yes)
				)
			)
		)
		(pad "2" smd custom
			(at 0 0.2794 180)
			(size 0.0762 0.0762)
			(layers "B.Cu" "B.Mask" "B.Paste")
			(net "GND")
			(options
				(clearance outline)
				(anchor circle)
			)
			(primitives
				(gr_poly
					(pts
						(arc
							(start 0.1524 0.127)
							(mid 0.137521 0.162921)
							(end 0.1016 0.1778)
						)
						(arc
							(start -0.1016 0.1778)
							(mid -0.137521 0.162921)
							(end -0.1524 0.127)
						)
						(arc
							(start -0.1524 -0.127)
							(mid -0.137521 -0.162921)
							(end -0.1016 -0.1778)
						)
						(arc
							(start 0.1016 -0.1778)
							(mid 0.137521 -0.162921)
							(end 0.1524 -0.127)
						)
					)
					(width 0)
					(fill yes)
				)
			)
		)
	)
	(footprint ""
		(layer "B.Cu")
		(at 201.803 -35.3314)
		(property "Reference" "R201"
			(at 0 0 0)
			(layer "B.SilkS")
			(hide yes)
			(effects
				(font
					(size 1.27 1.27)
				)
				(justify mirror)
			)
		)
		(property "Value" "4K7R2F-GP"
			(at -0.064008 -3.993896 0)
			(unlocked yes)
			(layer "B.Fab")
			(hide yes)
			(effects
				(font
					(size 1.016 1.016)
					(thickness 0.1524)
				)
				(justify mirror)
			)
		)
		(property "Device Type" "R402H16"
			(at -0.064008 -5.517896 0)
			(unlocked yes)
			(layer "B.Fab")
			(hide yes)
			(effects
				(font
					(size 1.016 1.016)
					(thickness 0.1524)
				)
				(justify mirror)
			)
		)
		(duplicate_pad_numbers_are_jumpers no)
		(fp_line
			(start -0.508 -0.9398)
			(end 0.508 -0.9398)
			(stroke
				(width 0.1524)
				(type default)
			)
			(layer "B.SilkS")
		)
		(fp_line
			(start 0.508 -0.9398)
			(end 0.508 0.9398)
			(stroke
				(width 0.1524)
				(type default)
			)
			(layer "B.SilkS")
		)
		(fp_rect
			(start 0.508 0.9398)
			(end -0.508 -0.9398)
			(stroke
				(width 0)
				(type default)
			)
			(fill no)
			(layer "B.CrtYd")
		)
		(fp_rect
			(start 0.508 0.9398)
			(end -0.508 -0.9398)
			(stroke
				(width 0)
				(type default)
			)
			(fill no)
			(layer "B.Fab")
		)
		(pad "1" smd custom
			(at 0 -0.4445 180)
			(size 0.1397 0.1397)
			(layers "B.Cu" "B.Mask" "B.Paste")
			(net "IOC_EEPROM_A1")
			(options
				(clearance outline)
				(anchor circle)
			)
			(primitives
				(gr_poly
					(pts
						(arc
							(start -0.1778 0.2794)
							(mid -0.249642 0.249642)
							(end -0.2794 0.1778)
						)
						(arc
							(start -0.2794 -0.1778)
							(mid -0.249642 -0.249642)
							(end -0.1778 -0.2794)
						)
						(arc
							(start 0.1778 -0.2794)
							(mid 0.249642 -0.249642)
							(end 0.2794 -0.1778)
						)
						(arc
							(start 0.2794 0.1778)
							(mid 0.249642 0.249642)
							(end 0.1778 0.2794)
						)
					)
					(width 0)
					(fill yes)
				)
			)
		)
		(pad "2" smd custom
			(at 0 0.4445 180)
			(size 0.1397 0.1397)
			(layers "B.Cu" "B.Mask" "B.Paste")
			(net "GND")
			(options
				(clearance outline)
				(anchor circle)
			)
			(primitives
				(gr_poly
					(pts
						(arc
							(start -0.1778 0.2794)
							(mid -0.249642 0.249642)
							(end -0.2794 0.1778)
						)
						(arc
							(start -0.2794 -0.1778)
							(mid -0.249642 -0.249642)
							(end -0.1778 -0.2794)
						)
						(arc
							(start 0.1778 -0.2794)
							(mid 0.249642 -0.249642)
							(end 0.2794 -0.1778)
						)
						(arc
							(start 0.2794 0.1778)
							(mid 0.249642 0.249642)
							(end 0.1778 0.2794)
						)
					)
					(width 0)
					(fill yes)
				)
			)
		)
	)
	(footprint ""
		(layer "B.Cu")
		(at 163.8173 -9.779 180)
		(property "Reference" "C735"
			(at 0 0 0)
			(layer "B.SilkS")
			(hide yes)
			(effects
				(font
					(size 1.27 1.27)
				)
				(justify mirror)
			)
		)
		(property "Value" "SCD1U16V2KX-3GP"
			(at -1.1811 -2.7051 180)
			(unlocked yes)
			(layer "B.Fab")
			(hide yes)
			(effects
				(font
					(size 1.016 1.016)
					(thickness 0.1524)
				)
				(justify mirror)
			)
		)
		(property "Device Type" "C402H22"
			(at -1.1811 -4.2291 180)
			(unlocked yes)
			(layer "B.Fab")
			(hide yes)
			(effects
				(font
					(size 1.016 1.016)
					(thickness 0.1524)
				)
				(justify mirror)
			)
		)
		(duplicate_pad_numbers_are_jumpers no)
		(fp_rect
			(start 0.4318 0.9525)
			(end -0.4318 -0.9525)
			(stroke
				(width 0)
				(type default)
			)
			(fill no)
			(layer "B.CrtYd")
		)
		(fp_rect
			(start 0.4318 0.9525)
			(end -0.4318 -0.9525)
			(stroke
				(width 0)
				(type default)
			)
			(fill no)
			(layer "B.Fab")
		)
		(pad "1" smd custom
			(at 0 -0.4445)
			(size 0.1524 0.1524)
			(layers "B.Cu" "B.Mask" "B.Paste")
			(net "P3V3")
			(options
				(clearance outline)
				(anchor circle)
			)
			(primitives
				(gr_poly
					(pts
						(arc
							(start 0.3048 0.2032)
							(mid 0.275042 0.275042)
							(end 0.2032 0.3048)
						)
						(arc
							(start -0.2032 0.3048)
							(mid -0.275042 0.275042)
							(end -0.3048 0.2032)
						)
						(arc
							(start -0.3048 -0.2032)
							(mid -0.275042 -0.275042)
							(end -0.2032 -0.3048)
						)
						(arc
							(start 0.2032 -0.3048)
							(mid 0.275042 -0.275042)
							(end 0.3048 -0.2032)
						)
					)
					(width 0)
					(fill yes)
				)
			)
		)
		(pad "2" smd custom
			(at 0 0.4445)
			(size 0.1524 0.1524)
			(layers "B.Cu" "B.Mask" "B.Paste")
			(net "GND")
			(options
				(clearance outline)
				(anchor circle)
			)
			(primitives
				(gr_poly
					(pts
						(arc
							(start 0.3048 0.2032)
							(mid 0.275042 0.275042)
							(end 0.2032 0.3048)
						)
						(arc
							(start -0.2032 0.3048)
							(mid -0.275042 0.275042)
							(end -0.3048 0.2032)
						)
						(arc
							(start -0.3048 -0.2032)
							(mid -0.275042 -0.275042)
							(end -0.2032 -0.3048)
						)
						(arc
							(start 0.2032 -0.3048)
							(mid 0.275042 -0.275042)
							(end 0.3048 -0.2032)
						)
					)
					(width 0)
					(fill yes)
				)
			)
		)
	)
	(footprint ""
		(layer "B.Cu")
		(at 112.6236 -66.3575)
		(property "Reference" "C169"
			(at 0 0 0)
			(layer "B.SilkS")
			(hide yes)
			(effects
				(font
					(size 1.27 1.27)
				)
				(justify mirror)
			)
		)
		(property "Value" "SCD1U6D3V1KX-GP"
			(at 2.8321 -1.7399 0)
			(unlocked yes)
			(layer "B.Fab")
			(hide yes)
			(effects
				(font
					(size 1.016 1.016)
					(thickness 0.1524)
				)
				(justify mirror)
			)
		)
		(property "Device Type" "C0201H13"
			(at 2.8321 -3.2639 0)
			(unlocked yes)
			(layer "B.Fab")
			(hide yes)
			(effects
				(font
					(size 1.016 1.016)
					(thickness 0.1524)
				)
				(justify mirror)
			)
		)
		(duplicate_pad_numbers_are_jumpers no)
		(fp_rect
			(start 0.2794 0.6477)
			(end -0.2794 -0.6477)
			(stroke
				(width 0)
				(type default)
			)
			(fill no)
			(layer "B.CrtYd")
		)
		(fp_rect
			(start 0.2794 0.6477)
			(end -0.2794 -0.6477)
			(stroke
				(width 0)
				(type default)
			)
			(fill no)
			(layer "B.Fab")
		)
		(pad "1" smd custom
			(at 0 -0.2794 180)
			(size 0.0762 0.0762)
			(layers "B.Cu" "B.Mask" "B.Paste")
			(net "P0V9")
			(options
				(clearance outline)
				(anchor circle)
			)
			(primitives
				(gr_poly
					(pts
						(arc
							(start 0.1524 0.127)
							(mid 0.137521 0.162921)
							(end 0.1016 0.1778)
						)
						(arc
							(start -0.1016 0.1778)
							(mid -0.137521 0.162921)
							(end -0.1524 0.127)
						)
						(arc
							(start -0.1524 -0.127)
							(mid -0.137521 -0.162921)
							(end -0.1016 -0.1778)
						)
						(arc
							(start 0.1016 -0.1778)
							(mid 0.137521 -0.162921)
							(end 0.1524 -0.127)
						)
					)
					(width 0)
					(fill yes)
				)
			)
		)
		(pad "2" smd custom
			(at 0 0.2794 180)
			(size 0.0762 0.0762)
			(layers "B.Cu" "B.Mask" "B.Paste")
			(net "GND")
			(options
				(clearance outline)
				(anchor circle)
			)
			(primitives
				(gr_poly
					(pts
						(arc
							(start 0.1524 0.127)
							(mid 0.137521 0.162921)
							(end 0.1016 0.1778)
						)
						(arc
							(start -0.1016 0.1778)
							(mid -0.137521 0.162921)
							(end -0.1524 0.127)
						)
						(arc
							(start -0.1524 -0.127)
							(mid -0.137521 -0.162921)
							(end -0.1016 -0.1778)
						)
						(arc
							(start 0.1016 -0.1778)
							(mid 0.137521 -0.162921)
							(end 0.1524 -0.127)
						)
					)
					(width 0)
					(fill yes)
				)
			)
		)
	)
	(footprint ""
		(layer "B.Cu")
		(at 170.942 -70.739)
		(property "Reference" "Q16"
			(at 0 0 0)
			(layer "B.SilkS")
			(hide yes)
			(effects
				(font
					(size 1.27 1.27)
				)
				(justify mirror)
			)
		)
		(property "Value" "SSM3K324R-GP"
			(at -0.127 -8.9662 0)
			(unlocked yes)
			(layer "B.Fab")
			(hide yes)
			(effects
				(font
					(size 1.016 1.016)
					(thickness 0.1524)
				)
				(justify mirror)
			)
		)
		(property "Device Type" "SOT23DGS2D4H35"
			(at -0.127 -10.4902 0)
			(unlocked yes)
			(layer "B.Fab")
			(hide yes)
			(effects
				(font
					(size 1.016 1.016)
					(thickness 0.1524)
				)
				(justify mirror)
			)
		)
		(duplicate_pad_numbers_are_jumpers no)
		(fp_line
			(start -1.651 -1.778)
			(end 1.651 -1.778)
			(stroke
				(width 0.1524)
				(type default)
			)
			(layer "B.SilkS")
		)
		(fp_line
			(start -1.651 1.778)
			(end -1.651 -1.778)
			(stroke
				(width 0.1524)
				(type default)
			)
			(layer "B.SilkS")
		)
		(fp_line
			(start 1.651 -1.778)
			(end 1.651 1.778)
			(stroke
				(width 0.1524)
				(type default)
			)
			(layer "B.SilkS")
		)
		(fp_line
			(start 1.651 1.778)
			(end -1.651 1.778)
			(stroke
				(width 0.1524)
				(type default)
			)
			(layer "B.SilkS")
		)
		(fp_poly
			(pts
				(xy 1.778 1.8796) (xy 1.778 -1.8796) (xy -1.778 -1.8796) (xy -1.778 1.8796)
			)
			(stroke
				(width 0)
				(type default)
			)
			(fill no)
			(layer "B.CrtYd")
		)
		(fp_poly
			(pts
				(xy 1.778 1.8796) (xy 1.778 -1.8796) (xy -1.778 -1.8796) (xy -1.778 1.8796)
			)
			(stroke
				(width 0)
				(type default)
			)
			(fill no)
			(layer "B.Fab")
		)
		(pad "D" smd custom
			(at 0 -0.9525 180)
			(size 0.1905 0.1905)
			(layers "B.Cu" "B.Mask" "B.Paste")
			(net "P3V3_STBY_Q15_R")
			(options
				(clearance outline)
				(anchor circle)
			)
			(primitives
				(gr_poly
					(pts
						(arc
							(start -0.1778 -0.5715)
							(mid -0.321484 -0.511984)
							(end -0.381 -0.3683)
						)
						(arc
							(start -0.381 0.3683)
							(mid -0.321484 0.511984)
							(end -0.1778 0.5715)
						)
						(arc
							(start 0.1778 0.5715)
							(mid 0.321484 0.511984)
							(end 0.381 0.3683)
						)
						(arc
							(start 0.381 -0.3683)
							(mid 0.321484 -0.511984)
							(end 0.1778 -0.5715)
						)
					)
					(width 0)
					(fill yes)
				)
			)
		)
		(pad "G" smd custom
			(at 0.98425 0.9525 180)
			(size 0.1905 0.1905)
			(layers "B.Cu" "B.Mask" "B.Paste")
			(net "IOC_VREF_SET")
			(options
				(clearance outline)
				(anchor circle)
			)
			(primitives
				(gr_poly
					(pts
						(arc
							(start -0.1778 -0.5715)
							(mid -0.321484 -0.511984)
							(end -0.381 -0.3683)
						)
						(arc
							(start -0.381 0.3683)
							(mid -0.321484 0.511984)
							(end -0.1778 0.5715)
						)
						(arc
							(start 0.1778 0.5715)
							(mid 0.321484 0.511984)
							(end 0.381 0.3683)
						)
						(arc
							(start 0.381 -0.3683)
							(mid 0.321484 -0.511984)
							(end 0.1778 -0.5715)
						)
					)
					(width 0)
					(fill yes)
				)
			)
		)
		(pad "S" smd custom
			(at -0.98425 0.9525 180)
			(size 0.1905 0.1905)
			(layers "B.Cu" "B.Mask" "B.Paste")
			(net "GND")
			(options
				(clearance outline)
				(anchor circle)
			)
			(primitives
				(gr_poly
					(pts
						(arc
							(start -0.1778 -0.5715)
							(mid -0.321484 -0.511984)
							(end -0.381 -0.3683)
						)
						(arc
							(start -0.381 0.3683)
							(mid -0.321484 0.511984)
							(end -0.1778 0.5715)
						)
						(arc
							(start 0.1778 0.5715)
							(mid 0.321484 0.511984)
							(end 0.381 0.3683)
						)
						(arc
							(start 0.381 -0.3683)
							(mid 0.321484 -0.511984)
							(end 0.1778 -0.5715)
						)
					)
					(width 0)
					(fill yes)
				)
			)
		)
	)
	(footprint ""
		(layer "B.Cu")
		(at 137.4648 -72.4408 -90)
		(property "Reference" "C12"
			(at 0 0 90)
			(layer "B.SilkS")
			(hide yes)
			(effects
				(font
					(size 1.27 1.27)
				)
				(justify mirror)
			)
		)
		(property "Value" "SCD01U16V1KX-GP"
			(at 2.8321 -1.7399 270)
			(unlocked yes)
			(layer "B.Fab")
			(hide yes)
			(effects
				(font
					(size 1.016 1.016)
					(thickness 0.1524)
				)
				(justify mirror)
			)
		)
		(property "Device Type" "C0201H13"
			(at 2.8321 -3.2639 270)
			(unlocked yes)
			(layer "B.Fab")
			(hide yes)
			(effects
				(font
					(size 1.016 1.016)
					(thickness 0.1524)
				)
				(justify mirror)
			)
		)
		(duplicate_pad_numbers_are_jumpers no)
		(fp_rect
			(start 0.2794 0.6477)
			(end -0.2794 -0.6477)
			(stroke
				(width 0)
				(type default)
			)
			(fill no)
			(layer "B.CrtYd")
		)
		(fp_rect
			(start 0.2794 0.6477)
			(end -0.2794 -0.6477)
			(stroke
				(width 0)
				(type default)
			)
			(fill no)
			(layer "B.Fab")
		)
		(pad "1" smd custom
			(at 0 -0.2794 90)
			(size 0.0762 0.0762)
			(layers "B.Cu" "B.Mask" "B.Paste")
			(net "PHY_DPB_TO_SCC_6_DN")
			(options
				(clearance outline)
				(anchor circle)
			)
			(primitives
				(gr_poly
					(pts
						(arc
							(start 0.1524 0.127)
							(mid 0.137521 0.162921)
							(end 0.1016 0.1778)
						)
						(arc
							(start -0.1016 0.1778)
							(mid -0.137521 0.162921)
							(end -0.1524 0.127)
						)
						(arc
							(start -0.1524 -0.127)
							(mid -0.137521 -0.162921)
							(end -0.1016 -0.1778)
						)
						(arc
							(start 0.1016 -0.1778)
							(mid 0.137521 -0.162921)
							(end 0.1524 -0.127)
						)
					)
					(width 0)
					(fill yes)
				)
			)
		)
		(pad "2" smd custom
			(at 0 0.2794 90)
			(size 0.0762 0.0762)
			(layers "B.Cu" "B.Mask" "B.Paste")
			(net "PHY_DPB_TO_SCC_C_6_DN")
			(options
				(clearance outline)
				(anchor circle)
			)
			(primitives
				(gr_poly
					(pts
						(arc
							(start 0.1524 0.127)
							(mid 0.137521 0.162921)
							(end 0.1016 0.1778)
						)
						(arc
							(start -0.1016 0.1778)
							(mid -0.137521 0.162921)
							(end -0.1524 0.127)
						)
						(arc
							(start -0.1524 -0.127)
							(mid -0.137521 -0.162921)
							(end -0.1016 -0.1778)
						)
						(arc
							(start 0.1016 -0.1778)
							(mid 0.137521 -0.162921)
							(end 0.1524 -0.127)
						)
					)
					(width 0)
					(fill yes)
				)
			)
		)
	)
	(footprint ""
		(layer "B.Cu")
		(at 133.2738 -44.3992 180)
		(property "Reference" "C28"
			(at 0 0 0)
			(layer "B.SilkS")
			(hide yes)
			(effects
				(font
					(size 1.27 1.27)
				)
				(justify mirror)
			)
		)
		(property "Value" "SCD01U16V1KX-GP"
			(at 2.8321 -1.7399 180)
			(unlocked yes)
			(layer "B.Fab")
			(hide yes)
			(effects
				(font
					(size 1.016 1.016)
					(thickness 0.1524)
				)
				(justify mirror)
			)
		)
		(property "Device Type" "C0201H13"
			(at 2.8321 -3.2639 180)
			(unlocked yes)
			(layer "B.Fab")
			(hide yes)
			(effects
				(font
					(size 1.016 1.016)
					(thickness 0.1524)
				)
				(justify mirror)
			)
		)
		(duplicate_pad_numbers_are_jumpers no)
		(fp_rect
			(start 0.2794 0.6477)
			(end -0.2794 -0.6477)
			(stroke
				(width 0)
				(type default)
			)
			(fill no)
			(layer "B.CrtYd")
		)
		(fp_rect
			(start 0.2794 0.6477)
			(end -0.2794 -0.6477)
			(stroke
				(width 0)
				(type default)
			)
			(fill no)
			(layer "B.Fab")
		)
		(pad "1" smd custom
			(at 0 -0.2794)
			(size 0.0762 0.0762)
			(layers "B.Cu" "B.Mask" "B.Paste")
			(net "PHY_DPB_TO_SCC_30_DN")
			(options
				(clearance outline)
				(anchor circle)
			)
			(primitives
				(gr_poly
					(pts
						(arc
							(start 0.1524 0.127)
							(mid 0.137521 0.162921)
							(end 0.1016 0.1778)
						)
						(arc
							(start -0.1016 0.1778)
							(mid -0.137521 0.162921)
							(end -0.1524 0.127)
						)
						(arc
							(start -0.1524 -0.127)
							(mid -0.137521 -0.162921)
							(end -0.1016 -0.1778)
						)
						(arc
							(start 0.1016 -0.1778)
							(mid 0.137521 -0.162921)
							(end 0.1524 -0.127)
						)
					)
					(width 0)
					(fill yes)
				)
			)
		)
		(pad "2" smd custom
			(at 0 0.2794)
			(size 0.0762 0.0762)
			(layers "B.Cu" "B.Mask" "B.Paste")
			(net "PHY_DPB_TO_SCC_C_30_DN")
			(options
				(clearance outline)
				(anchor circle)
			)
			(primitives
				(gr_poly
					(pts
						(arc
							(start 0.1524 0.127)
							(mid 0.137521 0.162921)
							(end 0.1016 0.1778)
						)
						(arc
							(start -0.1016 0.1778)
							(mid -0.137521 0.162921)
							(end -0.1524 0.127)
						)
						(arc
							(start -0.1524 -0.127)
							(mid -0.137521 -0.162921)
							(end -0.1016 -0.1778)
						)
						(arc
							(start 0.1016 -0.1778)
							(mid 0.137521 -0.162921)
							(end 0.1524 -0.127)
						)
					)
					(width 0)
					(fill yes)
				)
			)
		)
	)
	(footprint ""
		(layer "B.Cu")
		(at 170.484038 -32.785304 90)
		(property "Reference" "C393"
			(at 0 0 90)
			(layer "B.SilkS")
			(hide yes)
			(effects
				(font
					(size 1.27 1.27)
				)
				(justify mirror)
			)
		)
		(property "Value" "SCD1U6D3V1KX-GP"
			(at 2.8321 -1.7399 90)
			(unlocked yes)
			(layer "B.Fab")
			(hide yes)
			(effects
				(font
					(size 1.016 1.016)
					(thickness 0.1524)
				)
				(justify mirror)
			)
		)
		(property "Device Type" "C0201H13"
			(at 2.8321 -3.2639 90)
			(unlocked yes)
			(layer "B.Fab")
			(hide yes)
			(effects
				(font
					(size 1.016 1.016)
					(thickness 0.1524)
				)
				(justify mirror)
			)
		)
		(duplicate_pad_numbers_are_jumpers no)
		(fp_rect
			(start 0.2794 0.6477)
			(end -0.2794 -0.6477)
			(stroke
				(width 0)
				(type default)
			)
			(fill no)
			(layer "B.CrtYd")
		)
		(fp_rect
			(start 0.2794 0.6477)
			(end -0.2794 -0.6477)
			(stroke
				(width 0)
				(type default)
			)
			(fill no)
			(layer "B.Fab")
		)
		(pad "1" smd custom
			(at 0 -0.2794 270)
			(size 0.0762 0.0762)
			(layers "B.Cu" "B.Mask" "B.Paste")
			(net "PCE_AVDD")
			(options
				(clearance outline)
				(anchor circle)
			)
			(primitives
				(gr_poly
					(pts
						(arc
							(start 0.1524 0.127)
							(mid 0.137521 0.162921)
							(end 0.1016 0.1778)
						)
						(arc
							(start -0.1016 0.1778)
							(mid -0.137521 0.162921)
							(end -0.1524 0.127)
						)
						(arc
							(start -0.1524 -0.127)
							(mid -0.137521 -0.162921)
							(end -0.1016 -0.1778)
						)
						(arc
							(start 0.1016 -0.1778)
							(mid 0.137521 -0.162921)
							(end 0.1524 -0.127)
						)
					)
					(width 0)
					(fill yes)
				)
			)
		)
		(pad "2" smd custom
			(at 0 0.2794 270)
			(size 0.0762 0.0762)
			(layers "B.Cu" "B.Mask" "B.Paste")
			(net "GND")
			(options
				(clearance outline)
				(anchor circle)
			)
			(primitives
				(gr_poly
					(pts
						(arc
							(start 0.1524 0.127)
							(mid 0.137521 0.162921)
							(end 0.1016 0.1778)
						)
						(arc
							(start -0.1016 0.1778)
							(mid -0.137521 0.162921)
							(end -0.1524 0.127)
						)
						(arc
							(start -0.1524 -0.127)
							(mid -0.137521 -0.162921)
							(end -0.1016 -0.1778)
						)
						(arc
							(start 0.1016 -0.1778)
							(mid 0.137521 -0.162921)
							(end 0.1524 -0.127)
						)
					)
					(width 0)
					(fill yes)
				)
			)
		)
	)
	(footprint ""
		(layer "B.Cu")
		(at 153.803604 -66.916808 180)
		(property "Reference" "L20"
			(at 0 0 0)
			(layer "B.SilkS")
			(hide yes)
			(effects
				(font
					(size 1.27 1.27)
				)
				(justify mirror)
			)
		)
		(property "Value" "MPZ2012S601AT-GP"
			(at 0 -4.2418 180)
			(unlocked yes)
			(layer "B.Fab")
			(hide yes)
			(effects
				(font
					(size 1.016 1.016)
					(thickness 0.1524)
				)
				(justify mirror)
			)
		)
		(property "Device Type" "L805H42"
			(at 0 -5.7912 180)
			(unlocked yes)
			(layer "B.Fab")
			(hide yes)
			(effects
				(font
					(size 1.016 1.016)
					(thickness 0.1524)
				)
				(justify mirror)
			)
		)
		(duplicate_pad_numbers_are_jumpers no)
		(fp_line
			(start 0.889 1.7018)
			(end 0.889 -1.7018)
			(stroke
				(width 0.1524)
				(type default)
			)
			(layer "B.SilkS")
		)
		(fp_line
			(start 0.889 -1.7018)
			(end -0.889 -1.7018)
			(stroke
				(width 0.1524)
				(type default)
			)
			(layer "B.SilkS")
		)
		(fp_line
			(start -0.889 1.7018)
			(end 0.889 1.7018)
			(stroke
				(width 0.1524)
				(type default)
			)
			(layer "B.SilkS")
		)
		(fp_line
			(start -0.889 -1.7018)
			(end -0.889 1.7018)
			(stroke
				(width 0.1524)
				(type default)
			)
			(layer "B.SilkS")
		)
		(fp_rect
			(start 0.9652 1.778)
			(end -0.9652 -1.778)
			(stroke
				(width 0)
				(type default)
			)
			(fill no)
			(layer "B.CrtYd")
		)
		(fp_rect
			(start 0.9652 1.778)
			(end -0.9652 -1.778)
			(stroke
				(width 0)
				(type default)
			)
			(fill no)
			(layer "B.Fab")
		)
		(pad "1" smd rect
			(at 0 -0.9652)
			(size 1.397 1.143)
			(layers "B.Cu" "B.Mask" "B.Paste")
			(net "SYS_PLL_VDD")
		)
		(pad "2" smd rect
			(at 0 0.9652)
			(size 1.397 1.143)
			(layers "B.Cu" "B.Mask" "B.Paste")
			(net "P1V8_C")
		)
	)
	(footprint ""
		(layer "B.Cu")
		(at 137.4648 -71.4502 -90)
		(property "Reference" "C13"
			(at 0 0 90)
			(layer "B.SilkS")
			(hide yes)
			(effects
				(font
					(size 1.27 1.27)
				)
				(justify mirror)
			)
		)
		(property "Value" "SCD01U16V1KX-GP"
			(at 2.8321 -1.7399 270)
			(unlocked yes)
			(layer "B.Fab")
			(hide yes)
			(effects
				(font
					(size 1.016 1.016)
					(thickness 0.1524)
				)
				(justify mirror)
			)
		)
		(property "Device Type" "C0201H13"
			(at 2.8321 -3.2639 270)
			(unlocked yes)
			(layer "B.Fab")
			(hide yes)
			(effects
				(font
					(size 1.016 1.016)
					(thickness 0.1524)
				)
				(justify mirror)
			)
		)
		(duplicate_pad_numbers_are_jumpers no)
		(fp_rect
			(start 0.2794 0.6477)
			(end -0.2794 -0.6477)
			(stroke
				(width 0)
				(type default)
			)
			(fill no)
			(layer "B.CrtYd")
		)
		(fp_rect
			(start 0.2794 0.6477)
			(end -0.2794 -0.6477)
			(stroke
				(width 0)
				(type default)
			)
			(fill no)
			(layer "B.Fab")
		)
		(pad "1" smd custom
			(at 0 -0.2794 90)
			(size 0.0762 0.0762)
			(layers "B.Cu" "B.Mask" "B.Paste")
			(net "PHY_DPB_TO_SCC_5_DP")
			(options
				(clearance outline)
				(anchor circle)
			)
			(primitives
				(gr_poly
					(pts
						(arc
							(start 0.1524 0.127)
							(mid 0.137521 0.162921)
							(end 0.1016 0.1778)
						)
						(arc
							(start -0.1016 0.1778)
							(mid -0.137521 0.162921)
							(end -0.1524 0.127)
						)
						(arc
							(start -0.1524 -0.127)
							(mid -0.137521 -0.162921)
							(end -0.1016 -0.1778)
						)
						(arc
							(start 0.1016 -0.1778)
							(mid 0.137521 -0.162921)
							(end 0.1524 -0.127)
						)
					)
					(width 0)
					(fill yes)
				)
			)
		)
		(pad "2" smd custom
			(at 0 0.2794 90)
			(size 0.0762 0.0762)
			(layers "B.Cu" "B.Mask" "B.Paste")
			(net "PHY_DPB_TO_SCC_C_5_DP")
			(options
				(clearance outline)
				(anchor circle)
			)
			(primitives
				(gr_poly
					(pts
						(arc
							(start 0.1524 0.127)
							(mid 0.137521 0.162921)
							(end 0.1016 0.1778)
						)
						(arc
							(start -0.1016 0.1778)
							(mid -0.137521 0.162921)
							(end -0.1524 0.127)
						)
						(arc
							(start -0.1524 -0.127)
							(mid -0.137521 -0.162921)
							(end -0.1016 -0.1778)
						)
						(arc
							(start 0.1016 -0.1778)
							(mid 0.137521 -0.162921)
							(end 0.1524 -0.127)
						)
					)
					(width 0)
					(fill yes)
				)
			)
		)
	)
	(footprint ""
		(layer "B.Cu")
		(at 114.935 -44.2214 180)
		(property "Reference" "C64"
			(at 0 0 0)
			(layer "B.SilkS")
			(hide yes)
			(effects
				(font
					(size 1.27 1.27)
				)
				(justify mirror)
			)
		)
		(property "Value" "SCD01U16V1KX-GP"
			(at 2.8321 -1.7399 180)
			(unlocked yes)
			(layer "B.Fab")
			(hide yes)
			(effects
				(font
					(size 1.016 1.016)
					(thickness 0.1524)
				)
				(justify mirror)
			)
		)
		(property "Device Type" "C0201H13"
			(at 2.8321 -3.2639 180)
			(unlocked yes)
			(layer "B.Fab")
			(hide yes)
			(effects
				(font
					(size 1.016 1.016)
					(thickness 0.1524)
				)
				(justify mirror)
			)
		)
		(duplicate_pad_numbers_are_jumpers no)
		(fp_rect
			(start 0.2794 0.6477)
			(end -0.2794 -0.6477)
			(stroke
				(width 0)
				(type default)
			)
			(fill no)
			(layer "B.CrtYd")
		)
		(fp_rect
			(start 0.2794 0.6477)
			(end -0.2794 -0.6477)
			(stroke
				(width 0)
				(type default)
			)
			(fill no)
			(layer "B.Fab")
		)
		(pad "1" smd custom
			(at 0 -0.2794)
			(size 0.0762 0.0762)
			(layers "B.Cu" "B.Mask" "B.Paste")
			(net "PHY_DPB_TO_SCC_32_DN")
			(options
				(clearance outline)
				(anchor circle)
			)
			(primitives
				(gr_poly
					(pts
						(arc
							(start 0.1524 0.127)
							(mid 0.137521 0.162921)
							(end 0.1016 0.1778)
						)
						(arc
							(start -0.1016 0.1778)
							(mid -0.137521 0.162921)
							(end -0.1524 0.127)
						)
						(arc
							(start -0.1524 -0.127)
							(mid -0.137521 -0.162921)
							(end -0.1016 -0.1778)
						)
						(arc
							(start 0.1016 -0.1778)
							(mid 0.137521 -0.162921)
							(end 0.1524 -0.127)
						)
					)
					(width 0)
					(fill yes)
				)
			)
		)
		(pad "2" smd custom
			(at 0 0.2794)
			(size 0.0762 0.0762)
			(layers "B.Cu" "B.Mask" "B.Paste")
			(net "PHY_DPB_TO_SCC_C_32_DN")
			(options
				(clearance outline)
				(anchor circle)
			)
			(primitives
				(gr_poly
					(pts
						(arc
							(start 0.1524 0.127)
							(mid 0.137521 0.162921)
							(end 0.1016 0.1778)
						)
						(arc
							(start -0.1016 0.1778)
							(mid -0.137521 0.162921)
							(end -0.1524 0.127)
						)
						(arc
							(start -0.1524 -0.127)
							(mid -0.137521 -0.162921)
							(end -0.1016 -0.1778)
						)
						(arc
							(start 0.1016 -0.1778)
							(mid 0.137521 -0.162921)
							(end 0.1524 -0.127)
						)
					)
					(width 0)
					(fill yes)
				)
			)
		)
	)
	(footprint ""
		(layer "B.Cu")
		(at 106.8578 -57.4802)
		(property "Reference" "C581"
			(at 0 0 0)
			(layer "B.SilkS")
			(hide yes)
			(effects
				(font
					(size 1.27 1.27)
				)
				(justify mirror)
			)
		)
		(property "Value" "SCD1U6D3V1KX-GP"
			(at 2.8321 -1.7399 0)
			(unlocked yes)
			(layer "B.Fab")
			(hide yes)
			(effects
				(font
					(size 1.016 1.016)
					(thickness 0.1524)
				)
				(justify mirror)
			)
		)
		(property "Device Type" "C0201H13"
			(at 2.8321 -3.2639 0)
			(unlocked yes)
			(layer "B.Fab")
			(hide yes)
			(effects
				(font
					(size 1.016 1.016)
					(thickness 0.1524)
				)
				(justify mirror)
			)
		)
		(duplicate_pad_numbers_are_jumpers no)
		(fp_rect
			(start 0.2794 0.6477)
			(end -0.2794 -0.6477)
			(stroke
				(width 0)
				(type default)
			)
			(fill no)
			(layer "B.CrtYd")
		)
		(fp_rect
			(start 0.2794 0.6477)
			(end -0.2794 -0.6477)
			(stroke
				(width 0)
				(type default)
			)
			(fill no)
			(layer "B.Fab")
		)
		(pad "1" smd custom
			(at 0 -0.2794 180)
			(size 0.0762 0.0762)
			(layers "B.Cu" "B.Mask" "B.Paste")
			(net "GB_VDDA")
			(options
				(clearance outline)
				(anchor circle)
			)
			(primitives
				(gr_poly
					(pts
						(arc
							(start 0.1524 0.127)
							(mid 0.137521 0.162921)
							(end 0.1016 0.1778)
						)
						(arc
							(start -0.1016 0.1778)
							(mid -0.137521 0.162921)
							(end -0.1524 0.127)
						)
						(arc
							(start -0.1524 -0.127)
							(mid -0.137521 -0.162921)
							(end -0.1016 -0.1778)
						)
						(arc
							(start 0.1016 -0.1778)
							(mid 0.137521 -0.162921)
							(end 0.1524 -0.127)
						)
					)
					(width 0)
					(fill yes)
				)
			)
		)
		(pad "2" smd custom
			(at 0 0.2794 180)
			(size 0.0762 0.0762)
			(layers "B.Cu" "B.Mask" "B.Paste")
			(net "GND")
			(options
				(clearance outline)
				(anchor circle)
			)
			(primitives
				(gr_poly
					(pts
						(arc
							(start 0.1524 0.127)
							(mid 0.137521 0.162921)
							(end 0.1016 0.1778)
						)
						(arc
							(start -0.1016 0.1778)
							(mid -0.137521 0.162921)
							(end -0.1524 0.127)
						)
						(arc
							(start -0.1524 -0.127)
							(mid -0.137521 -0.162921)
							(end -0.1016 -0.1778)
						)
						(arc
							(start 0.1016 -0.1778)
							(mid 0.137521 -0.162921)
							(end 0.1524 -0.127)
						)
					)
					(width 0)
					(fill yes)
				)
			)
		)
	)
	(footprint ""
		(layer "B.Cu")
		(at 137.4648 -66.2686 -90)
		(property "Reference" "C20"
			(at 0 0 90)
			(layer "B.SilkS")
			(hide yes)
			(effects
				(font
					(size 1.27 1.27)
				)
				(justify mirror)
			)
		)
		(property "Value" "SCD01U16V1KX-GP"
			(at 2.8321 -1.7399 270)
			(unlocked yes)
			(layer "B.Fab")
			(hide yes)
			(effects
				(font
					(size 1.016 1.016)
					(thickness 0.1524)
				)
				(justify mirror)
			)
		)
		(property "Device Type" "C0201H13"
			(at 2.8321 -3.2639 270)
			(unlocked yes)
			(layer "B.Fab")
			(hide yes)
			(effects
				(font
					(size 1.016 1.016)
					(thickness 0.1524)
				)
				(justify mirror)
			)
		)
		(duplicate_pad_numbers_are_jumpers no)
		(fp_rect
			(start 0.2794 0.6477)
			(end -0.2794 -0.6477)
			(stroke
				(width 0)
				(type default)
			)
			(fill no)
			(layer "B.CrtYd")
		)
		(fp_rect
			(start 0.2794 0.6477)
			(end -0.2794 -0.6477)
			(stroke
				(width 0)
				(type default)
			)
			(fill no)
			(layer "B.Fab")
		)
		(pad "1" smd custom
			(at 0 -0.2794 90)
			(size 0.0762 0.0762)
			(layers "B.Cu" "B.Mask" "B.Paste")
			(net "PHY_DPB_TO_SCC_2_DN")
			(options
				(clearance outline)
				(anchor circle)
			)
			(primitives
				(gr_poly
					(pts
						(arc
							(start 0.1524 0.127)
							(mid 0.137521 0.162921)
							(end 0.1016 0.1778)
						)
						(arc
							(start -0.1016 0.1778)
							(mid -0.137521 0.162921)
							(end -0.1524 0.127)
						)
						(arc
							(start -0.1524 -0.127)
							(mid -0.137521 -0.162921)
							(end -0.1016 -0.1778)
						)
						(arc
							(start 0.1016 -0.1778)
							(mid 0.137521 -0.162921)
							(end 0.1524 -0.127)
						)
					)
					(width 0)
					(fill yes)
				)
			)
		)
		(pad "2" smd custom
			(at 0 0.2794 90)
			(size 0.0762 0.0762)
			(layers "B.Cu" "B.Mask" "B.Paste")
			(net "PHY_DPB_TO_SCC_C_2_DN")
			(options
				(clearance outline)
				(anchor circle)
			)
			(primitives
				(gr_poly
					(pts
						(arc
							(start 0.1524 0.127)
							(mid 0.137521 0.162921)
							(end 0.1016 0.1778)
						)
						(arc
							(start -0.1016 0.1778)
							(mid -0.137521 0.162921)
							(end -0.1524 0.127)
						)
						(arc
							(start -0.1524 -0.127)
							(mid -0.137521 -0.162921)
							(end -0.1016 -0.1778)
						)
						(arc
							(start 0.1016 -0.1778)
							(mid 0.137521 -0.162921)
							(end 0.1524 -0.127)
						)
					)
					(width 0)
					(fill yes)
				)
			)
		)
	)
	(footprint ""
		(layer "B.Cu")
		(at 116.713 -61.488066)
		(property "Reference" "C220"
			(at 0 0 0)
			(layer "B.SilkS")
			(hide yes)
			(effects
				(font
					(size 1.27 1.27)
				)
				(justify mirror)
			)
		)
		(property "Value" "SCD1U16V2KX-3GP"
			(at -1.1811 -2.7051 0)
			(unlocked yes)
			(layer "B.Fab")
			(hide yes)
			(effects
				(font
					(size 1.016 1.016)
					(thickness 0.1524)
				)
				(justify mirror)
			)
		)
		(property "Device Type" "C402H22"
			(at -1.1811 -4.2291 0)
			(unlocked yes)
			(layer "B.Fab")
			(hide yes)
			(effects
				(font
					(size 1.016 1.016)
					(thickness 0.1524)
				)
				(justify mirror)
			)
		)
		(duplicate_pad_numbers_are_jumpers no)
		(fp_rect
			(start 0.4318 0.9525)
			(end -0.4318 -0.9525)
			(stroke
				(width 0)
				(type default)
			)
			(fill no)
			(layer "B.CrtYd")
		)
		(fp_rect
			(start 0.4318 0.9525)
			(end -0.4318 -0.9525)
			(stroke
				(width 0)
				(type default)
			)
			(fill no)
			(layer "B.Fab")
		)
		(pad "1" smd custom
			(at 0 -0.4445 180)
			(size 0.1524 0.1524)
			(layers "B.Cu" "B.Mask" "B.Paste")
			(net "GB_VDDH")
			(options
				(clearance outline)
				(anchor circle)
			)
			(primitives
				(gr_poly
					(pts
						(arc
							(start 0.3048 0.2032)
							(mid 0.275042 0.275042)
							(end 0.2032 0.3048)
						)
						(arc
							(start -0.2032 0.3048)
							(mid -0.275042 0.275042)
							(end -0.3048 0.2032)
						)
						(arc
							(start -0.3048 -0.2032)
							(mid -0.275042 -0.275042)
							(end -0.2032 -0.3048)
						)
						(arc
							(start 0.2032 -0.3048)
							(mid 0.275042 -0.275042)
							(end 0.3048 -0.2032)
						)
					)
					(width 0)
					(fill yes)
				)
			)
		)
		(pad "2" smd custom
			(at 0 0.4445 180)
			(size 0.1524 0.1524)
			(layers "B.Cu" "B.Mask" "B.Paste")
			(net "GND")
			(options
				(clearance outline)
				(anchor circle)
			)
			(primitives
				(gr_poly
					(pts
						(arc
							(start 0.3048 0.2032)
							(mid 0.275042 0.275042)
							(end 0.2032 0.3048)
						)
						(arc
							(start -0.2032 0.3048)
							(mid -0.275042 0.275042)
							(end -0.3048 0.2032)
						)
						(arc
							(start -0.3048 -0.2032)
							(mid -0.275042 -0.275042)
							(end -0.2032 -0.3048)
						)
						(arc
							(start 0.2032 -0.3048)
							(mid 0.275042 -0.275042)
							(end 0.3048 -0.2032)
						)
					)
					(width 0)
					(fill yes)
				)
			)
		)
	)
	(footprint ""
		(layer "B.Cu")
		(at 187.9346 -28.575 90)
		(property "Reference" "TP63"
			(at 0 0 90)
			(layer "B.SilkS")
			(hide yes)
			(effects
				(font
					(size 1.27 1.27)
				)
				(justify mirror)
			)
		)
		(property "Value" "TPAD28-2-GP"
			(at 0.0127 -1.6637 90)
			(unlocked yes)
			(layer "B.Fab")
			(hide yes)
			(effects
				(font
					(size 1.016 1.016)
					(thickness 0.1524)
				)
				(justify mirror)
			)
		)
		(property "Device Type" "TPAD28"
			(at 0.0127 -3.1877 90)
			(unlocked yes)
			(layer "B.Fab")
			(hide yes)
			(effects
				(font
					(size 1.016 1.016)
					(thickness 0.1524)
				)
				(justify mirror)
			)
		)
		(duplicate_pad_numbers_are_jumpers no)
		(fp_poly
			(pts
				(arc
					(start 0 0.3556)
					(mid 0 -0.3556)
					(end 0 0.3556)
				)
			)
			(stroke
				(width 0)
				(type default)
			)
			(fill no)
			(layer "B.CrtYd")
		)
		(fp_poly
			(pts
				(arc
					(start 0 0.6096)
					(mid 0 -0.6096)
					(end 0 0.6096)
				)
			)
			(stroke
				(width 0)
				(type default)
			)
			(fill no)
			(layer "B.Fab")
		)
		(pad "1" smd circle
			(at 0 0 270)
			(size 0.7112 0.7112)
			(layers "B.Cu" "B.Mask" "B.Paste")
			(net "IOC_GPIO_10")
		)
	)
	(footprint ""
		(layer "B.Cu")
		(at 198.755 -35.3314)
		(property "Reference" "R199"
			(at 0 0 0)
			(layer "B.SilkS")
			(hide yes)
			(effects
				(font
					(size 1.27 1.27)
				)
				(justify mirror)
			)
		)
		(property "Value" "4K7R2F-GP"
			(at -0.064008 -3.993896 0)
			(unlocked yes)
			(layer "B.Fab")
			(hide yes)
			(effects
				(font
					(size 1.016 1.016)
					(thickness 0.1524)
				)
				(justify mirror)
			)
		)
		(property "Device Type" "R402H16"
			(at -0.064008 -5.517896 0)
			(unlocked yes)
			(layer "B.Fab")
			(hide yes)
			(effects
				(font
					(size 1.016 1.016)
					(thickness 0.1524)
				)
				(justify mirror)
			)
		)
		(duplicate_pad_numbers_are_jumpers no)
		(fp_line
			(start -0.508 -0.9398)
			(end 0.508 -0.9398)
			(stroke
				(width 0.1524)
				(type default)
			)
			(layer "B.SilkS")
		)
		(fp_line
			(start 0.508 -0.9398)
			(end 0.508 0.9398)
			(stroke
				(width 0.1524)
				(type default)
			)
			(layer "B.SilkS")
		)
		(fp_rect
			(start 0.508 0.9398)
			(end -0.508 -0.9398)
			(stroke
				(width 0)
				(type default)
			)
			(fill no)
			(layer "B.CrtYd")
		)
		(fp_rect
			(start 0.508 0.9398)
			(end -0.508 -0.9398)
			(stroke
				(width 0)
				(type default)
			)
			(fill no)
			(layer "B.Fab")
		)
		(pad "1" smd custom
			(at 0 -0.4445 180)
			(size 0.1397 0.1397)
			(layers "B.Cu" "B.Mask" "B.Paste")
			(net "IOC_EEPROM_A2")
			(options
				(clearance outline)
				(anchor circle)
			)
			(primitives
				(gr_poly
					(pts
						(arc
							(start -0.1778 0.2794)
							(mid -0.249642 0.249642)
							(end -0.2794 0.1778)
						)
						(arc
							(start -0.2794 -0.1778)
							(mid -0.249642 -0.249642)
							(end -0.1778 -0.2794)
						)
						(arc
							(start 0.1778 -0.2794)
							(mid 0.249642 -0.249642)
							(end 0.2794 -0.1778)
						)
						(arc
							(start 0.2794 0.1778)
							(mid 0.249642 0.249642)
							(end 0.1778 0.2794)
						)
					)
					(width 0)
					(fill yes)
				)
			)
		)
		(pad "2" smd custom
			(at 0 0.4445 180)
			(size 0.1397 0.1397)
			(layers "B.Cu" "B.Mask" "B.Paste")
			(net "GND")
			(options
				(clearance outline)
				(anchor circle)
			)
			(primitives
				(gr_poly
					(pts
						(arc
							(start -0.1778 0.2794)
							(mid -0.249642 0.249642)
							(end -0.2794 0.1778)
						)
						(arc
							(start -0.2794 -0.1778)
							(mid -0.249642 -0.249642)
							(end -0.1778 -0.2794)
						)
						(arc
							(start 0.1778 -0.2794)
							(mid 0.249642 -0.249642)
							(end 0.2794 -0.1778)
						)
						(arc
							(start 0.2794 0.1778)
							(mid 0.249642 0.249642)
							(end 0.1778 0.2794)
						)
					)
					(width 0)
					(fill yes)
				)
			)
		)
	)
	(footprint ""
		(layer "B.Cu")
		(at 127.4572 -39.4716 180)
		(property "Reference" "C49"
			(at 0 0 0)
			(layer "B.SilkS")
			(hide yes)
			(effects
				(font
					(size 1.27 1.27)
				)
				(justify mirror)
			)
		)
		(property "Value" "SCD01U16V1KX-GP"
			(at 2.8321 -1.7399 180)
			(unlocked yes)
			(layer "B.Fab")
			(hide yes)
			(effects
				(font
					(size 1.016 1.016)
					(thickness 0.1524)
				)
				(justify mirror)
			)
		)
		(property "Device Type" "C0201H13"
			(at 2.8321 -3.2639 180)
			(unlocked yes)
			(layer "B.Fab")
			(hide yes)
			(effects
				(font
					(size 1.016 1.016)
					(thickness 0.1524)
				)
				(justify mirror)
			)
		)
		(duplicate_pad_numbers_are_jumpers no)
		(fp_rect
			(start 0.2794 0.6477)
			(end -0.2794 -0.6477)
			(stroke
				(width 0)
				(type default)
			)
			(fill no)
			(layer "B.CrtYd")
		)
		(fp_rect
			(start 0.2794 0.6477)
			(end -0.2794 -0.6477)
			(stroke
				(width 0)
				(type default)
			)
			(fill no)
			(layer "B.Fab")
		)
		(pad "1" smd custom
			(at 0 -0.2794)
			(size 0.0762 0.0762)
			(layers "B.Cu" "B.Mask" "B.Paste")
			(net "PHY_DPB_TO_SCC_39_DP")
			(options
				(clearance outline)
				(anchor circle)
			)
			(primitives
				(gr_poly
					(pts
						(arc
							(start 0.1524 0.127)
							(mid 0.137521 0.162921)
							(end 0.1016 0.1778)
						)
						(arc
							(start -0.1016 0.1778)
							(mid -0.137521 0.162921)
							(end -0.1524 0.127)
						)
						(arc
							(start -0.1524 -0.127)
							(mid -0.137521 -0.162921)
							(end -0.1016 -0.1778)
						)
						(arc
							(start 0.1016 -0.1778)
							(mid 0.137521 -0.162921)
							(end 0.1524 -0.127)
						)
					)
					(width 0)
					(fill yes)
				)
			)
		)
		(pad "2" smd custom
			(at 0 0.2794)
			(size 0.0762 0.0762)
			(layers "B.Cu" "B.Mask" "B.Paste")
			(net "PHY_DPB_TO_SCC_C_39_DP")
			(options
				(clearance outline)
				(anchor circle)
			)
			(primitives
				(gr_poly
					(pts
						(arc
							(start 0.1524 0.127)
							(mid 0.137521 0.162921)
							(end 0.1016 0.1778)
						)
						(arc
							(start -0.1016 0.1778)
							(mid -0.137521 0.162921)
							(end -0.1524 0.127)
						)
						(arc
							(start -0.1524 -0.127)
							(mid -0.137521 -0.162921)
							(end -0.1016 -0.1778)
						)
						(arc
							(start 0.1016 -0.1778)
							(mid 0.137521 -0.162921)
							(end 0.1524 -0.127)
						)
					)
					(width 0)
					(fill yes)
				)
			)
		)
	)
	(footprint ""
		(layer "B.Cu")
		(at 154.133804 -60.617608 -90)
		(property "Reference" "C357"
			(at 0 0 90)
			(layer "B.SilkS")
			(hide yes)
			(effects
				(font
					(size 1.27 1.27)
				)
				(justify mirror)
			)
		)
		(property "Value" "SC1U16V2KX-7-GP"
			(at -1.7526 -1.6002 270)
			(unlocked yes)
			(layer "B.Fab")
			(hide yes)
			(effects
				(font
					(size 1.016 1.016)
					(thickness 0.1524)
				)
				(justify mirror)
			)
		)
		(property "Device Type" "C402-TO0D2H24"
			(at -1.7526 -3.1242 270)
			(unlocked yes)
			(layer "B.Fab")
			(hide yes)
			(effects
				(font
					(size 1.016 1.016)
					(thickness 0.1524)
				)
				(justify mirror)
			)
		)
		(duplicate_pad_numbers_are_jumpers no)
		(fp_rect
			(start 0.4826 0.889)
			(end -0.4826 -0.889)
			(stroke
				(width 0)
				(type default)
			)
			(fill no)
			(layer "B.CrtYd")
		)
		(fp_rect
			(start 0.4826 0.889)
			(end -0.4826 -0.889)
			(stroke
				(width 0)
				(type default)
			)
			(fill no)
			(layer "B.Fab")
		)
		(pad "1" smd custom
			(at 0 -0.4572 90)
			(size 0.1524 0.1524)
			(layers "B.Cu" "B.Mask" "B.Paste")
			(net "SYS_PLL_VDD")
			(options
				(clearance outline)
				(anchor circle)
			)
			(primitives
				(gr_poly
					(pts
						(arc
							(start -0.254 -0.3048)
							(mid -0.325842 -0.275042)
							(end -0.3556 -0.2032)
						)
						(arc
							(start -0.3556 0.2032)
							(mid -0.325842 0.275042)
							(end -0.254 0.3048)
						)
						(arc
							(start 0.254 0.3048)
							(mid 0.325842 0.275042)
							(end 0.3556 0.2032)
						)
						(arc
							(start 0.3556 -0.2032)
							(mid 0.325842 -0.275042)
							(end 0.254 -0.3048)
						)
					)
					(width 0)
					(fill yes)
				)
			)
		)
		(pad "2" smd custom
			(at 0 0.4572 90)
			(size 0.1524 0.1524)
			(layers "B.Cu" "B.Mask" "B.Paste")
			(net "GND")
			(options
				(clearance outline)
				(anchor circle)
			)
			(primitives
				(gr_poly
					(pts
						(arc
							(start -0.254 -0.3048)
							(mid -0.325842 -0.275042)
							(end -0.3556 -0.2032)
						)
						(arc
							(start -0.3556 0.2032)
							(mid -0.325842 0.275042)
							(end -0.254 0.3048)
						)
						(arc
							(start 0.254 0.3048)
							(mid 0.325842 0.275042)
							(end 0.3556 0.2032)
						)
						(arc
							(start 0.3556 -0.2032)
							(mid 0.325842 -0.275042)
							(end 0.254 -0.3048)
						)
					)
					(width 0)
					(fill yes)
				)
			)
		)
	)
	(footprint ""
		(layer "B.Cu")
		(at 202.819 -35.3314)
		(property "Reference" "R198"
			(at 0 0 0)
			(layer "B.SilkS")
			(hide yes)
			(effects
				(font
					(size 1.27 1.27)
				)
				(justify mirror)
			)
		)
		(property "Value" "4K7R2F-GP"
			(at -0.064008 -3.993896 0)
			(unlocked yes)
			(layer "B.Fab")
			(hide yes)
			(effects
				(font
					(size 1.016 1.016)
					(thickness 0.1524)
				)
				(justify mirror)
			)
		)
		(property "Device Type" "R402H16"
			(at -0.064008 -5.517896 0)
			(unlocked yes)
			(layer "B.Fab")
			(hide yes)
			(effects
				(font
					(size 1.016 1.016)
					(thickness 0.1524)
				)
				(justify mirror)
			)
		)
		(duplicate_pad_numbers_are_jumpers no)
		(fp_line
			(start -0.508 -0.9398)
			(end 0.508 -0.9398)
			(stroke
				(width 0.1524)
				(type default)
			)
			(layer "B.SilkS")
		)
		(fp_line
			(start 0.508 -0.9398)
			(end 0.508 0.9398)
			(stroke
				(width 0.1524)
				(type default)
			)
			(layer "B.SilkS")
		)
		(fp_rect
			(start 0.508 0.9398)
			(end -0.508 -0.9398)
			(stroke
				(width 0)
				(type default)
			)
			(fill no)
			(layer "B.CrtYd")
		)
		(fp_rect
			(start 0.508 0.9398)
			(end -0.508 -0.9398)
			(stroke
				(width 0)
				(type default)
			)
			(fill no)
			(layer "B.Fab")
		)
		(pad "1" smd custom
			(at 0 -0.4445 180)
			(size 0.1397 0.1397)
			(layers "B.Cu" "B.Mask" "B.Paste")
			(net "IOC_EEPROM_A0")
			(options
				(clearance outline)
				(anchor circle)
			)
			(primitives
				(gr_poly
					(pts
						(arc
							(start -0.1778 0.2794)
							(mid -0.249642 0.249642)
							(end -0.2794 0.1778)
						)
						(arc
							(start -0.2794 -0.1778)
							(mid -0.249642 -0.249642)
							(end -0.1778 -0.2794)
						)
						(arc
							(start 0.1778 -0.2794)
							(mid 0.249642 -0.249642)
							(end 0.2794 -0.1778)
						)
						(arc
							(start 0.2794 0.1778)
							(mid 0.249642 0.249642)
							(end 0.1778 0.2794)
						)
					)
					(width 0)
					(fill yes)
				)
			)
		)
		(pad "2" smd custom
			(at 0 0.4445 180)
			(size 0.1397 0.1397)
			(layers "B.Cu" "B.Mask" "B.Paste")
			(net "GND")
			(options
				(clearance outline)
				(anchor circle)
			)
			(primitives
				(gr_poly
					(pts
						(arc
							(start -0.1778 0.2794)
							(mid -0.249642 0.249642)
							(end -0.2794 0.1778)
						)
						(arc
							(start -0.2794 -0.1778)
							(mid -0.249642 -0.249642)
							(end -0.1778 -0.2794)
						)
						(arc
							(start 0.1778 -0.2794)
							(mid 0.249642 -0.249642)
							(end 0.2794 -0.1778)
						)
						(arc
							(start 0.2794 0.1778)
							(mid 0.249642 0.249642)
							(end 0.1778 0.2794)
						)
					)
					(width 0)
					(fill yes)
				)
			)
		)
	)
	(footprint ""
		(layer "B.Cu")
		(at 104.06888 -85.25002 90)
		(property "Reference" "R569"
			(at 0 0 90)
			(layer "B.SilkS")
			(hide yes)
			(effects
				(font
					(size 1.27 1.27)
				)
				(justify mirror)
			)
		)
		(property "Value" "10KR2F-2-GP"
			(at -0.064008 -3.993896 90)
			(unlocked yes)
			(layer "B.Fab")
			(hide yes)
			(effects
				(font
					(size 1.016 1.016)
					(thickness 0.1524)
				)
				(justify mirror)
			)
		)
		(property "Device Type" "R402H16"
			(at -0.064008 -5.517896 90)
			(unlocked yes)
			(layer "B.Fab")
			(hide yes)
			(effects
				(font
					(size 1.016 1.016)
					(thickness 0.1524)
				)
				(justify mirror)
			)
		)
		(duplicate_pad_numbers_are_jumpers no)
		(fp_line
			(start 0.508 -0.9398)
			(end 0.508 0.9398)
			(stroke
				(width 0.1524)
				(type default)
			)
			(layer "B.SilkS")
		)
		(fp_line
			(start -0.508 -0.9398)
			(end 0.508 -0.9398)
			(stroke
				(width 0.1524)
				(type default)
			)
			(layer "B.SilkS")
		)
		(fp_rect
			(start 0.508 0.9398)
			(end -0.508 -0.9398)
			(stroke
				(width 0)
				(type default)
			)
			(fill no)
			(layer "B.CrtYd")
		)
		(fp_rect
			(start 0.508 0.9398)
			(end -0.508 -0.9398)
			(stroke
				(width 0)
				(type default)
			)
			(fill no)
			(layer "B.Fab")
		)
		(pad "1" smd custom
			(at 0 -0.4445 270)
			(size 0.1397 0.1397)
			(layers "B.Cu" "B.Mask" "B.Paste")
			(net "SYS_PWR_LED_LS_N")
			(options
				(clearance outline)
				(anchor circle)
			)
			(primitives
				(gr_poly
					(pts
						(arc
							(start -0.1778 0.2794)
							(mid -0.249642 0.249642)
							(end -0.2794 0.1778)
						)
						(arc
							(start -0.2794 -0.1778)
							(mid -0.249642 -0.249642)
							(end -0.1778 -0.2794)
						)
						(arc
							(start 0.1778 -0.2794)
							(mid 0.249642 -0.249642)
							(end 0.2794 -0.1778)
						)
						(arc
							(start 0.2794 0.1778)
							(mid 0.249642 0.249642)
							(end 0.1778 0.2794)
						)
					)
					(width 0)
					(fill yes)
				)
			)
		)
		(pad "2" smd custom
			(at 0 0.4445 270)
			(size 0.1397 0.1397)
			(layers "B.Cu" "B.Mask" "B.Paste")
			(net "GND")
			(options
				(clearance outline)
				(anchor circle)
			)
			(primitives
				(gr_poly
					(pts
						(arc
							(start -0.1778 0.2794)
							(mid -0.249642 0.249642)
							(end -0.2794 0.1778)
						)
						(arc
							(start -0.2794 -0.1778)
							(mid -0.249642 -0.249642)
							(end -0.1778 -0.2794)
						)
						(arc
							(start 0.1778 -0.2794)
							(mid 0.249642 -0.249642)
							(end 0.2794 -0.1778)
						)
						(arc
							(start 0.2794 0.1778)
							(mid 0.249642 0.249642)
							(end 0.1778 0.2794)
						)
					)
					(width 0)
					(fill yes)
				)
			)
		)
	)
	(footprint ""
		(layer "B.Cu")
		(at 179.441348 -41.329102 90)
		(property "Reference" "C441"
			(at 0 0 90)
			(layer "B.SilkS")
			(hide yes)
			(effects
				(font
					(size 1.27 1.27)
				)
				(justify mirror)
			)
		)
		(property "Value" "SCD1U6D3V1KX-GP"
			(at 2.8321 -1.7399 90)
			(unlocked yes)
			(layer "B.Fab")
			(hide yes)
			(effects
				(font
					(size 1.016 1.016)
					(thickness 0.1524)
				)
				(justify mirror)
			)
		)
		(property "Device Type" "C0201H13"
			(at 2.8321 -3.2639 90)
			(unlocked yes)
			(layer "B.Fab")
			(hide yes)
			(effects
				(font
					(size 1.016 1.016)
					(thickness 0.1524)
				)
				(justify mirror)
			)
		)
		(duplicate_pad_numbers_are_jumpers no)
		(fp_rect
			(start 0.2794 0.6477)
			(end -0.2794 -0.6477)
			(stroke
				(width 0)
				(type default)
			)
			(fill no)
			(layer "B.CrtYd")
		)
		(fp_rect
			(start 0.2794 0.6477)
			(end -0.2794 -0.6477)
			(stroke
				(width 0)
				(type default)
			)
			(fill no)
			(layer "B.Fab")
		)
		(pad "1" smd custom
			(at 0 -0.2794 270)
			(size 0.0762 0.0762)
			(layers "B.Cu" "B.Mask" "B.Paste")
			(net "P0V975")
			(options
				(clearance outline)
				(anchor circle)
			)
			(primitives
				(gr_poly
					(pts
						(arc
							(start 0.1524 0.127)
							(mid 0.137521 0.162921)
							(end 0.1016 0.1778)
						)
						(arc
							(start -0.1016 0.1778)
							(mid -0.137521 0.162921)
							(end -0.1524 0.127)
						)
						(arc
							(start -0.1524 -0.127)
							(mid -0.137521 -0.162921)
							(end -0.1016 -0.1778)
						)
						(arc
							(start 0.1016 -0.1778)
							(mid 0.137521 -0.162921)
							(end 0.1524 -0.127)
						)
					)
					(width 0)
					(fill yes)
				)
			)
		)
		(pad "2" smd custom
			(at 0 0.2794 270)
			(size 0.0762 0.0762)
			(layers "B.Cu" "B.Mask" "B.Paste")
			(net "GND")
			(options
				(clearance outline)
				(anchor circle)
			)
			(primitives
				(gr_poly
					(pts
						(arc
							(start 0.1524 0.127)
							(mid 0.137521 0.162921)
							(end 0.1016 0.1778)
						)
						(arc
							(start -0.1016 0.1778)
							(mid -0.137521 0.162921)
							(end -0.1524 0.127)
						)
						(arc
							(start -0.1524 -0.127)
							(mid -0.137521 -0.162921)
							(end -0.1016 -0.1778)
						)
						(arc
							(start 0.1016 -0.1778)
							(mid 0.137521 -0.162921)
							(end 0.1524 -0.127)
						)
					)
					(width 0)
					(fill yes)
				)
			)
		)
	)
	(footprint ""
		(layer "B.Cu")
		(at 176.1617 -43.4721 90)
		(property "Reference" "C422"
			(at 0 0 90)
			(layer "B.SilkS")
			(hide yes)
			(effects
				(font
					(size 1.27 1.27)
				)
				(justify mirror)
			)
		)
		(property "Value" "SCD1U6D3V1KX-GP"
			(at 2.8321 -1.7399 90)
			(unlocked yes)
			(layer "B.Fab")
			(hide yes)
			(effects
				(font
					(size 1.016 1.016)
					(thickness 0.1524)
				)
				(justify mirror)
			)
		)
		(property "Device Type" "C0201H13"
			(at 2.8321 -3.2639 90)
			(unlocked yes)
			(layer "B.Fab")
			(hide yes)
			(effects
				(font
					(size 1.016 1.016)
					(thickness 0.1524)
				)
				(justify mirror)
			)
		)
		(duplicate_pad_numbers_are_jumpers no)
		(fp_rect
			(start 0.2794 0.6477)
			(end -0.2794 -0.6477)
			(stroke
				(width 0)
				(type default)
			)
			(fill no)
			(layer "B.CrtYd")
		)
		(fp_rect
			(start 0.2794 0.6477)
			(end -0.2794 -0.6477)
			(stroke
				(width 0)
				(type default)
			)
			(fill no)
			(layer "B.Fab")
		)
		(pad "1" smd custom
			(at 0 -0.2794 270)
			(size 0.0762 0.0762)
			(layers "B.Cu" "B.Mask" "B.Paste")
			(net "P0V975")
			(options
				(clearance outline)
				(anchor circle)
			)
			(primitives
				(gr_poly
					(pts
						(arc
							(start 0.1524 0.127)
							(mid 0.137521 0.162921)
							(end 0.1016 0.1778)
						)
						(arc
							(start -0.1016 0.1778)
							(mid -0.137521 0.162921)
							(end -0.1524 0.127)
						)
						(arc
							(start -0.1524 -0.127)
							(mid -0.137521 -0.162921)
							(end -0.1016 -0.1778)
						)
						(arc
							(start 0.1016 -0.1778)
							(mid 0.137521 -0.162921)
							(end 0.1524 -0.127)
						)
					)
					(width 0)
					(fill yes)
				)
			)
		)
		(pad "2" smd custom
			(at 0 0.2794 270)
			(size 0.0762 0.0762)
			(layers "B.Cu" "B.Mask" "B.Paste")
			(net "GND")
			(options
				(clearance outline)
				(anchor circle)
			)
			(primitives
				(gr_poly
					(pts
						(arc
							(start 0.1524 0.127)
							(mid 0.137521 0.162921)
							(end 0.1016 0.1778)
						)
						(arc
							(start -0.1016 0.1778)
							(mid -0.137521 0.162921)
							(end -0.1524 0.127)
						)
						(arc
							(start -0.1524 -0.127)
							(mid -0.137521 -0.162921)
							(end -0.1016 -0.1778)
						)
						(arc
							(start 0.1016 -0.1778)
							(mid 0.137521 -0.162921)
							(end 0.1524 -0.127)
						)
					)
					(width 0)
					(fill yes)
				)
			)
		)
	)
	(footprint ""
		(layer "B.Cu")
		(at 118.531132 -70.427596 180)
		(property "Reference" "C189"
			(at 0 0 0)
			(layer "B.SilkS")
			(hide yes)
			(effects
				(font
					(size 1.27 1.27)
				)
				(justify mirror)
			)
		)
		(property "Value" "SC1KP25V1KX-GP"
			(at 2.8321 -1.7399 180)
			(unlocked yes)
			(layer "B.Fab")
			(hide yes)
			(effects
				(font
					(size 1.016 1.016)
					(thickness 0.1524)
				)
				(justify mirror)
			)
		)
		(property "Device Type" "C0201H13"
			(at 2.8321 -3.2639 180)
			(unlocked yes)
			(layer "B.Fab")
			(hide yes)
			(effects
				(font
					(size 1.016 1.016)
					(thickness 0.1524)
				)
				(justify mirror)
			)
		)
		(duplicate_pad_numbers_are_jumpers no)
		(fp_rect
			(start 0.2794 0.6477)
			(end -0.2794 -0.6477)
			(stroke
				(width 0)
				(type default)
			)
			(fill no)
			(layer "B.CrtYd")
		)
		(fp_rect
			(start 0.2794 0.6477)
			(end -0.2794 -0.6477)
			(stroke
				(width 0)
				(type default)
			)
			(fill no)
			(layer "B.Fab")
		)
		(pad "1" smd custom
			(at 0 -0.2794)
			(size 0.0762 0.0762)
			(layers "B.Cu" "B.Mask" "B.Paste")
			(net "P0V9")
			(options
				(clearance outline)
				(anchor circle)
			)
			(primitives
				(gr_poly
					(pts
						(arc
							(start 0.1524 0.127)
							(mid 0.137521 0.162921)
							(end 0.1016 0.1778)
						)
						(arc
							(start -0.1016 0.1778)
							(mid -0.137521 0.162921)
							(end -0.1524 0.127)
						)
						(arc
							(start -0.1524 -0.127)
							(mid -0.137521 -0.162921)
							(end -0.1016 -0.1778)
						)
						(arc
							(start 0.1016 -0.1778)
							(mid 0.137521 -0.162921)
							(end 0.1524 -0.127)
						)
					)
					(width 0)
					(fill yes)
				)
			)
		)
		(pad "2" smd custom
			(at 0 0.2794)
			(size 0.0762 0.0762)
			(layers "B.Cu" "B.Mask" "B.Paste")
			(net "GND")
			(options
				(clearance outline)
				(anchor circle)
			)
			(primitives
				(gr_poly
					(pts
						(arc
							(start 0.1524 0.127)
							(mid 0.137521 0.162921)
							(end 0.1016 0.1778)
						)
						(arc
							(start -0.1016 0.1778)
							(mid -0.137521 0.162921)
							(end -0.1524 0.127)
						)
						(arc
							(start -0.1524 -0.127)
							(mid -0.137521 -0.162921)
							(end -0.1016 -0.1778)
						)
						(arc
							(start 0.1016 -0.1778)
							(mid 0.137521 -0.162921)
							(end 0.1524 -0.127)
						)
					)
					(width 0)
					(fill yes)
				)
			)
		)
	)
	(footprint ""
		(layer "B.Cu")
		(at 104.504744 -62.23)
		(property "Reference" "C202"
			(at 0 0 0)
			(layer "B.SilkS")
			(hide yes)
			(effects
				(font
					(size 1.27 1.27)
				)
				(justify mirror)
			)
		)
		(property "Value" "SC1U6D3V1MX-GP"
			(at -1.9177 2.0193 0)
			(unlocked yes)
			(layer "B.Fab")
			(hide yes)
			(effects
				(font
					(size 1.016 1.016)
					(thickness 0.1524)
				)
				(justify mirror)
			)
		)
		(property "Device Type" "C0201H14"
			(at -1.9177 0.4953 0)
			(unlocked yes)
			(layer "B.Fab")
			(hide yes)
			(effects
				(font
					(size 1.016 1.016)
					(thickness 0.1524)
				)
				(justify mirror)
			)
		)
		(duplicate_pad_numbers_are_jumpers no)
		(fp_rect
			(start 0.1524 0.3048)
			(end -0.1524 -0.3048)
			(stroke
				(width 0)
				(type default)
			)
			(fill no)
			(layer "B.CrtYd")
		)
		(fp_poly
			(pts
				(xy 0.2794 0.6477) (xy 0.2794 -0.6477) (xy -0.2794 -0.6477) (xy -0.2794 -0.1905) (xy -0.1524 -0.1905)
				(xy -0.1524 -0.3048) (xy 0.1524 -0.3048) (xy 0.1524 0.3048) (xy -0.1524 0.3048) (xy -0.1524 -0.1778)
				(xy -0.2794 -0.1778) (xy -0.2794 0.6477)
			)
			(stroke
				(width 0)
				(type default)
			)
			(fill no)
			(layer "B.CrtYd")
		)
		(fp_rect
			(start 0.2794 0.6477)
			(end -0.2794 -0.6477)
			(stroke
				(width 0)
				(type default)
			)
			(fill no)
			(layer "B.Fab")
		)
		(pad "1" smd custom
			(at 0 -0.2794 180)
			(size 0.0762 0.0762)
			(layers "B.Cu" "B.Mask" "B.Paste")
			(net "PLLDDR_VDDA18")
			(options
				(clearance outline)
				(anchor circle)
			)
			(primitives
				(gr_poly
					(pts
						(arc
							(start 0.1524 0.127)
							(mid 0.137521 0.162921)
							(end 0.1016 0.1778)
						)
						(arc
							(start -0.1016 0.1778)
							(mid -0.137521 0.162921)
							(end -0.1524 0.127)
						)
						(arc
							(start -0.1524 -0.127)
							(mid -0.137521 -0.162921)
							(end -0.1016 -0.1778)
						)
						(arc
							(start 0.1016 -0.1778)
							(mid 0.137521 -0.162921)
							(end 0.1524 -0.127)
						)
					)
					(width 0)
					(fill yes)
				)
			)
		)
		(pad "2" smd custom
			(at 0 0.2794 180)
			(size 0.0762 0.0762)
			(layers "B.Cu" "B.Mask" "B.Paste")
			(net "GND")
			(options
				(clearance outline)
				(anchor circle)
			)
			(primitives
				(gr_poly
					(pts
						(arc
							(start 0.1524 0.127)
							(mid 0.137521 0.162921)
							(end 0.1016 0.1778)
						)
						(arc
							(start -0.1016 0.1778)
							(mid -0.137521 0.162921)
							(end -0.1524 0.127)
						)
						(arc
							(start -0.1524 -0.127)
							(mid -0.137521 -0.162921)
							(end -0.1016 -0.1778)
						)
						(arc
							(start 0.1016 -0.1778)
							(mid 0.137521 -0.162921)
							(end 0.1524 -0.127)
						)
					)
					(width 0)
					(fill yes)
				)
			)
		)
	)
	(footprint ""
		(layer "B.Cu")
		(at 109.33938 -61.488066)
		(property "Reference" "C225"
			(at 0 0 0)
			(layer "B.SilkS")
			(hide yes)
			(effects
				(font
					(size 1.27 1.27)
				)
				(justify mirror)
			)
		)
		(property "Value" "SCD1U16V2KX-3GP"
			(at -1.1811 -2.7051 0)
			(unlocked yes)
			(layer "B.Fab")
			(hide yes)
			(effects
				(font
					(size 1.016 1.016)
					(thickness 0.1524)
				)
				(justify mirror)
			)
		)
		(property "Device Type" "C402H22"
			(at -1.1811 -4.2291 0)
			(unlocked yes)
			(layer "B.Fab")
			(hide yes)
			(effects
				(font
					(size 1.016 1.016)
					(thickness 0.1524)
				)
				(justify mirror)
			)
		)
		(duplicate_pad_numbers_are_jumpers no)
		(fp_rect
			(start 0.4318 0.9525)
			(end -0.4318 -0.9525)
			(stroke
				(width 0)
				(type default)
			)
			(fill no)
			(layer "B.CrtYd")
		)
		(fp_rect
			(start 0.4318 0.9525)
			(end -0.4318 -0.9525)
			(stroke
				(width 0)
				(type default)
			)
			(fill no)
			(layer "B.Fab")
		)
		(pad "1" smd custom
			(at 0 -0.4445 180)
			(size 0.1524 0.1524)
			(layers "B.Cu" "B.Mask" "B.Paste")
			(net "GB_VDDH")
			(options
				(clearance outline)
				(anchor circle)
			)
			(primitives
				(gr_poly
					(pts
						(arc
							(start 0.3048 0.2032)
							(mid 0.275042 0.275042)
							(end 0.2032 0.3048)
						)
						(arc
							(start -0.2032 0.3048)
							(mid -0.275042 0.275042)
							(end -0.3048 0.2032)
						)
						(arc
							(start -0.3048 -0.2032)
							(mid -0.275042 -0.275042)
							(end -0.2032 -0.3048)
						)
						(arc
							(start 0.2032 -0.3048)
							(mid 0.275042 -0.275042)
							(end 0.3048 -0.2032)
						)
					)
					(width 0)
					(fill yes)
				)
			)
		)
		(pad "2" smd custom
			(at 0 0.4445 180)
			(size 0.1524 0.1524)
			(layers "B.Cu" "B.Mask" "B.Paste")
			(net "GND")
			(options
				(clearance outline)
				(anchor circle)
			)
			(primitives
				(gr_poly
					(pts
						(arc
							(start 0.3048 0.2032)
							(mid 0.275042 0.275042)
							(end 0.2032 0.3048)
						)
						(arc
							(start -0.2032 0.3048)
							(mid -0.275042 0.275042)
							(end -0.3048 0.2032)
						)
						(arc
							(start -0.3048 -0.2032)
							(mid -0.275042 -0.275042)
							(end -0.2032 -0.3048)
						)
						(arc
							(start 0.2032 -0.3048)
							(mid 0.275042 -0.275042)
							(end 0.3048 -0.2032)
						)
					)
					(width 0)
					(fill yes)
				)
			)
		)
	)
	(footprint ""
		(layer "B.Cu")
		(at 187.2234 -26.162 90)
		(property "Reference" "TP72"
			(at 0 0 90)
			(layer "B.SilkS")
			(hide yes)
			(effects
				(font
					(size 1.27 1.27)
				)
				(justify mirror)
			)
		)
		(property "Value" "TPAD28-2-GP"
			(at 0.0127 -1.6637 90)
			(unlocked yes)
			(layer "B.Fab")
			(hide yes)
			(effects
				(font
					(size 1.016 1.016)
					(thickness 0.1524)
				)
				(justify mirror)
			)
		)
		(property "Device Type" "TPAD28"
			(at 0.0127 -3.1877 90)
			(unlocked yes)
			(layer "B.Fab")
			(hide yes)
			(effects
				(font
					(size 1.016 1.016)
					(thickness 0.1524)
				)
				(justify mirror)
			)
		)
		(duplicate_pad_numbers_are_jumpers no)
		(fp_poly
			(pts
				(arc
					(start 0 0.3556)
					(mid 0 -0.3556)
					(end 0 0.3556)
				)
			)
			(stroke
				(width 0)
				(type default)
			)
			(fill no)
			(layer "B.CrtYd")
		)
		(fp_poly
			(pts
				(arc
					(start 0 0.6096)
					(mid 0 -0.6096)
					(end 0 0.6096)
				)
			)
			(stroke
				(width 0)
				(type default)
			)
			(fill no)
			(layer "B.Fab")
		)
		(pad "1" smd circle
			(at 0 0 270)
			(size 0.7112 0.7112)
			(layers "B.Cu" "B.Mask" "B.Paste")
			(net "IOC_GPIO_19")
		)
	)
	(footprint ""
		(layer "B.Cu")
		(at 93.262958 -78.323948)
		(property "Reference" "C209"
			(at 0 0 0)
			(layer "B.SilkS")
			(hide yes)
			(effects
				(font
					(size 1.27 1.27)
				)
				(justify mirror)
			)
		)
		(property "Value" "SC10U6D3V2MX-GP-U"
			(at 1.524 -1.905 0)
			(unlocked yes)
			(layer "B.Fab")
			(hide yes)
			(effects
				(font
					(size 1.016 1.016)
					(thickness 0.1524)
				)
				(justify mirror)
			)
		)
		(property "Device Type" "C402-TO0D2H28"
			(at 1.524 -3.429 0)
			(unlocked yes)
			(layer "B.Fab")
			(hide yes)
			(effects
				(font
					(size 1.016 1.016)
					(thickness 0.1524)
				)
				(justify mirror)
			)
		)
		(duplicate_pad_numbers_are_jumpers no)
		(fp_rect
			(start 0.4826 0.889)
			(end -0.4826 -0.889)
			(stroke
				(width 0)
				(type default)
			)
			(fill no)
			(layer "B.CrtYd")
		)
		(fp_rect
			(start 0.4826 0.889)
			(end -0.4826 -0.889)
			(stroke
				(width 0)
				(type default)
			)
			(fill no)
			(layer "B.Fab")
		)
		(pad "1" smd custom
			(at 0 -0.4572 180)
			(size 0.1524 0.1524)
			(layers "B.Cu" "B.Mask" "B.Paste")
			(net "SYSPLL_VDDA09")
			(options
				(clearance outline)
				(anchor circle)
			)
			(primitives
				(gr_poly
					(pts
						(arc
							(start -0.254 -0.3048)
							(mid -0.325842 -0.275042)
							(end -0.3556 -0.2032)
						)
						(arc
							(start -0.3556 0.2032)
							(mid -0.325842 0.275042)
							(end -0.254 0.3048)
						)
						(arc
							(start 0.254 0.3048)
							(mid 0.325842 0.275042)
							(end 0.3556 0.2032)
						)
						(arc
							(start 0.3556 -0.2032)
							(mid 0.325842 -0.275042)
							(end 0.254 -0.3048)
						)
					)
					(width 0)
					(fill yes)
				)
			)
		)
		(pad "2" smd custom
			(at 0 0.4572 180)
			(size 0.1524 0.1524)
			(layers "B.Cu" "B.Mask" "B.Paste")
			(net "GND")
			(options
				(clearance outline)
				(anchor circle)
			)
			(primitives
				(gr_poly
					(pts
						(arc
							(start -0.254 -0.3048)
							(mid -0.325842 -0.275042)
							(end -0.3556 -0.2032)
						)
						(arc
							(start -0.3556 0.2032)
							(mid -0.325842 0.275042)
							(end -0.254 0.3048)
						)
						(arc
							(start 0.254 0.3048)
							(mid 0.325842 0.275042)
							(end 0.3556 0.2032)
						)
						(arc
							(start 0.3556 -0.2032)
							(mid 0.325842 -0.275042)
							(end 0.254 -0.3048)
						)
					)
					(width 0)
					(fill yes)
				)
			)
		)
	)
	(footprint ""
		(layer "B.Cu")
		(at 176.1617 -42.9133 90)
		(property "Reference" "C432"
			(at 0 0 90)
			(layer "B.SilkS")
			(hide yes)
			(effects
				(font
					(size 1.27 1.27)
				)
				(justify mirror)
			)
		)
		(property "Value" "SCD1U6D3V1KX-GP"
			(at 2.8321 -1.7399 90)
			(unlocked yes)
			(layer "B.Fab")
			(hide yes)
			(effects
				(font
					(size 1.016 1.016)
					(thickness 0.1524)
				)
				(justify mirror)
			)
		)
		(property "Device Type" "C0201H13"
			(at 2.8321 -3.2639 90)
			(unlocked yes)
			(layer "B.Fab")
			(hide yes)
			(effects
				(font
					(size 1.016 1.016)
					(thickness 0.1524)
				)
				(justify mirror)
			)
		)
		(duplicate_pad_numbers_are_jumpers no)
		(fp_rect
			(start 0.2794 0.6477)
			(end -0.2794 -0.6477)
			(stroke
				(width 0)
				(type default)
			)
			(fill no)
			(layer "B.CrtYd")
		)
		(fp_rect
			(start 0.2794 0.6477)
			(end -0.2794 -0.6477)
			(stroke
				(width 0)
				(type default)
			)
			(fill no)
			(layer "B.Fab")
		)
		(pad "1" smd custom
			(at 0 -0.2794 270)
			(size 0.0762 0.0762)
			(layers "B.Cu" "B.Mask" "B.Paste")
			(net "P0V975")
			(options
				(clearance outline)
				(anchor circle)
			)
			(primitives
				(gr_poly
					(pts
						(arc
							(start 0.1524 0.127)
							(mid 0.137521 0.162921)
							(end 0.1016 0.1778)
						)
						(arc
							(start -0.1016 0.1778)
							(mid -0.137521 0.162921)
							(end -0.1524 0.127)
						)
						(arc
							(start -0.1524 -0.127)
							(mid -0.137521 -0.162921)
							(end -0.1016 -0.1778)
						)
						(arc
							(start 0.1016 -0.1778)
							(mid 0.137521 -0.162921)
							(end 0.1524 -0.127)
						)
					)
					(width 0)
					(fill yes)
				)
			)
		)
		(pad "2" smd custom
			(at 0 0.2794 270)
			(size 0.0762 0.0762)
			(layers "B.Cu" "B.Mask" "B.Paste")
			(net "GND")
			(options
				(clearance outline)
				(anchor circle)
			)
			(primitives
				(gr_poly
					(pts
						(arc
							(start 0.1524 0.127)
							(mid 0.137521 0.162921)
							(end 0.1016 0.1778)
						)
						(arc
							(start -0.1016 0.1778)
							(mid -0.137521 0.162921)
							(end -0.1524 0.127)
						)
						(arc
							(start -0.1524 -0.127)
							(mid -0.137521 -0.162921)
							(end -0.1016 -0.1778)
						)
						(arc
							(start 0.1016 -0.1778)
							(mid 0.137521 -0.162921)
							(end 0.1524 -0.127)
						)
					)
					(width 0)
					(fill yes)
				)
			)
		)
	)
	(footprint ""
		(layer "B.Cu")
		(at 70.612 -35.814 90)
		(property "Reference" "R157"
			(at 0 0 90)
			(layer "B.SilkS")
			(hide yes)
			(effects
				(font
					(size 1.27 1.27)
				)
				(justify mirror)
			)
		)
		(property "Value" "D51R3F-2-GP"
			(at 0.0254 -2.5146 90)
			(unlocked yes)
			(layer "B.Fab")
			(hide yes)
			(effects
				(font
					(size 1.016 1.016)
					(thickness 0.1524)
				)
				(justify mirror)
			)
		)
		(property "Device Type" "R603H22"
			(at 0.0254 -4.0386 90)
			(unlocked yes)
			(layer "B.Fab")
			(hide yes)
			(effects
				(font
					(size 1.016 1.016)
					(thickness 0.1524)
				)
				(justify mirror)
			)
		)
		(duplicate_pad_numbers_are_jumpers no)
		(fp_line
			(start 0.4826 0)
			(end 0.2032 0)
			(stroke
				(width 0.2032)
				(type default)
			)
			(layer "B.SilkS")
		)
		(fp_line
			(start -0.2032 0)
			(end -0.4826 0)
			(stroke
				(width 0.2032)
				(type default)
			)
			(layer "B.SilkS")
		)
		(fp_rect
			(start 0.5842 1.3335)
			(end -0.5842 -1.3335)
			(stroke
				(width 0)
				(type default)
			)
			(fill no)
			(layer "B.CrtYd")
		)
		(fp_rect
			(start 0.5842 1.3335)
			(end -0.5842 -1.3335)
			(stroke
				(width 0)
				(type default)
			)
			(fill no)
			(layer "B.Fab")
		)
		(pad "1" smd custom
			(at 0 -0.762 270)
			(size 0.2159 0.2159)
			(layers "B.Cu" "B.Mask" "B.Paste")
			(net "P0V9")
			(options
				(clearance outline)
				(anchor circle)
			)
			(primitives
				(gr_poly
					(pts
						(arc
							(start -0.3302 0.4318)
							(mid -0.402042 0.402042)
							(end -0.4318 0.3302)
						)
						(arc
							(start -0.4318 -0.3302)
							(mid -0.402042 -0.402042)
							(end -0.3302 -0.4318)
						)
						(arc
							(start 0.3302 -0.4318)
							(mid 0.402042 -0.402042)
							(end 0.4318 -0.3302)
						)
						(arc
							(start 0.4318 0.3302)
							(mid 0.402042 0.402042)
							(end 0.3302 0.4318)
						)
					)
					(width 0)
					(fill yes)
				)
			)
		)
		(pad "2" smd custom
			(at 0 0.762 270)
			(size 0.2159 0.2159)
			(layers "B.Cu" "B.Mask" "B.Paste")
			(net "GB_VDDA")
			(options
				(clearance outline)
				(anchor circle)
			)
			(primitives
				(gr_poly
					(pts
						(arc
							(start -0.3302 0.4318)
							(mid -0.402042 0.402042)
							(end -0.4318 0.3302)
						)
						(arc
							(start -0.4318 -0.3302)
							(mid -0.402042 -0.402042)
							(end -0.3302 -0.4318)
						)
						(arc
							(start 0.3302 -0.4318)
							(mid 0.402042 -0.402042)
							(end 0.4318 -0.3302)
						)
						(arc
							(start 0.4318 0.3302)
							(mid 0.402042 0.402042)
							(end 0.3302 0.4318)
						)
					)
					(width 0)
					(fill yes)
				)
			)
		)
	)
	(footprint ""
		(layer "B.Cu")
		(at 175.611028 -20.954746)
		(property "Reference" "C322"
			(at 0 0 0)
			(layer "B.SilkS")
			(hide yes)
			(effects
				(font
					(size 1.27 1.27)
				)
				(justify mirror)
			)
		)
		(property "Value" "SCD22U10V1KX-GP"
			(at 2.8321 -1.7399 0)
			(unlocked yes)
			(layer "B.Fab")
			(hide yes)
			(effects
				(font
					(size 1.016 1.016)
					(thickness 0.1524)
				)
				(justify mirror)
			)
		)
		(property "Device Type" "C0201H13"
			(at 2.8321 -3.2639 0)
			(unlocked yes)
			(layer "B.Fab")
			(hide yes)
			(effects
				(font
					(size 1.016 1.016)
					(thickness 0.1524)
				)
				(justify mirror)
			)
		)
		(duplicate_pad_numbers_are_jumpers no)
		(fp_rect
			(start 0.2794 0.6477)
			(end -0.2794 -0.6477)
			(stroke
				(width 0)
				(type default)
			)
			(fill no)
			(layer "B.CrtYd")
		)
		(fp_rect
			(start 0.2794 0.6477)
			(end -0.2794 -0.6477)
			(stroke
				(width 0)
				(type default)
			)
			(fill no)
			(layer "B.Fab")
		)
		(pad "1" smd custom
			(at 0 -0.2794 180)
			(size 0.0762 0.0762)
			(layers "B.Cu" "B.Mask" "B.Paste")
			(net "PCIE_SCC_TO_COMP_C_5_DN")
			(options
				(clearance outline)
				(anchor circle)
			)
			(primitives
				(gr_poly
					(pts
						(arc
							(start 0.1524 0.127)
							(mid 0.137521 0.162921)
							(end 0.1016 0.1778)
						)
						(arc
							(start -0.1016 0.1778)
							(mid -0.137521 0.162921)
							(end -0.1524 0.127)
						)
						(arc
							(start -0.1524 -0.127)
							(mid -0.137521 -0.162921)
							(end -0.1016 -0.1778)
						)
						(arc
							(start 0.1016 -0.1778)
							(mid 0.137521 -0.162921)
							(end 0.1524 -0.127)
						)
					)
					(width 0)
					(fill yes)
				)
			)
		)
		(pad "2" smd custom
			(at 0 0.2794 180)
			(size 0.0762 0.0762)
			(layers "B.Cu" "B.Mask" "B.Paste")
			(net "PCIE_SCC_TO_COMP_5_DN")
			(options
				(clearance outline)
				(anchor circle)
			)
			(primitives
				(gr_poly
					(pts
						(arc
							(start 0.1524 0.127)
							(mid 0.137521 0.162921)
							(end 0.1016 0.1778)
						)
						(arc
							(start -0.1016 0.1778)
							(mid -0.137521 0.162921)
							(end -0.1524 0.127)
						)
						(arc
							(start -0.1524 -0.127)
							(mid -0.137521 -0.162921)
							(end -0.1016 -0.1778)
						)
						(arc
							(start 0.1016 -0.1778)
							(mid 0.137521 -0.162921)
							(end 0.1524 -0.127)
						)
					)
					(width 0)
					(fill yes)
				)
			)
		)
	)
	(footprint ""
		(layer "B.Cu")
		(at 120.6246 -57.4802)
		(property "Reference" "C267"
			(at 0 0 0)
			(layer "B.SilkS")
			(hide yes)
			(effects
				(font
					(size 1.27 1.27)
				)
				(justify mirror)
			)
		)
		(property "Value" "SCD1U6D3V1KX-GP"
			(at 2.8321 -1.7399 0)
			(unlocked yes)
			(layer "B.Fab")
			(hide yes)
			(effects
				(font
					(size 1.016 1.016)
					(thickness 0.1524)
				)
				(justify mirror)
			)
		)
		(property "Device Type" "C0201H13"
			(at 2.8321 -3.2639 0)
			(unlocked yes)
			(layer "B.Fab")
			(hide yes)
			(effects
				(font
					(size 1.016 1.016)
					(thickness 0.1524)
				)
				(justify mirror)
			)
		)
		(duplicate_pad_numbers_are_jumpers no)
		(fp_rect
			(start 0.2794 0.6477)
			(end -0.2794 -0.6477)
			(stroke
				(width 0)
				(type default)
			)
			(fill no)
			(layer "B.CrtYd")
		)
		(fp_rect
			(start 0.2794 0.6477)
			(end -0.2794 -0.6477)
			(stroke
				(width 0)
				(type default)
			)
			(fill no)
			(layer "B.Fab")
		)
		(pad "1" smd custom
			(at 0 -0.2794 180)
			(size 0.0762 0.0762)
			(layers "B.Cu" "B.Mask" "B.Paste")
			(net "GB_VDDA")
			(options
				(clearance outline)
				(anchor circle)
			)
			(primitives
				(gr_poly
					(pts
						(arc
							(start 0.1524 0.127)
							(mid 0.137521 0.162921)
							(end 0.1016 0.1778)
						)
						(arc
							(start -0.1016 0.1778)
							(mid -0.137521 0.162921)
							(end -0.1524 0.127)
						)
						(arc
							(start -0.1524 -0.127)
							(mid -0.137521 -0.162921)
							(end -0.1016 -0.1778)
						)
						(arc
							(start 0.1016 -0.1778)
							(mid 0.137521 -0.162921)
							(end 0.1524 -0.127)
						)
					)
					(width 0)
					(fill yes)
				)
			)
		)
		(pad "2" smd custom
			(at 0 0.2794 180)
			(size 0.0762 0.0762)
			(layers "B.Cu" "B.Mask" "B.Paste")
			(net "GND")
			(options
				(clearance outline)
				(anchor circle)
			)
			(primitives
				(gr_poly
					(pts
						(arc
							(start 0.1524 0.127)
							(mid 0.137521 0.162921)
							(end 0.1016 0.1778)
						)
						(arc
							(start -0.1016 0.1778)
							(mid -0.137521 0.162921)
							(end -0.1524 0.127)
						)
						(arc
							(start -0.1524 -0.127)
							(mid -0.137521 -0.162921)
							(end -0.1016 -0.1778)
						)
						(arc
							(start 0.1016 -0.1778)
							(mid 0.137521 -0.162921)
							(end 0.1524 -0.127)
						)
					)
					(width 0)
					(fill yes)
				)
			)
		)
	)
	(footprint ""
		(layer "B.Cu")
		(at 64.5922 -93.091)
		(property "Reference" "R499"
			(at 0 0 0)
			(layer "B.SilkS")
			(hide yes)
			(effects
				(font
					(size 1.27 1.27)
				)
				(justify mirror)
			)
		)
		(property "Value" "2D2R3J-2-GP"
			(at 0.0254 -2.5146 0)
			(unlocked yes)
			(layer "B.Fab")
			(hide yes)
			(effects
				(font
					(size 1.016 1.016)
					(thickness 0.1524)
				)
				(justify mirror)
			)
		)
		(property "Device Type" "R603H22"
			(at 0.0254 -4.0386 0)
			(unlocked yes)
			(layer "B.Fab")
			(hide yes)
			(effects
				(font
					(size 1.016 1.016)
					(thickness 0.1524)
				)
				(justify mirror)
			)
		)
		(duplicate_pad_numbers_are_jumpers no)
		(fp_line
			(start -0.2032 0)
			(end -0.4826 0)
			(stroke
				(width 0.2032)
				(type default)
			)
			(layer "B.SilkS")
		)
		(fp_line
			(start 0.4826 0)
			(end 0.2032 0)
			(stroke
				(width 0.2032)
				(type default)
			)
			(layer "B.SilkS")
		)
		(fp_rect
			(start 0.5842 1.3335)
			(end -0.5842 -1.3335)
			(stroke
				(width 0)
				(type default)
			)
			(fill no)
			(layer "B.CrtYd")
		)
		(fp_rect
			(start 0.5842 1.3335)
			(end -0.5842 -1.3335)
			(stroke
				(width 0)
				(type default)
			)
			(fill no)
			(layer "B.Fab")
		)
		(pad "1" smd custom
			(at 0 -0.762 180)
			(size 0.2159 0.2159)
			(layers "B.Cu" "B.Mask" "B.Paste")
			(net "P12V_STBY_VDD_U10")
			(options
				(clearance outline)
				(anchor circle)
			)
			(primitives
				(gr_poly
					(pts
						(arc
							(start -0.3302 0.4318)
							(mid -0.402042 0.402042)
							(end -0.4318 0.3302)
						)
						(arc
							(start -0.4318 -0.3302)
							(mid -0.402042 -0.402042)
							(end -0.3302 -0.4318)
						)
						(arc
							(start 0.3302 -0.4318)
							(mid 0.402042 -0.402042)
							(end 0.4318 -0.3302)
						)
						(arc
							(start 0.4318 0.3302)
							(mid 0.402042 0.402042)
							(end 0.3302 0.4318)
						)
					)
					(width 0)
					(fill yes)
				)
			)
		)
		(pad "2" smd custom
			(at 0 0.762 180)
			(size 0.2159 0.2159)
			(layers "B.Cu" "B.Mask" "B.Paste")
			(net "P12V_STBY_SCC")
			(options
				(clearance outline)
				(anchor circle)
			)
			(primitives
				(gr_poly
					(pts
						(arc
							(start -0.3302 0.4318)
							(mid -0.402042 0.402042)
							(end -0.4318 0.3302)
						)
						(arc
							(start -0.4318 -0.3302)
							(mid -0.402042 -0.402042)
							(end -0.3302 -0.4318)
						)
						(arc
							(start 0.3302 -0.4318)
							(mid 0.402042 -0.402042)
							(end 0.4318 -0.3302)
						)
						(arc
							(start 0.4318 0.3302)
							(mid 0.402042 0.402042)
							(end 0.3302 0.4318)
						)
					)
					(width 0)
					(fill yes)
				)
			)
		)
	)
	(footprint ""
		(layer "B.Cu")
		(at 169.920158 -34.370772 90)
		(property "Reference" "C402"
			(at 0 0 90)
			(layer "B.SilkS")
			(hide yes)
			(effects
				(font
					(size 1.27 1.27)
				)
				(justify mirror)
			)
		)
		(property "Value" "SCD1U16V2KX-3GP"
			(at -1.1811 -2.7051 90)
			(unlocked yes)
			(layer "B.Fab")
			(hide yes)
			(effects
				(font
					(size 1.016 1.016)
					(thickness 0.1524)
				)
				(justify mirror)
			)
		)
		(property "Device Type" "C402H22"
			(at -1.1811 -4.2291 90)
			(unlocked yes)
			(layer "B.Fab")
			(hide yes)
			(effects
				(font
					(size 1.016 1.016)
					(thickness 0.1524)
				)
				(justify mirror)
			)
		)
		(duplicate_pad_numbers_are_jumpers no)
		(fp_rect
			(start 0.4318 0.9525)
			(end -0.4318 -0.9525)
			(stroke
				(width 0)
				(type default)
			)
			(fill no)
			(layer "B.CrtYd")
		)
		(fp_rect
			(start 0.4318 0.9525)
			(end -0.4318 -0.9525)
			(stroke
				(width 0)
				(type default)
			)
			(fill no)
			(layer "B.Fab")
		)
		(pad "1" smd custom
			(at 0 -0.4445 270)
			(size 0.1524 0.1524)
			(layers "B.Cu" "B.Mask" "B.Paste")
			(net "SAS0_AVDD")
			(options
				(clearance outline)
				(anchor circle)
			)
			(primitives
				(gr_poly
					(pts
						(arc
							(start 0.3048 0.2032)
							(mid 0.275042 0.275042)
							(end 0.2032 0.3048)
						)
						(arc
							(start -0.2032 0.3048)
							(mid -0.275042 0.275042)
							(end -0.3048 0.2032)
						)
						(arc
							(start -0.3048 -0.2032)
							(mid -0.275042 -0.275042)
							(end -0.2032 -0.3048)
						)
						(arc
							(start 0.2032 -0.3048)
							(mid 0.275042 -0.275042)
							(end 0.3048 -0.2032)
						)
					)
					(width 0)
					(fill yes)
				)
			)
		)
		(pad "2" smd custom
			(at 0 0.4445 270)
			(size 0.1524 0.1524)
			(layers "B.Cu" "B.Mask" "B.Paste")
			(net "GND")
			(options
				(clearance outline)
				(anchor circle)
			)
			(primitives
				(gr_poly
					(pts
						(arc
							(start 0.3048 0.2032)
							(mid 0.275042 0.275042)
							(end 0.2032 0.3048)
						)
						(arc
							(start -0.2032 0.3048)
							(mid -0.275042 0.275042)
							(end -0.3048 0.2032)
						)
						(arc
							(start -0.3048 -0.2032)
							(mid -0.275042 -0.275042)
							(end -0.2032 -0.3048)
						)
						(arc
							(start 0.2032 -0.3048)
							(mid 0.275042 -0.275042)
							(end 0.3048 -0.2032)
						)
					)
					(width 0)
					(fill yes)
				)
			)
		)
	)
	(footprint ""
		(layer "B.Cu")
		(at 180.5432 -54.9402)
		(property "Reference" "R394"
			(at 0 0 0)
			(layer "B.SilkS")
			(hide yes)
			(effects
				(font
					(size 1.27 1.27)
				)
				(justify mirror)
			)
		)
		(property "Value" "10KR2F-2-GP"
			(at -0.064008 -3.993896 0)
			(unlocked yes)
			(layer "B.Fab")
			(hide yes)
			(effects
				(font
					(size 1.016 1.016)
					(thickness 0.1524)
				)
				(justify mirror)
			)
		)
		(property "Device Type" "R402H16"
			(at -0.064008 -5.517896 0)
			(unlocked yes)
			(layer "B.Fab")
			(hide yes)
			(effects
				(font
					(size 1.016 1.016)
					(thickness 0.1524)
				)
				(justify mirror)
			)
		)
		(duplicate_pad_numbers_are_jumpers no)
		(fp_line
			(start -0.508 -0.9398)
			(end 0.508 -0.9398)
			(stroke
				(width 0.1524)
				(type default)
			)
			(layer "B.SilkS")
		)
		(fp_line
			(start 0.508 -0.9398)
			(end 0.508 0.9398)
			(stroke
				(width 0.1524)
				(type default)
			)
			(layer "B.SilkS")
		)
		(fp_rect
			(start 0.508 0.9398)
			(end -0.508 -0.9398)
			(stroke
				(width 0)
				(type default)
			)
			(fill no)
			(layer "B.CrtYd")
		)
		(fp_rect
			(start 0.508 0.9398)
			(end -0.508 -0.9398)
			(stroke
				(width 0)
				(type default)
			)
			(fill no)
			(layer "B.Fab")
		)
		(pad "1" smd custom
			(at 0 -0.4445 180)
			(size 0.1397 0.1397)
			(layers "B.Cu" "B.Mask" "B.Paste")
			(net "P1V8_C")
			(options
				(clearance outline)
				(anchor circle)
			)
			(primitives
				(gr_poly
					(pts
						(arc
							(start -0.1778 0.2794)
							(mid -0.249642 0.249642)
							(end -0.2794 0.1778)
						)
						(arc
							(start -0.2794 -0.1778)
							(mid -0.249642 -0.249642)
							(end -0.1778 -0.2794)
						)
						(arc
							(start 0.1778 -0.2794)
							(mid 0.249642 -0.249642)
							(end 0.2794 -0.1778)
						)
						(arc
							(start 0.2794 0.1778)
							(mid 0.249642 0.249642)
							(end 0.1778 0.2794)
						)
					)
					(width 0)
					(fill yes)
				)
			)
		)
		(pad "2" smd custom
			(at 0 0.4445 180)
			(size 0.1397 0.1397)
			(layers "B.Cu" "B.Mask" "B.Paste")
			(net "XM_OE_N")
			(options
				(clearance outline)
				(anchor circle)
			)
			(primitives
				(gr_poly
					(pts
						(arc
							(start -0.1778 0.2794)
							(mid -0.249642 0.249642)
							(end -0.2794 0.1778)
						)
						(arc
							(start -0.2794 -0.1778)
							(mid -0.249642 -0.249642)
							(end -0.1778 -0.2794)
						)
						(arc
							(start 0.1778 -0.2794)
							(mid 0.249642 -0.249642)
							(end 0.2794 -0.1778)
						)
						(arc
							(start 0.2794 0.1778)
							(mid 0.249642 0.249642)
							(end 0.1778 0.2794)
						)
					)
					(width 0)
					(fill yes)
				)
			)
		)
	)
	(footprint ""
		(layer "B.Cu")
		(at 107.061 -84.455 180)
		(property "Reference" "R107"
			(at 0 0 0)
			(layer "B.SilkS")
			(hide yes)
			(effects
				(font
					(size 1.27 1.27)
				)
				(justify mirror)
			)
		)
		(property "Value" "4K75R2F-1-GP"
			(at -0.064008 -3.993896 180)
			(unlocked yes)
			(layer "B.Fab")
			(hide yes)
			(effects
				(font
					(size 1.016 1.016)
					(thickness 0.1524)
				)
				(justify mirror)
			)
		)
		(property "Device Type" "R402H16"
			(at -0.064008 -5.517896 180)
			(unlocked yes)
			(layer "B.Fab")
			(hide yes)
			(effects
				(font
					(size 1.016 1.016)
					(thickness 0.1524)
				)
				(justify mirror)
			)
		)
		(duplicate_pad_numbers_are_jumpers no)
		(fp_line
			(start 0.508 -0.9398)
			(end 0.508 0.9398)
			(stroke
				(width 0.1524)
				(type default)
			)
			(layer "B.SilkS")
		)
		(fp_line
			(start -0.508 -0.9398)
			(end 0.508 -0.9398)
			(stroke
				(width 0.1524)
				(type default)
			)
			(layer "B.SilkS")
		)
		(fp_rect
			(start 0.508 0.9398)
			(end -0.508 -0.9398)
			(stroke
				(width 0)
				(type default)
			)
			(fill no)
			(layer "B.CrtYd")
		)
		(fp_rect
			(start 0.508 0.9398)
			(end -0.508 -0.9398)
			(stroke
				(width 0)
				(type default)
			)
			(fill no)
			(layer "B.Fab")
		)
		(pad "1" smd custom
			(at 0 -0.4445)
			(size 0.1397 0.1397)
			(layers "B.Cu" "B.Mask" "B.Paste")
			(net "LSI_TRST_N")
			(options
				(clearance outline)
				(anchor circle)
			)
			(primitives
				(gr_poly
					(pts
						(arc
							(start -0.1778 0.2794)
							(mid -0.249642 0.249642)
							(end -0.2794 0.1778)
						)
						(arc
							(start -0.2794 -0.1778)
							(mid -0.249642 -0.249642)
							(end -0.1778 -0.2794)
						)
						(arc
							(start 0.1778 -0.2794)
							(mid 0.249642 -0.249642)
							(end 0.2794 -0.1778)
						)
						(arc
							(start 0.2794 0.1778)
							(mid 0.249642 0.249642)
							(end 0.1778 0.2794)
						)
					)
					(width 0)
					(fill yes)
				)
			)
		)
		(pad "2" smd custom
			(at 0 0.4445)
			(size 0.1397 0.1397)
			(layers "B.Cu" "B.Mask" "B.Paste")
			(net "GND")
			(options
				(clearance outline)
				(anchor circle)
			)
			(primitives
				(gr_poly
					(pts
						(arc
							(start -0.1778 0.2794)
							(mid -0.249642 0.249642)
							(end -0.2794 0.1778)
						)
						(arc
							(start -0.2794 -0.1778)
							(mid -0.249642 -0.249642)
							(end -0.1778 -0.2794)
						)
						(arc
							(start 0.1778 -0.2794)
							(mid 0.249642 -0.249642)
							(end 0.2794 -0.1778)
						)
						(arc
							(start 0.2794 0.1778)
							(mid 0.249642 0.249642)
							(end 0.1778 0.2794)
						)
					)
					(width 0)
					(fill yes)
				)
			)
		)
	)
	(footprint ""
		(layer "B.Cu")
		(at 111.2266 -71.9074)
		(property "Reference" "C130"
			(at 0 0 0)
			(layer "B.SilkS")
			(hide yes)
			(effects
				(font
					(size 1.27 1.27)
				)
				(justify mirror)
			)
		)
		(property "Value" "SCD1U6D3V1KX-GP"
			(at 2.8321 -1.7399 0)
			(unlocked yes)
			(layer "B.Fab")
			(hide yes)
			(effects
				(font
					(size 1.016 1.016)
					(thickness 0.1524)
				)
				(justify mirror)
			)
		)
		(property "Device Type" "C0201H13"
			(at 2.8321 -3.2639 0)
			(unlocked yes)
			(layer "B.Fab")
			(hide yes)
			(effects
				(font
					(size 1.016 1.016)
					(thickness 0.1524)
				)
				(justify mirror)
			)
		)
		(duplicate_pad_numbers_are_jumpers no)
		(fp_rect
			(start 0.2794 0.6477)
			(end -0.2794 -0.6477)
			(stroke
				(width 0)
				(type default)
			)
			(fill no)
			(layer "B.CrtYd")
		)
		(fp_rect
			(start 0.2794 0.6477)
			(end -0.2794 -0.6477)
			(stroke
				(width 0)
				(type default)
			)
			(fill no)
			(layer "B.Fab")
		)
		(pad "1" smd custom
			(at 0 -0.2794 180)
			(size 0.0762 0.0762)
			(layers "B.Cu" "B.Mask" "B.Paste")
			(net "P1V8_E")
			(options
				(clearance outline)
				(anchor circle)
			)
			(primitives
				(gr_poly
					(pts
						(arc
							(start 0.1524 0.127)
							(mid 0.137521 0.162921)
							(end 0.1016 0.1778)
						)
						(arc
							(start -0.1016 0.1778)
							(mid -0.137521 0.162921)
							(end -0.1524 0.127)
						)
						(arc
							(start -0.1524 -0.127)
							(mid -0.137521 -0.162921)
							(end -0.1016 -0.1778)
						)
						(arc
							(start 0.1016 -0.1778)
							(mid 0.137521 -0.162921)
							(end 0.1524 -0.127)
						)
					)
					(width 0)
					(fill yes)
				)
			)
		)
		(pad "2" smd custom
			(at 0 0.2794 180)
			(size 0.0762 0.0762)
			(layers "B.Cu" "B.Mask" "B.Paste")
			(net "GND")
			(options
				(clearance outline)
				(anchor circle)
			)
			(primitives
				(gr_poly
					(pts
						(arc
							(start 0.1524 0.127)
							(mid 0.137521 0.162921)
							(end 0.1016 0.1778)
						)
						(arc
							(start -0.1016 0.1778)
							(mid -0.137521 0.162921)
							(end -0.1524 0.127)
						)
						(arc
							(start -0.1524 -0.127)
							(mid -0.137521 -0.162921)
							(end -0.1016 -0.1778)
						)
						(arc
							(start 0.1016 -0.1778)
							(mid 0.137521 -0.162921)
							(end 0.1524 -0.127)
						)
					)
					(width 0)
					(fill yes)
				)
			)
		)
	)
	(footprint ""
		(layer "B.Cu")
		(at 110.5916 -71.9074)
		(property "Reference" "C135"
			(at 0 0 0)
			(layer "B.SilkS")
			(hide yes)
			(effects
				(font
					(size 1.27 1.27)
				)
				(justify mirror)
			)
		)
		(property "Value" "SCD1U6D3V1KX-GP"
			(at 2.8321 -1.7399 0)
			(unlocked yes)
			(layer "B.Fab")
			(hide yes)
			(effects
				(font
					(size 1.016 1.016)
					(thickness 0.1524)
				)
				(justify mirror)
			)
		)
		(property "Device Type" "C0201H13"
			(at 2.8321 -3.2639 0)
			(unlocked yes)
			(layer "B.Fab")
			(hide yes)
			(effects
				(font
					(size 1.016 1.016)
					(thickness 0.1524)
				)
				(justify mirror)
			)
		)
		(duplicate_pad_numbers_are_jumpers no)
		(fp_rect
			(start 0.2794 0.6477)
			(end -0.2794 -0.6477)
			(stroke
				(width 0)
				(type default)
			)
			(fill no)
			(layer "B.CrtYd")
		)
		(fp_rect
			(start 0.2794 0.6477)
			(end -0.2794 -0.6477)
			(stroke
				(width 0)
				(type default)
			)
			(fill no)
			(layer "B.Fab")
		)
		(pad "1" smd custom
			(at 0 -0.2794 180)
			(size 0.0762 0.0762)
			(layers "B.Cu" "B.Mask" "B.Paste")
			(net "P1V8_E")
			(options
				(clearance outline)
				(anchor circle)
			)
			(primitives
				(gr_poly
					(pts
						(arc
							(start 0.1524 0.127)
							(mid 0.137521 0.162921)
							(end 0.1016 0.1778)
						)
						(arc
							(start -0.1016 0.1778)
							(mid -0.137521 0.162921)
							(end -0.1524 0.127)
						)
						(arc
							(start -0.1524 -0.127)
							(mid -0.137521 -0.162921)
							(end -0.1016 -0.1778)
						)
						(arc
							(start 0.1016 -0.1778)
							(mid 0.137521 -0.162921)
							(end 0.1524 -0.127)
						)
					)
					(width 0)
					(fill yes)
				)
			)
		)
		(pad "2" smd custom
			(at 0 0.2794 180)
			(size 0.0762 0.0762)
			(layers "B.Cu" "B.Mask" "B.Paste")
			(net "GND")
			(options
				(clearance outline)
				(anchor circle)
			)
			(primitives
				(gr_poly
					(pts
						(arc
							(start 0.1524 0.127)
							(mid 0.137521 0.162921)
							(end 0.1016 0.1778)
						)
						(arc
							(start -0.1016 0.1778)
							(mid -0.137521 0.162921)
							(end -0.1524 0.127)
						)
						(arc
							(start -0.1524 -0.127)
							(mid -0.137521 -0.162921)
							(end -0.1016 -0.1778)
						)
						(arc
							(start 0.1016 -0.1778)
							(mid 0.137521 -0.162921)
							(end 0.1524 -0.127)
						)
					)
					(width 0)
					(fill yes)
				)
			)
		)
	)
	(footprint ""
		(layer "B.Cu")
		(at 131.6736 -116.0272 -90)
		(property "Reference" "C689"
			(at 0 0 90)
			(layer "B.SilkS")
			(hide yes)
			(effects
				(font
					(size 1.27 1.27)
				)
				(justify mirror)
			)
		)
		(property "Value" "SCD1U16V2KX-3GP"
			(at -1.1811 -2.7051 270)
			(unlocked yes)
			(layer "B.Fab")
			(hide yes)
			(effects
				(font
					(size 1.016 1.016)
					(thickness 0.1524)
				)
				(justify mirror)
			)
		)
		(property "Device Type" "C402H22"
			(at -1.1811 -4.2291 270)
			(unlocked yes)
			(layer "B.Fab")
			(hide yes)
			(effects
				(font
					(size 1.016 1.016)
					(thickness 0.1524)
				)
				(justify mirror)
			)
		)
		(duplicate_pad_numbers_are_jumpers no)
		(fp_rect
			(start 0.4318 0.9525)
			(end -0.4318 -0.9525)
			(stroke
				(width 0)
				(type default)
			)
			(fill no)
			(layer "B.CrtYd")
		)
		(fp_rect
			(start 0.4318 0.9525)
			(end -0.4318 -0.9525)
			(stroke
				(width 0)
				(type default)
			)
			(fill no)
			(layer "B.Fab")
		)
		(pad "1" smd custom
			(at 0 -0.4445 90)
			(size 0.1524 0.1524)
			(layers "B.Cu" "B.Mask" "B.Paste")
			(net "P1V5_C")
			(options
				(clearance outline)
				(anchor circle)
			)
			(primitives
				(gr_poly
					(pts
						(arc
							(start 0.3048 0.2032)
							(mid 0.275042 0.275042)
							(end 0.2032 0.3048)
						)
						(arc
							(start -0.2032 0.3048)
							(mid -0.275042 0.275042)
							(end -0.3048 0.2032)
						)
						(arc
							(start -0.3048 -0.2032)
							(mid -0.275042 -0.275042)
							(end -0.2032 -0.3048)
						)
						(arc
							(start 0.2032 -0.3048)
							(mid 0.275042 -0.275042)
							(end 0.3048 -0.2032)
						)
					)
					(width 0)
					(fill yes)
				)
			)
		)
		(pad "2" smd custom
			(at 0 0.4445 90)
			(size 0.1524 0.1524)
			(layers "B.Cu" "B.Mask" "B.Paste")
			(net "GND")
			(options
				(clearance outline)
				(anchor circle)
			)
			(primitives
				(gr_poly
					(pts
						(arc
							(start 0.3048 0.2032)
							(mid 0.275042 0.275042)
							(end 0.2032 0.3048)
						)
						(arc
							(start -0.2032 0.3048)
							(mid -0.275042 0.275042)
							(end -0.3048 0.2032)
						)
						(arc
							(start -0.3048 -0.2032)
							(mid -0.275042 -0.275042)
							(end -0.2032 -0.3048)
						)
						(arc
							(start 0.2032 -0.3048)
							(mid 0.275042 -0.275042)
							(end 0.3048 -0.2032)
						)
					)
					(width 0)
					(fill yes)
				)
			)
		)
	)
	(footprint ""
		(layer "B.Cu")
		(at 122.4788 -71.5137 -90)
		(property "Reference" "C531"
			(at 0 0 90)
			(layer "B.SilkS")
			(hide yes)
			(effects
				(font
					(size 1.27 1.27)
				)
				(justify mirror)
			)
		)
		(property "Value" "SCD1U6D3V1KX-GP"
			(at 2.8321 -1.7399 270)
			(unlocked yes)
			(layer "B.Fab")
			(hide yes)
			(effects
				(font
					(size 1.016 1.016)
					(thickness 0.1524)
				)
				(justify mirror)
			)
		)
		(property "Device Type" "C0201H13"
			(at 2.8321 -3.2639 270)
			(unlocked yes)
			(layer "B.Fab")
			(hide yes)
			(effects
				(font
					(size 1.016 1.016)
					(thickness 0.1524)
				)
				(justify mirror)
			)
		)
		(duplicate_pad_numbers_are_jumpers no)
		(fp_rect
			(start 0.2794 0.6477)
			(end -0.2794 -0.6477)
			(stroke
				(width 0)
				(type default)
			)
			(fill no)
			(layer "B.CrtYd")
		)
		(fp_rect
			(start 0.2794 0.6477)
			(end -0.2794 -0.6477)
			(stroke
				(width 0)
				(type default)
			)
			(fill no)
			(layer "B.Fab")
		)
		(pad "1" smd custom
			(at 0 -0.2794 90)
			(size 0.0762 0.0762)
			(layers "B.Cu" "B.Mask" "B.Paste")
			(net "GB_VDDA")
			(options
				(clearance outline)
				(anchor circle)
			)
			(primitives
				(gr_poly
					(pts
						(arc
							(start 0.1524 0.127)
							(mid 0.137521 0.162921)
							(end 0.1016 0.1778)
						)
						(arc
							(start -0.1016 0.1778)
							(mid -0.137521 0.162921)
							(end -0.1524 0.127)
						)
						(arc
							(start -0.1524 -0.127)
							(mid -0.137521 -0.162921)
							(end -0.1016 -0.1778)
						)
						(arc
							(start 0.1016 -0.1778)
							(mid 0.137521 -0.162921)
							(end 0.1524 -0.127)
						)
					)
					(width 0)
					(fill yes)
				)
			)
		)
		(pad "2" smd custom
			(at 0 0.2794 90)
			(size 0.0762 0.0762)
			(layers "B.Cu" "B.Mask" "B.Paste")
			(net "GND")
			(options
				(clearance outline)
				(anchor circle)
			)
			(primitives
				(gr_poly
					(pts
						(arc
							(start 0.1524 0.127)
							(mid 0.137521 0.162921)
							(end 0.1016 0.1778)
						)
						(arc
							(start -0.1016 0.1778)
							(mid -0.137521 0.162921)
							(end -0.1524 0.127)
						)
						(arc
							(start -0.1524 -0.127)
							(mid -0.137521 -0.162921)
							(end -0.1016 -0.1778)
						)
						(arc
							(start 0.1016 -0.1778)
							(mid 0.137521 -0.162921)
							(end 0.1524 -0.127)
						)
					)
					(width 0)
					(fill yes)
				)
			)
		)
	)
	(footprint ""
		(layer "B.Cu")
		(at 183.144668 -36.87191 -90)
		(property "Reference" "C474"
			(at 0 0 90)
			(layer "B.SilkS")
			(hide yes)
			(effects
				(font
					(size 1.27 1.27)
				)
				(justify mirror)
			)
		)
		(property "Value" "SCD1U6D3V1KX-GP"
			(at 2.8321 -1.7399 270)
			(unlocked yes)
			(layer "B.Fab")
			(hide yes)
			(effects
				(font
					(size 1.016 1.016)
					(thickness 0.1524)
				)
				(justify mirror)
			)
		)
		(property "Device Type" "C0201H13"
			(at 2.8321 -3.2639 270)
			(unlocked yes)
			(layer "B.Fab")
			(hide yes)
			(effects
				(font
					(size 1.016 1.016)
					(thickness 0.1524)
				)
				(justify mirror)
			)
		)
		(duplicate_pad_numbers_are_jumpers no)
		(fp_rect
			(start 0.2794 0.6477)
			(end -0.2794 -0.6477)
			(stroke
				(width 0)
				(type default)
			)
			(fill no)
			(layer "B.CrtYd")
		)
		(fp_rect
			(start 0.2794 0.6477)
			(end -0.2794 -0.6477)
			(stroke
				(width 0)
				(type default)
			)
			(fill no)
			(layer "B.Fab")
		)
		(pad "1" smd custom
			(at 0 -0.2794 90)
			(size 0.0762 0.0762)
			(layers "B.Cu" "B.Mask" "B.Paste")
			(net "P1V8_C")
			(options
				(clearance outline)
				(anchor circle)
			)
			(primitives
				(gr_poly
					(pts
						(arc
							(start 0.1524 0.127)
							(mid 0.137521 0.162921)
							(end 0.1016 0.1778)
						)
						(arc
							(start -0.1016 0.1778)
							(mid -0.137521 0.162921)
							(end -0.1524 0.127)
						)
						(arc
							(start -0.1524 -0.127)
							(mid -0.137521 -0.162921)
							(end -0.1016 -0.1778)
						)
						(arc
							(start 0.1016 -0.1778)
							(mid 0.137521 -0.162921)
							(end 0.1524 -0.127)
						)
					)
					(width 0)
					(fill yes)
				)
			)
		)
		(pad "2" smd custom
			(at 0 0.2794 90)
			(size 0.0762 0.0762)
			(layers "B.Cu" "B.Mask" "B.Paste")
			(net "GND")
			(options
				(clearance outline)
				(anchor circle)
			)
			(primitives
				(gr_poly
					(pts
						(arc
							(start 0.1524 0.127)
							(mid 0.137521 0.162921)
							(end 0.1016 0.1778)
						)
						(arc
							(start -0.1016 0.1778)
							(mid -0.137521 0.162921)
							(end -0.1524 0.127)
						)
						(arc
							(start -0.1524 -0.127)
							(mid -0.137521 -0.162921)
							(end -0.1016 -0.1778)
						)
						(arc
							(start 0.1016 -0.1778)
							(mid 0.137521 -0.162921)
							(end 0.1524 -0.127)
						)
					)
					(width 0)
					(fill yes)
				)
			)
		)
	)
	(footprint ""
		(layer "B.Cu")
		(at 127.970788 -56.5023 -90)
		(property "Reference" "C229"
			(at 0 0 90)
			(layer "B.SilkS")
			(hide yes)
			(effects
				(font
					(size 1.27 1.27)
				)
				(justify mirror)
			)
		)
		(property "Value" "SC1U6D3V1MX-GP"
			(at -1.9177 2.0193 270)
			(unlocked yes)
			(layer "B.Fab")
			(hide yes)
			(effects
				(font
					(size 1.016 1.016)
					(thickness 0.1524)
				)
				(justify mirror)
			)
		)
		(property "Device Type" "C0201H14"
			(at -1.9177 0.4953 270)
			(unlocked yes)
			(layer "B.Fab")
			(hide yes)
			(effects
				(font
					(size 1.016 1.016)
					(thickness 0.1524)
				)
				(justify mirror)
			)
		)
		(duplicate_pad_numbers_are_jumpers no)
		(fp_rect
			(start 0.1524 0.3048)
			(end -0.1524 -0.3048)
			(stroke
				(width 0)
				(type default)
			)
			(fill no)
			(layer "B.CrtYd")
		)
		(fp_poly
			(pts
				(xy 0.2794 0.6477) (xy 0.2794 -0.6477) (xy -0.2794 -0.6477) (xy -0.2794 -0.1905) (xy -0.1524 -0.1905)
				(xy -0.1524 -0.3048) (xy 0.1524 -0.3048) (xy 0.1524 0.3048) (xy -0.1524 0.3048) (xy -0.1524 -0.1778)
				(xy -0.2794 -0.1778) (xy -0.2794 0.6477)
			)
			(stroke
				(width 0)
				(type default)
			)
			(fill no)
			(layer "B.CrtYd")
		)
		(fp_rect
			(start 0.2794 0.6477)
			(end -0.2794 -0.6477)
			(stroke
				(width 0)
				(type default)
			)
			(fill no)
			(layer "B.Fab")
		)
		(pad "1" smd custom
			(at 0 -0.2794 90)
			(size 0.0762 0.0762)
			(layers "B.Cu" "B.Mask" "B.Paste")
			(net "GB_VDDA")
			(options
				(clearance outline)
				(anchor circle)
			)
			(primitives
				(gr_poly
					(pts
						(arc
							(start 0.1524 0.127)
							(mid 0.137521 0.162921)
							(end 0.1016 0.1778)
						)
						(arc
							(start -0.1016 0.1778)
							(mid -0.137521 0.162921)
							(end -0.1524 0.127)
						)
						(arc
							(start -0.1524 -0.127)
							(mid -0.137521 -0.162921)
							(end -0.1016 -0.1778)
						)
						(arc
							(start 0.1016 -0.1778)
							(mid 0.137521 -0.162921)
							(end 0.1524 -0.127)
						)
					)
					(width 0)
					(fill yes)
				)
			)
		)
		(pad "2" smd custom
			(at 0 0.2794 90)
			(size 0.0762 0.0762)
			(layers "B.Cu" "B.Mask" "B.Paste")
			(net "GND")
			(options
				(clearance outline)
				(anchor circle)
			)
			(primitives
				(gr_poly
					(pts
						(arc
							(start 0.1524 0.127)
							(mid 0.137521 0.162921)
							(end 0.1016 0.1778)
						)
						(arc
							(start -0.1016 0.1778)
							(mid -0.137521 0.162921)
							(end -0.1524 0.127)
						)
						(arc
							(start -0.1524 -0.127)
							(mid -0.137521 -0.162921)
							(end -0.1016 -0.1778)
						)
						(arc
							(start 0.1016 -0.1778)
							(mid 0.137521 -0.162921)
							(end 0.1524 -0.127)
						)
					)
					(width 0)
					(fill yes)
				)
			)
		)
	)
	(footprint ""
		(layer "B.Cu")
		(at 169.926 -62.992 180)
		(property "Reference" "C212"
			(at 0 0 0)
			(layer "B.SilkS")
			(hide yes)
			(effects
				(font
					(size 1.27 1.27)
				)
				(justify mirror)
			)
		)
		(property "Value" "SCD1U16V2KX-3GP"
			(at -1.1811 -2.7051 180)
			(unlocked yes)
			(layer "B.Fab")
			(hide yes)
			(effects
				(font
					(size 1.016 1.016)
					(thickness 0.1524)
				)
				(justify mirror)
			)
		)
		(property "Device Type" "C402H22"
			(at -1.1811 -4.2291 180)
			(unlocked yes)
			(layer "B.Fab")
			(hide yes)
			(effects
				(font
					(size 1.016 1.016)
					(thickness 0.1524)
				)
				(justify mirror)
			)
		)
		(duplicate_pad_numbers_are_jumpers no)
		(fp_rect
			(start 0.4318 0.9525)
			(end -0.4318 -0.9525)
			(stroke
				(width 0)
				(type default)
			)
			(fill no)
			(layer "B.CrtYd")
		)
		(fp_rect
			(start 0.4318 0.9525)
			(end -0.4318 -0.9525)
			(stroke
				(width 0)
				(type default)
			)
			(fill no)
			(layer "B.Fab")
		)
		(pad "1" smd custom
			(at 0 -0.4445)
			(size 0.1524 0.1524)
			(layers "B.Cu" "B.Mask" "B.Paste")
			(net "P3V3")
			(options
				(clearance outline)
				(anchor circle)
			)
			(primitives
				(gr_poly
					(pts
						(arc
							(start 0.3048 0.2032)
							(mid 0.275042 0.275042)
							(end 0.2032 0.3048)
						)
						(arc
							(start -0.2032 0.3048)
							(mid -0.275042 0.275042)
							(end -0.3048 0.2032)
						)
						(arc
							(start -0.3048 -0.2032)
							(mid -0.275042 -0.275042)
							(end -0.2032 -0.3048)
						)
						(arc
							(start 0.2032 -0.3048)
							(mid 0.275042 -0.275042)
							(end 0.3048 -0.2032)
						)
					)
					(width 0)
					(fill yes)
				)
			)
		)
		(pad "2" smd custom
			(at 0 0.4445)
			(size 0.1524 0.1524)
			(layers "B.Cu" "B.Mask" "B.Paste")
			(net "GND")
			(options
				(clearance outline)
				(anchor circle)
			)
			(primitives
				(gr_poly
					(pts
						(arc
							(start 0.3048 0.2032)
							(mid 0.275042 0.275042)
							(end 0.2032 0.3048)
						)
						(arc
							(start -0.2032 0.3048)
							(mid -0.275042 0.275042)
							(end -0.3048 0.2032)
						)
						(arc
							(start -0.3048 -0.2032)
							(mid -0.275042 -0.275042)
							(end -0.2032 -0.3048)
						)
						(arc
							(start 0.2032 -0.3048)
							(mid 0.275042 -0.275042)
							(end 0.3048 -0.2032)
						)
					)
					(width 0)
					(fill yes)
				)
			)
		)
	)
	(footprint ""
		(layer "B.Cu")
		(at 124.039376 -90.137742 90)
		(property "Reference" "R307"
			(at 0 0 90)
			(layer "B.SilkS")
			(hide yes)
			(effects
				(font
					(size 1.27 1.27)
				)
				(justify mirror)
			)
		)
		(property "Value" "10KR2F-2-GP"
			(at -0.064008 -3.993896 90)
			(unlocked yes)
			(layer "B.Fab")
			(hide yes)
			(effects
				(font
					(size 1.016 1.016)
					(thickness 0.1524)
				)
				(justify mirror)
			)
		)
		(property "Device Type" "R402H16"
			(at -0.064008 -5.517896 90)
			(unlocked yes)
			(layer "B.Fab")
			(hide yes)
			(effects
				(font
					(size 1.016 1.016)
					(thickness 0.1524)
				)
				(justify mirror)
			)
		)
		(duplicate_pad_numbers_are_jumpers no)
		(fp_line
			(start 0.508 -0.9398)
			(end 0.508 0.9398)
			(stroke
				(width 0.1524)
				(type default)
			)
			(layer "B.SilkS")
		)
		(fp_line
			(start -0.508 -0.9398)
			(end 0.508 -0.9398)
			(stroke
				(width 0.1524)
				(type default)
			)
			(layer "B.SilkS")
		)
		(fp_rect
			(start 0.508 0.9398)
			(end -0.508 -0.9398)
			(stroke
				(width 0)
				(type default)
			)
			(fill no)
			(layer "B.CrtYd")
		)
		(fp_rect
			(start 0.508 0.9398)
			(end -0.508 -0.9398)
			(stroke
				(width 0)
				(type default)
			)
			(fill no)
			(layer "B.Fab")
		)
		(pad "1" smd custom
			(at 0 -0.4445 270)
			(size 0.1397 0.1397)
			(layers "B.Cu" "B.Mask" "B.Paste")
			(net "BMC_SPARE_0_LS")
			(options
				(clearance outline)
				(anchor circle)
			)
			(primitives
				(gr_poly
					(pts
						(arc
							(start -0.1778 0.2794)
							(mid -0.249642 0.249642)
							(end -0.2794 0.1778)
						)
						(arc
							(start -0.2794 -0.1778)
							(mid -0.249642 -0.249642)
							(end -0.1778 -0.2794)
						)
						(arc
							(start 0.1778 -0.2794)
							(mid 0.249642 -0.249642)
							(end 0.2794 -0.1778)
						)
						(arc
							(start 0.2794 0.1778)
							(mid 0.249642 0.249642)
							(end 0.1778 0.2794)
						)
					)
					(width 0)
					(fill yes)
				)
			)
		)
		(pad "2" smd custom
			(at 0 0.4445 270)
			(size 0.1397 0.1397)
			(layers "B.Cu" "B.Mask" "B.Paste")
			(net "GND")
			(options
				(clearance outline)
				(anchor circle)
			)
			(primitives
				(gr_poly
					(pts
						(arc
							(start -0.1778 0.2794)
							(mid -0.249642 0.249642)
							(end -0.2794 0.1778)
						)
						(arc
							(start -0.2794 -0.1778)
							(mid -0.249642 -0.249642)
							(end -0.1778 -0.2794)
						)
						(arc
							(start 0.1778 -0.2794)
							(mid 0.249642 -0.249642)
							(end 0.2794 -0.1778)
						)
						(arc
							(start 0.2794 0.1778)
							(mid 0.249642 0.249642)
							(end 0.1778 0.2794)
						)
					)
					(width 0)
					(fill yes)
				)
			)
		)
	)
	(footprint ""
		(layer "B.Cu")
		(at 111.499904 -78.49997)
		(property "Reference" "TP49"
			(at 0 0 0)
			(layer "B.SilkS")
			(hide yes)
			(effects
				(font
					(size 1.27 1.27)
				)
				(justify mirror)
			)
		)
		(property "Value" "TPAD28-2-GP"
			(at 0.0127 -1.6637 0)
			(unlocked yes)
			(layer "B.Fab")
			(hide yes)
			(effects
				(font
					(size 1.016 1.016)
					(thickness 0.1524)
				)
				(justify mirror)
			)
		)
		(property "Device Type" "TPAD28"
			(at 0.0127 -3.1877 0)
			(unlocked yes)
			(layer "B.Fab")
			(hide yes)
			(effects
				(font
					(size 1.016 1.016)
					(thickness 0.1524)
				)
				(justify mirror)
			)
		)
		(duplicate_pad_numbers_are_jumpers no)
		(fp_poly
			(pts
				(arc
					(start 0.3556 0)
					(mid -0.3556 0)
					(end 0.3556 0)
				)
			)
			(stroke
				(width 0)
				(type default)
			)
			(fill no)
			(layer "B.CrtYd")
		)
		(fp_poly
			(pts
				(arc
					(start 0.6096 0)
					(mid -0.6096 0)
					(end 0.6096 0)
				)
			)
			(stroke
				(width 0)
				(type default)
			)
			(fill no)
			(layer "B.Fab")
		)
		(pad "1" smd circle
			(at 0 0 180)
			(size 0.7112 0.7112)
			(layers "B.Cu" "B.Mask" "B.Paste")
			(net "XM_GP_CS_1#_TP")
		)
	)
	(footprint ""
		(layer "B.Cu")
		(at 137.4648 -72.9996 -90)
		(property "Reference" "C11"
			(at 0 0 90)
			(layer "B.SilkS")
			(hide yes)
			(effects
				(font
					(size 1.27 1.27)
				)
				(justify mirror)
			)
		)
		(property "Value" "SCD01U16V1KX-GP"
			(at 2.8321 -1.7399 270)
			(unlocked yes)
			(layer "B.Fab")
			(hide yes)
			(effects
				(font
					(size 1.016 1.016)
					(thickness 0.1524)
				)
				(justify mirror)
			)
		)
		(property "Device Type" "C0201H13"
			(at 2.8321 -3.2639 270)
			(unlocked yes)
			(layer "B.Fab")
			(hide yes)
			(effects
				(font
					(size 1.016 1.016)
					(thickness 0.1524)
				)
				(justify mirror)
			)
		)
		(duplicate_pad_numbers_are_jumpers no)
		(fp_rect
			(start 0.2794 0.6477)
			(end -0.2794 -0.6477)
			(stroke
				(width 0)
				(type default)
			)
			(fill no)
			(layer "B.CrtYd")
		)
		(fp_rect
			(start 0.2794 0.6477)
			(end -0.2794 -0.6477)
			(stroke
				(width 0)
				(type default)
			)
			(fill no)
			(layer "B.Fab")
		)
		(pad "1" smd custom
			(at 0 -0.2794 90)
			(size 0.0762 0.0762)
			(layers "B.Cu" "B.Mask" "B.Paste")
			(net "PHY_DPB_TO_SCC_6_DP")
			(options
				(clearance outline)
				(anchor circle)
			)
			(primitives
				(gr_poly
					(pts
						(arc
							(start 0.1524 0.127)
							(mid 0.137521 0.162921)
							(end 0.1016 0.1778)
						)
						(arc
							(start -0.1016 0.1778)
							(mid -0.137521 0.162921)
							(end -0.1524 0.127)
						)
						(arc
							(start -0.1524 -0.127)
							(mid -0.137521 -0.162921)
							(end -0.1016 -0.1778)
						)
						(arc
							(start 0.1016 -0.1778)
							(mid 0.137521 -0.162921)
							(end 0.1524 -0.127)
						)
					)
					(width 0)
					(fill yes)
				)
			)
		)
		(pad "2" smd custom
			(at 0 0.2794 90)
			(size 0.0762 0.0762)
			(layers "B.Cu" "B.Mask" "B.Paste")
			(net "PHY_DPB_TO_SCC_C_6_DP")
			(options
				(clearance outline)
				(anchor circle)
			)
			(primitives
				(gr_poly
					(pts
						(arc
							(start 0.1524 0.127)
							(mid 0.137521 0.162921)
							(end 0.1016 0.1778)
						)
						(arc
							(start -0.1016 0.1778)
							(mid -0.137521 0.162921)
							(end -0.1524 0.127)
						)
						(arc
							(start -0.1524 -0.127)
							(mid -0.137521 -0.162921)
							(end -0.1016 -0.1778)
						)
						(arc
							(start 0.1016 -0.1778)
							(mid 0.137521 -0.162921)
							(end 0.1524 -0.127)
						)
					)
					(width 0)
					(fill yes)
				)
			)
		)
	)
	(footprint ""
		(layer "B.Cu")
		(at 70.485 -41.402 90)
		(property "Reference" "R168"
			(at 0 0 90)
			(layer "B.SilkS")
			(hide yes)
			(effects
				(font
					(size 1.27 1.27)
				)
				(justify mirror)
			)
		)
		(property "Value" "D51R3F-2-GP"
			(at 0.0254 -2.5146 90)
			(unlocked yes)
			(layer "B.Fab")
			(hide yes)
			(effects
				(font
					(size 1.016 1.016)
					(thickness 0.1524)
				)
				(justify mirror)
			)
		)
		(property "Device Type" "R603H22"
			(at 0.0254 -4.0386 90)
			(unlocked yes)
			(layer "B.Fab")
			(hide yes)
			(effects
				(font
					(size 1.016 1.016)
					(thickness 0.1524)
				)
				(justify mirror)
			)
		)
		(duplicate_pad_numbers_are_jumpers no)
		(fp_line
			(start 0.4826 0)
			(end 0.2032 0)
			(stroke
				(width 0.2032)
				(type default)
			)
			(layer "B.SilkS")
		)
		(fp_line
			(start -0.2032 0)
			(end -0.4826 0)
			(stroke
				(width 0.2032)
				(type default)
			)
			(layer "B.SilkS")
		)
		(fp_rect
			(start 0.5842 1.3335)
			(end -0.5842 -1.3335)
			(stroke
				(width 0)
				(type default)
			)
			(fill no)
			(layer "B.CrtYd")
		)
		(fp_rect
			(start 0.5842 1.3335)
			(end -0.5842 -1.3335)
			(stroke
				(width 0)
				(type default)
			)
			(fill no)
			(layer "B.Fab")
		)
		(pad "1" smd custom
			(at 0 -0.762 270)
			(size 0.2159 0.2159)
			(layers "B.Cu" "B.Mask" "B.Paste")
			(net "P0V9")
			(options
				(clearance outline)
				(anchor circle)
			)
			(primitives
				(gr_poly
					(pts
						(arc
							(start -0.3302 0.4318)
							(mid -0.402042 0.402042)
							(end -0.4318 0.3302)
						)
						(arc
							(start -0.4318 -0.3302)
							(mid -0.402042 -0.402042)
							(end -0.3302 -0.4318)
						)
						(arc
							(start 0.3302 -0.4318)
							(mid 0.402042 -0.402042)
							(end 0.4318 -0.3302)
						)
						(arc
							(start 0.4318 0.3302)
							(mid 0.402042 0.402042)
							(end 0.3302 0.4318)
						)
					)
					(width 0)
					(fill yes)
				)
			)
		)
		(pad "2" smd custom
			(at 0 0.762 270)
			(size 0.2159 0.2159)
			(layers "B.Cu" "B.Mask" "B.Paste")
			(net "GB_VDDA")
			(options
				(clearance outline)
				(anchor circle)
			)
			(primitives
				(gr_poly
					(pts
						(arc
							(start -0.3302 0.4318)
							(mid -0.402042 0.402042)
							(end -0.4318 0.3302)
						)
						(arc
							(start -0.4318 -0.3302)
							(mid -0.402042 -0.402042)
							(end -0.3302 -0.4318)
						)
						(arc
							(start 0.3302 -0.4318)
							(mid 0.402042 -0.402042)
							(end 0.4318 -0.3302)
						)
						(arc
							(start 0.4318 0.3302)
							(mid 0.402042 0.402042)
							(end 0.3302 0.4318)
						)
					)
					(width 0)
					(fill yes)
				)
			)
		)
	)
	(footprint ""
		(layer "B.Cu")
		(at 146.2532 -122.7836 -90)
		(property "Reference" "R599"
			(at 0 0 90)
			(layer "B.SilkS")
			(hide yes)
			(effects
				(font
					(size 1.27 1.27)
				)
				(justify mirror)
			)
		)
		(property "Value" "4K7R2F-GP"
			(at -0.064008 -3.993896 270)
			(unlocked yes)
			(layer "B.Fab")
			(hide yes)
			(effects
				(font
					(size 1.016 1.016)
					(thickness 0.1524)
				)
				(justify mirror)
			)
		)
		(property "Device Type" "R402H16"
			(at -0.064008 -5.517896 270)
			(unlocked yes)
			(layer "B.Fab")
			(hide yes)
			(effects
				(font
					(size 1.016 1.016)
					(thickness 0.1524)
				)
				(justify mirror)
			)
		)
		(duplicate_pad_numbers_are_jumpers no)
		(fp_line
			(start -0.508 -0.9398)
			(end 0.508 -0.9398)
			(stroke
				(width 0.1524)
				(type default)
			)
			(layer "B.SilkS")
		)
		(fp_line
			(start 0.508 -0.9398)
			(end 0.508 0.9398)
			(stroke
				(width 0.1524)
				(type default)
			)
			(layer "B.SilkS")
		)
		(fp_rect
			(start 0.508 0.9398)
			(end -0.508 -0.9398)
			(stroke
				(width 0)
				(type default)
			)
			(fill no)
			(layer "B.CrtYd")
		)
		(fp_rect
			(start 0.508 0.9398)
			(end -0.508 -0.9398)
			(stroke
				(width 0)
				(type default)
			)
			(fill no)
			(layer "B.Fab")
		)
		(pad "1" smd custom
			(at 0 -0.4445 90)
			(size 0.1397 0.1397)
			(layers "B.Cu" "B.Mask" "B.Paste")
			(net "P3V3")
			(options
				(clearance outline)
				(anchor circle)
			)
			(primitives
				(gr_poly
					(pts
						(arc
							(start -0.1778 0.2794)
							(mid -0.249642 0.249642)
							(end -0.2794 0.1778)
						)
						(arc
							(start -0.2794 -0.1778)
							(mid -0.249642 -0.249642)
							(end -0.1778 -0.2794)
						)
						(arc
							(start 0.1778 -0.2794)
							(mid 0.249642 -0.249642)
							(end 0.2794 -0.1778)
						)
						(arc
							(start 0.2794 0.1778)
							(mid 0.249642 0.249642)
							(end 0.1778 0.2794)
						)
					)
					(width 0)
					(fill yes)
				)
			)
		)
		(pad "2" smd custom
			(at 0 0.4445 90)
			(size 0.1397 0.1397)
			(layers "B.Cu" "B.Mask" "B.Paste")
			(net "P1V5_C_PG_R_1")
			(options
				(clearance outline)
				(anchor circle)
			)
			(primitives
				(gr_poly
					(pts
						(arc
							(start -0.1778 0.2794)
							(mid -0.249642 0.249642)
							(end -0.2794 0.1778)
						)
						(arc
							(start -0.2794 -0.1778)
							(mid -0.249642 -0.249642)
							(end -0.1778 -0.2794)
						)
						(arc
							(start 0.1778 -0.2794)
							(mid 0.249642 -0.249642)
							(end 0.2794 -0.1778)
						)
						(arc
							(start 0.2794 0.1778)
							(mid 0.249642 0.249642)
							(end 0.1778 0.2794)
						)
					)
					(width 0)
					(fill yes)
				)
			)
		)
	)
	(footprint ""
		(layer "B.Cu")
		(at 199.4789 -21.844)
		(property "Reference" "R244"
			(at 0 0 0)
			(layer "B.SilkS")
			(hide yes)
			(effects
				(font
					(size 1.27 1.27)
				)
				(justify mirror)
			)
		)
		(property "Value" "4K7R2F-GP"
			(at -0.064008 -3.993896 0)
			(unlocked yes)
			(layer "B.Fab")
			(hide yes)
			(effects
				(font
					(size 1.016 1.016)
					(thickness 0.1524)
				)
				(justify mirror)
			)
		)
		(property "Device Type" "R402H16"
			(at -0.064008 -5.517896 0)
			(unlocked yes)
			(layer "B.Fab")
			(hide yes)
			(effects
				(font
					(size 1.016 1.016)
					(thickness 0.1524)
				)
				(justify mirror)
			)
		)
		(duplicate_pad_numbers_are_jumpers no)
		(fp_line
			(start -0.508 -0.9398)
			(end 0.508 -0.9398)
			(stroke
				(width 0.1524)
				(type default)
			)
			(layer "B.SilkS")
		)
		(fp_line
			(start 0.508 -0.9398)
			(end 0.508 0.9398)
			(stroke
				(width 0.1524)
				(type default)
			)
			(layer "B.SilkS")
		)
		(fp_rect
			(start 0.508 0.9398)
			(end -0.508 -0.9398)
			(stroke
				(width 0)
				(type default)
			)
			(fill no)
			(layer "B.CrtYd")
		)
		(fp_rect
			(start 0.508 0.9398)
			(end -0.508 -0.9398)
			(stroke
				(width 0)
				(type default)
			)
			(fill no)
			(layer "B.Fab")
		)
		(pad "1" smd custom
			(at 0 -0.4445 180)
			(size 0.1397 0.1397)
			(layers "B.Cu" "B.Mask" "B.Paste")
			(net "P3V3")
			(options
				(clearance outline)
				(anchor circle)
			)
			(primitives
				(gr_poly
					(pts
						(arc
							(start -0.1778 0.2794)
							(mid -0.249642 0.249642)
							(end -0.2794 0.1778)
						)
						(arc
							(start -0.2794 -0.1778)
							(mid -0.249642 -0.249642)
							(end -0.1778 -0.2794)
						)
						(arc
							(start 0.1778 -0.2794)
							(mid 0.249642 -0.249642)
							(end 0.2794 -0.1778)
						)
						(arc
							(start 0.2794 0.1778)
							(mid 0.249642 0.249642)
							(end 0.1778 0.2794)
						)
					)
					(width 0)
					(fill yes)
				)
			)
		)
		(pad "2" smd custom
			(at 0 0.4445 180)
			(size 0.1397 0.1397)
			(layers "B.Cu" "B.Mask" "B.Paste")
			(net "P3V3_STBY_R")
			(options
				(clearance outline)
				(anchor circle)
			)
			(primitives
				(gr_poly
					(pts
						(arc
							(start -0.1778 0.2794)
							(mid -0.249642 0.249642)
							(end -0.2794 0.1778)
						)
						(arc
							(start -0.2794 -0.1778)
							(mid -0.249642 -0.249642)
							(end -0.1778 -0.2794)
						)
						(arc
							(start 0.1778 -0.2794)
							(mid 0.249642 -0.249642)
							(end 0.2794 -0.1778)
						)
						(arc
							(start 0.2794 0.1778)
							(mid 0.249642 0.249642)
							(end 0.1778 0.2794)
						)
					)
					(width 0)
					(fill yes)
				)
			)
		)
	)
	(footprint ""
		(layer "B.Cu")
		(at 176.72558 -31.858966 90)
		(property "Reference" "TP58"
			(at 0 0 90)
			(layer "B.SilkS")
			(hide yes)
			(effects
				(font
					(size 1.27 1.27)
				)
				(justify mirror)
			)
		)
		(property "Value" "TPAD28-2-GP"
			(at 0.0127 -1.6637 90)
			(unlocked yes)
			(layer "B.Fab")
			(hide yes)
			(effects
				(font
					(size 1.016 1.016)
					(thickness 0.1524)
				)
				(justify mirror)
			)
		)
		(property "Device Type" "TPAD28"
			(at 0.0127 -3.1877 90)
			(unlocked yes)
			(layer "B.Fab")
			(hide yes)
			(effects
				(font
					(size 1.016 1.016)
					(thickness 0.1524)
				)
				(justify mirror)
			)
		)
		(duplicate_pad_numbers_are_jumpers no)
		(fp_poly
			(pts
				(arc
					(start 0 0.3556)
					(mid 0 -0.3556)
					(end 0 0.3556)
				)
			)
			(stroke
				(width 0)
				(type default)
			)
			(fill no)
			(layer "B.CrtYd")
		)
		(fp_poly
			(pts
				(arc
					(start 0 0.6096)
					(mid 0 -0.6096)
					(end 0 0.6096)
				)
			)
			(stroke
				(width 0)
				(type default)
			)
			(fill no)
			(layer "B.Fab")
		)
		(pad "1" smd circle
			(at 0 0 270)
			(size 0.7112 0.7112)
			(layers "B.Cu" "B.Mask" "B.Paste")
			(net "IOC_GPIO_7")
		)
	)
	(footprint ""
		(layer "B.Cu")
		(at 176.298098 -51.237896)
		(property "Reference" "TP137"
			(at 0 0 0)
			(layer "B.SilkS")
			(hide yes)
			(effects
				(font
					(size 1.27 1.27)
				)
				(justify mirror)
			)
		)
		(property "Value" "TPAD28-2-GP"
			(at 0.0127 -1.6637 0)
			(unlocked yes)
			(layer "B.Fab")
			(hide yes)
			(effects
				(font
					(size 1.016 1.016)
					(thickness 0.1524)
				)
				(justify mirror)
			)
		)
		(property "Device Type" "TPAD28"
			(at 0.0127 -3.1877 0)
			(unlocked yes)
			(layer "B.Fab")
			(hide yes)
			(effects
				(font
					(size 1.016 1.016)
					(thickness 0.1524)
				)
				(justify mirror)
			)
		)
		(duplicate_pad_numbers_are_jumpers no)
		(fp_poly
			(pts
				(arc
					(start 0.3556 0)
					(mid -0.3556 0)
					(end 0.3556 0)
				)
			)
			(stroke
				(width 0)
				(type default)
			)
			(fill no)
			(layer "B.CrtYd")
		)
		(fp_poly
			(pts
				(arc
					(start 0.6096 0)
					(mid -0.6096 0)
					(end 0.6096 0)
				)
			)
			(stroke
				(width 0)
				(type default)
			)
			(fill no)
			(layer "B.Fab")
		)
		(pad "1" smd circle
			(at 0 0 180)
			(size 0.7112 0.7112)
			(layers "B.Cu" "B.Mask" "B.Paste")
			(net "IOC_TDO")
		)
	)
	(footprint ""
		(layer "B.Cu")
		(at 110.494572 -64.287654 -90)
		(property "Reference" "C184"
			(at 0 0 90)
			(layer "B.SilkS")
			(hide yes)
			(effects
				(font
					(size 1.27 1.27)
				)
				(justify mirror)
			)
		)
		(property "Value" "SC10U6D3V2MX-GP-U"
			(at 1.524 -1.905 270)
			(unlocked yes)
			(layer "B.Fab")
			(hide yes)
			(effects
				(font
					(size 1.016 1.016)
					(thickness 0.1524)
				)
				(justify mirror)
			)
		)
		(property "Device Type" "C402-TO0D2H28"
			(at 1.524 -3.429 270)
			(unlocked yes)
			(layer "B.Fab")
			(hide yes)
			(effects
				(font
					(size 1.016 1.016)
					(thickness 0.1524)
				)
				(justify mirror)
			)
		)
		(duplicate_pad_numbers_are_jumpers no)
		(fp_rect
			(start 0.4826 0.889)
			(end -0.4826 -0.889)
			(stroke
				(width 0)
				(type default)
			)
			(fill no)
			(layer "B.CrtYd")
		)
		(fp_rect
			(start 0.4826 0.889)
			(end -0.4826 -0.889)
			(stroke
				(width 0)
				(type default)
			)
			(fill no)
			(layer "B.Fab")
		)
		(pad "1" smd custom
			(at 0 -0.4572 90)
			(size 0.1524 0.1524)
			(layers "B.Cu" "B.Mask" "B.Paste")
			(net "P0V9")
			(options
				(clearance outline)
				(anchor circle)
			)
			(primitives
				(gr_poly
					(pts
						(arc
							(start -0.254 -0.3048)
							(mid -0.325842 -0.275042)
							(end -0.3556 -0.2032)
						)
						(arc
							(start -0.3556 0.2032)
							(mid -0.325842 0.275042)
							(end -0.254 0.3048)
						)
						(arc
							(start 0.254 0.3048)
							(mid 0.325842 0.275042)
							(end 0.3556 0.2032)
						)
						(arc
							(start 0.3556 -0.2032)
							(mid 0.325842 -0.275042)
							(end 0.254 -0.3048)
						)
					)
					(width 0)
					(fill yes)
				)
			)
		)
		(pad "2" smd custom
			(at 0 0.4572 90)
			(size 0.1524 0.1524)
			(layers "B.Cu" "B.Mask" "B.Paste")
			(net "GND")
			(options
				(clearance outline)
				(anchor circle)
			)
			(primitives
				(gr_poly
					(pts
						(arc
							(start -0.254 -0.3048)
							(mid -0.325842 -0.275042)
							(end -0.3556 -0.2032)
						)
						(arc
							(start -0.3556 0.2032)
							(mid -0.325842 0.275042)
							(end -0.254 0.3048)
						)
						(arc
							(start 0.254 0.3048)
							(mid 0.325842 0.275042)
							(end 0.3556 0.2032)
						)
						(arc
							(start 0.3556 -0.2032)
							(mid 0.325842 -0.275042)
							(end 0.254 -0.3048)
						)
					)
					(width 0)
					(fill yes)
				)
			)
		)
	)
	(footprint ""
		(layer "B.Cu")
		(at 115.7732 -71.882508)
		(property "Reference" "C134"
			(at 0 0 0)
			(layer "B.SilkS")
			(hide yes)
			(effects
				(font
					(size 1.27 1.27)
				)
				(justify mirror)
			)
		)
		(property "Value" "SCD1U6D3V1KX-GP"
			(at 2.8321 -1.7399 0)
			(unlocked yes)
			(layer "B.Fab")
			(hide yes)
			(effects
				(font
					(size 1.016 1.016)
					(thickness 0.1524)
				)
				(justify mirror)
			)
		)
		(property "Device Type" "C0201H13"
			(at 2.8321 -3.2639 0)
			(unlocked yes)
			(layer "B.Fab")
			(hide yes)
			(effects
				(font
					(size 1.016 1.016)
					(thickness 0.1524)
				)
				(justify mirror)
			)
		)
		(duplicate_pad_numbers_are_jumpers no)
		(fp_rect
			(start 0.2794 0.6477)
			(end -0.2794 -0.6477)
			(stroke
				(width 0)
				(type default)
			)
			(fill no)
			(layer "B.CrtYd")
		)
		(fp_rect
			(start 0.2794 0.6477)
			(end -0.2794 -0.6477)
			(stroke
				(width 0)
				(type default)
			)
			(fill no)
			(layer "B.Fab")
		)
		(pad "1" smd custom
			(at 0 -0.2794 180)
			(size 0.0762 0.0762)
			(layers "B.Cu" "B.Mask" "B.Paste")
			(net "P1V8_E")
			(options
				(clearance outline)
				(anchor circle)
			)
			(primitives
				(gr_poly
					(pts
						(arc
							(start 0.1524 0.127)
							(mid 0.137521 0.162921)
							(end 0.1016 0.1778)
						)
						(arc
							(start -0.1016 0.1778)
							(mid -0.137521 0.162921)
							(end -0.1524 0.127)
						)
						(arc
							(start -0.1524 -0.127)
							(mid -0.137521 -0.162921)
							(end -0.1016 -0.1778)
						)
						(arc
							(start 0.1016 -0.1778)
							(mid 0.137521 -0.162921)
							(end 0.1524 -0.127)
						)
					)
					(width 0)
					(fill yes)
				)
			)
		)
		(pad "2" smd custom
			(at 0 0.2794 180)
			(size 0.0762 0.0762)
			(layers "B.Cu" "B.Mask" "B.Paste")
			(net "GND")
			(options
				(clearance outline)
				(anchor circle)
			)
			(primitives
				(gr_poly
					(pts
						(arc
							(start 0.1524 0.127)
							(mid 0.137521 0.162921)
							(end 0.1016 0.1778)
						)
						(arc
							(start -0.1016 0.1778)
							(mid -0.137521 0.162921)
							(end -0.1524 0.127)
						)
						(arc
							(start -0.1524 -0.127)
							(mid -0.137521 -0.162921)
							(end -0.1016 -0.1778)
						)
						(arc
							(start 0.1016 -0.1778)
							(mid 0.137521 -0.162921)
							(end 0.1524 -0.127)
						)
					)
					(width 0)
					(fill yes)
				)
			)
		)
	)
	(footprint ""
		(layer "B.Cu")
		(at 167.27932 -20.572984)
		(property "Reference" "C314"
			(at 0 0 0)
			(layer "B.SilkS")
			(hide yes)
			(effects
				(font
					(size 1.27 1.27)
				)
				(justify mirror)
			)
		)
		(property "Value" "SCD22U10V1KX-GP"
			(at 2.8321 -1.7399 0)
			(unlocked yes)
			(layer "B.Fab")
			(hide yes)
			(effects
				(font
					(size 1.016 1.016)
					(thickness 0.1524)
				)
				(justify mirror)
			)
		)
		(property "Device Type" "C0201H13"
			(at 2.8321 -3.2639 0)
			(unlocked yes)
			(layer "B.Fab")
			(hide yes)
			(effects
				(font
					(size 1.016 1.016)
					(thickness 0.1524)
				)
				(justify mirror)
			)
		)
		(duplicate_pad_numbers_are_jumpers no)
		(fp_rect
			(start 0.2794 0.6477)
			(end -0.2794 -0.6477)
			(stroke
				(width 0)
				(type default)
			)
			(fill no)
			(layer "B.CrtYd")
		)
		(fp_rect
			(start 0.2794 0.6477)
			(end -0.2794 -0.6477)
			(stroke
				(width 0)
				(type default)
			)
			(fill no)
			(layer "B.Fab")
		)
		(pad "1" smd custom
			(at 0 -0.2794 180)
			(size 0.0762 0.0762)
			(layers "B.Cu" "B.Mask" "B.Paste")
			(net "PCIE_SCC_TO_COMP_C_1_DN")
			(options
				(clearance outline)
				(anchor circle)
			)
			(primitives
				(gr_poly
					(pts
						(arc
							(start 0.1524 0.127)
							(mid 0.137521 0.162921)
							(end 0.1016 0.1778)
						)
						(arc
							(start -0.1016 0.1778)
							(mid -0.137521 0.162921)
							(end -0.1524 0.127)
						)
						(arc
							(start -0.1524 -0.127)
							(mid -0.137521 -0.162921)
							(end -0.1016 -0.1778)
						)
						(arc
							(start 0.1016 -0.1778)
							(mid 0.137521 -0.162921)
							(end 0.1524 -0.127)
						)
					)
					(width 0)
					(fill yes)
				)
			)
		)
		(pad "2" smd custom
			(at 0 0.2794 180)
			(size 0.0762 0.0762)
			(layers "B.Cu" "B.Mask" "B.Paste")
			(net "PCIE_SCC_TO_COMP_1_DN")
			(options
				(clearance outline)
				(anchor circle)
			)
			(primitives
				(gr_poly
					(pts
						(arc
							(start 0.1524 0.127)
							(mid 0.137521 0.162921)
							(end 0.1016 0.1778)
						)
						(arc
							(start -0.1016 0.1778)
							(mid -0.137521 0.162921)
							(end -0.1524 0.127)
						)
						(arc
							(start -0.1524 -0.127)
							(mid -0.137521 -0.162921)
							(end -0.1016 -0.1778)
						)
						(arc
							(start 0.1016 -0.1778)
							(mid 0.137521 -0.162921)
							(end 0.1524 -0.127)
						)
					)
					(width 0)
					(fill yes)
				)
			)
		)
	)
	(footprint ""
		(layer "B.Cu")
		(at 114.6302 -87.0204 180)
		(property "Reference" "R141"
			(at 0 0 0)
			(layer "B.SilkS")
			(hide yes)
			(effects
				(font
					(size 1.27 1.27)
				)
				(justify mirror)
			)
		)
		(property "Value" "4K7R2F-GP"
			(at -0.064008 -3.993896 180)
			(unlocked yes)
			(layer "B.Fab")
			(hide yes)
			(effects
				(font
					(size 1.016 1.016)
					(thickness 0.1524)
				)
				(justify mirror)
			)
		)
		(property "Device Type" "R402H16"
			(at -0.064008 -5.517896 180)
			(unlocked yes)
			(layer "B.Fab")
			(hide yes)
			(effects
				(font
					(size 1.016 1.016)
					(thickness 0.1524)
				)
				(justify mirror)
			)
		)
		(duplicate_pad_numbers_are_jumpers no)
		(fp_line
			(start 0.508 -0.9398)
			(end 0.508 0.9398)
			(stroke
				(width 0.1524)
				(type default)
			)
			(layer "B.SilkS")
		)
		(fp_line
			(start -0.508 -0.9398)
			(end 0.508 -0.9398)
			(stroke
				(width 0.1524)
				(type default)
			)
			(layer "B.SilkS")
		)
		(fp_rect
			(start 0.508 0.9398)
			(end -0.508 -0.9398)
			(stroke
				(width 0)
				(type default)
			)
			(fill no)
			(layer "B.CrtYd")
		)
		(fp_rect
			(start 0.508 0.9398)
			(end -0.508 -0.9398)
			(stroke
				(width 0)
				(type default)
			)
			(fill no)
			(layer "B.Fab")
		)
		(pad "1" smd custom
			(at 0 -0.4445)
			(size 0.1397 0.1397)
			(layers "B.Cu" "B.Mask" "B.Paste")
			(net "EXP_XM_ADDR_15")
			(options
				(clearance outline)
				(anchor circle)
			)
			(primitives
				(gr_poly
					(pts
						(arc
							(start -0.1778 0.2794)
							(mid -0.249642 0.249642)
							(end -0.2794 0.1778)
						)
						(arc
							(start -0.2794 -0.1778)
							(mid -0.249642 -0.249642)
							(end -0.1778 -0.2794)
						)
						(arc
							(start 0.1778 -0.2794)
							(mid 0.249642 -0.249642)
							(end 0.2794 -0.1778)
						)
						(arc
							(start 0.2794 0.1778)
							(mid 0.249642 0.249642)
							(end 0.1778 0.2794)
						)
					)
					(width 0)
					(fill yes)
				)
			)
		)
		(pad "2" smd custom
			(at 0 0.4445)
			(size 0.1397 0.1397)
			(layers "B.Cu" "B.Mask" "B.Paste")
			(net "GND")
			(options
				(clearance outline)
				(anchor circle)
			)
			(primitives
				(gr_poly
					(pts
						(arc
							(start -0.1778 0.2794)
							(mid -0.249642 0.249642)
							(end -0.2794 0.1778)
						)
						(arc
							(start -0.2794 -0.1778)
							(mid -0.249642 -0.249642)
							(end -0.1778 -0.2794)
						)
						(arc
							(start 0.1778 -0.2794)
							(mid 0.249642 -0.249642)
							(end 0.2794 -0.1778)
						)
						(arc
							(start 0.2794 0.1778)
							(mid 0.249642 0.249642)
							(end 0.1778 0.2794)
						)
					)
					(width 0)
					(fill yes)
				)
			)
		)
	)
	(footprint ""
		(layer "B.Cu")
		(at 116.713 -68.6562)
		(property "Reference" "C179"
			(at 0 0 0)
			(layer "B.SilkS")
			(hide yes)
			(effects
				(font
					(size 1.27 1.27)
				)
				(justify mirror)
			)
		)
		(property "Value" "SCD1U6D3V1KX-GP"
			(at 2.8321 -1.7399 0)
			(unlocked yes)
			(layer "B.Fab")
			(hide yes)
			(effects
				(font
					(size 1.016 1.016)
					(thickness 0.1524)
				)
				(justify mirror)
			)
		)
		(property "Device Type" "C0201H13"
			(at 2.8321 -3.2639 0)
			(unlocked yes)
			(layer "B.Fab")
			(hide yes)
			(effects
				(font
					(size 1.016 1.016)
					(thickness 0.1524)
				)
				(justify mirror)
			)
		)
		(duplicate_pad_numbers_are_jumpers no)
		(fp_rect
			(start 0.2794 0.6477)
			(end -0.2794 -0.6477)
			(stroke
				(width 0)
				(type default)
			)
			(fill no)
			(layer "B.CrtYd")
		)
		(fp_rect
			(start 0.2794 0.6477)
			(end -0.2794 -0.6477)
			(stroke
				(width 0)
				(type default)
			)
			(fill no)
			(layer "B.Fab")
		)
		(pad "1" smd custom
			(at 0 -0.2794 180)
			(size 0.0762 0.0762)
			(layers "B.Cu" "B.Mask" "B.Paste")
			(net "P0V9")
			(options
				(clearance outline)
				(anchor circle)
			)
			(primitives
				(gr_poly
					(pts
						(arc
							(start 0.1524 0.127)
							(mid 0.137521 0.162921)
							(end 0.1016 0.1778)
						)
						(arc
							(start -0.1016 0.1778)
							(mid -0.137521 0.162921)
							(end -0.1524 0.127)
						)
						(arc
							(start -0.1524 -0.127)
							(mid -0.137521 -0.162921)
							(end -0.1016 -0.1778)
						)
						(arc
							(start 0.1016 -0.1778)
							(mid 0.137521 -0.162921)
							(end 0.1524 -0.127)
						)
					)
					(width 0)
					(fill yes)
				)
			)
		)
		(pad "2" smd custom
			(at 0 0.2794 180)
			(size 0.0762 0.0762)
			(layers "B.Cu" "B.Mask" "B.Paste")
			(net "GND")
			(options
				(clearance outline)
				(anchor circle)
			)
			(primitives
				(gr_poly
					(pts
						(arc
							(start 0.1524 0.127)
							(mid 0.137521 0.162921)
							(end 0.1016 0.1778)
						)
						(arc
							(start -0.1016 0.1778)
							(mid -0.137521 0.162921)
							(end -0.1524 0.127)
						)
						(arc
							(start -0.1524 -0.127)
							(mid -0.137521 -0.162921)
							(end -0.1016 -0.1778)
						)
						(arc
							(start 0.1016 -0.1778)
							(mid 0.137521 -0.162921)
							(end 0.1524 -0.127)
						)
					)
					(width 0)
					(fill yes)
				)
			)
		)
	)
	(footprint ""
		(layer "B.Cu")
		(at 115.316 -68.6562)
		(property "Reference" "C168"
			(at 0 0 0)
			(layer "B.SilkS")
			(hide yes)
			(effects
				(font
					(size 1.27 1.27)
				)
				(justify mirror)
			)
		)
		(property "Value" "SCD1U6D3V1KX-GP"
			(at 2.8321 -1.7399 0)
			(unlocked yes)
			(layer "B.Fab")
			(hide yes)
			(effects
				(font
					(size 1.016 1.016)
					(thickness 0.1524)
				)
				(justify mirror)
			)
		)
		(property "Device Type" "C0201H13"
			(at 2.8321 -3.2639 0)
			(unlocked yes)
			(layer "B.Fab")
			(hide yes)
			(effects
				(font
					(size 1.016 1.016)
					(thickness 0.1524)
				)
				(justify mirror)
			)
		)
		(duplicate_pad_numbers_are_jumpers no)
		(fp_rect
			(start 0.2794 0.6477)
			(end -0.2794 -0.6477)
			(stroke
				(width 0)
				(type default)
			)
			(fill no)
			(layer "B.CrtYd")
		)
		(fp_rect
			(start 0.2794 0.6477)
			(end -0.2794 -0.6477)
			(stroke
				(width 0)
				(type default)
			)
			(fill no)
			(layer "B.Fab")
		)
		(pad "1" smd custom
			(at 0 -0.2794 180)
			(size 0.0762 0.0762)
			(layers "B.Cu" "B.Mask" "B.Paste")
			(net "P0V9")
			(options
				(clearance outline)
				(anchor circle)
			)
			(primitives
				(gr_poly
					(pts
						(arc
							(start 0.1524 0.127)
							(mid 0.137521 0.162921)
							(end 0.1016 0.1778)
						)
						(arc
							(start -0.1016 0.1778)
							(mid -0.137521 0.162921)
							(end -0.1524 0.127)
						)
						(arc
							(start -0.1524 -0.127)
							(mid -0.137521 -0.162921)
							(end -0.1016 -0.1778)
						)
						(arc
							(start 0.1016 -0.1778)
							(mid 0.137521 -0.162921)
							(end 0.1524 -0.127)
						)
					)
					(width 0)
					(fill yes)
				)
			)
		)
		(pad "2" smd custom
			(at 0 0.2794 180)
			(size 0.0762 0.0762)
			(layers "B.Cu" "B.Mask" "B.Paste")
			(net "GND")
			(options
				(clearance outline)
				(anchor circle)
			)
			(primitives
				(gr_poly
					(pts
						(arc
							(start 0.1524 0.127)
							(mid 0.137521 0.162921)
							(end 0.1016 0.1778)
						)
						(arc
							(start -0.1016 0.1778)
							(mid -0.137521 0.162921)
							(end -0.1524 0.127)
						)
						(arc
							(start -0.1524 -0.127)
							(mid -0.137521 -0.162921)
							(end -0.1016 -0.1778)
						)
						(arc
							(start 0.1016 -0.1778)
							(mid 0.137521 -0.162921)
							(end 0.1524 -0.127)
						)
					)
					(width 0)
					(fill yes)
				)
			)
		)
	)
	(footprint ""
		(layer "B.Cu")
		(at 200.5203 -46.4439 -90)
		(property "Reference" "R202"
			(at 0 0 90)
			(layer "B.SilkS")
			(hide yes)
			(effects
				(font
					(size 1.27 1.27)
				)
				(justify mirror)
			)
		)
		(property "Value" "0R2J-2-GP"
			(at -0.064008 -3.993896 270)
			(unlocked yes)
			(layer "B.Fab")
			(hide yes)
			(effects
				(font
					(size 1.016 1.016)
					(thickness 0.1524)
				)
				(justify mirror)
			)
		)
		(property "Device Type" "R402H16"
			(at -0.064008 -5.517896 270)
			(unlocked yes)
			(layer "B.Fab")
			(hide yes)
			(effects
				(font
					(size 1.016 1.016)
					(thickness 0.1524)
				)
				(justify mirror)
			)
		)
		(duplicate_pad_numbers_are_jumpers no)
		(fp_line
			(start -0.508 -0.9398)
			(end 0.508 -0.9398)
			(stroke
				(width 0.1524)
				(type default)
			)
			(layer "B.SilkS")
		)
		(fp_line
			(start 0.508 -0.9398)
			(end 0.508 0.9398)
			(stroke
				(width 0.1524)
				(type default)
			)
			(layer "B.SilkS")
		)
		(fp_rect
			(start 0.508 0.9398)
			(end -0.508 -0.9398)
			(stroke
				(width 0)
				(type default)
			)
			(fill no)
			(layer "B.CrtYd")
		)
		(fp_rect
			(start 0.508 0.9398)
			(end -0.508 -0.9398)
			(stroke
				(width 0)
				(type default)
			)
			(fill no)
			(layer "B.Fab")
		)
		(pad "1" smd custom
			(at 0 -0.4445 90)
			(size 0.1397 0.1397)
			(layers "B.Cu" "B.Mask" "B.Paste")
			(net "IOC_EEPROM_SCL")
			(options
				(clearance outline)
				(anchor circle)
			)
			(primitives
				(gr_poly
					(pts
						(arc
							(start -0.1778 0.2794)
							(mid -0.249642 0.249642)
							(end -0.2794 0.1778)
						)
						(arc
							(start -0.2794 -0.1778)
							(mid -0.249642 -0.249642)
							(end -0.1778 -0.2794)
						)
						(arc
							(start 0.1778 -0.2794)
							(mid 0.249642 -0.249642)
							(end 0.2794 -0.1778)
						)
						(arc
							(start 0.2794 0.1778)
							(mid 0.249642 0.249642)
							(end 0.1778 0.2794)
						)
					)
					(width 0)
					(fill yes)
				)
			)
		)
		(pad "2" smd custom
			(at 0 0.4445 90)
			(size 0.1397 0.1397)
			(layers "B.Cu" "B.Mask" "B.Paste")
			(net "SBL_SCL")
			(options
				(clearance outline)
				(anchor circle)
			)
			(primitives
				(gr_poly
					(pts
						(arc
							(start -0.1778 0.2794)
							(mid -0.249642 0.249642)
							(end -0.2794 0.1778)
						)
						(arc
							(start -0.2794 -0.1778)
							(mid -0.249642 -0.249642)
							(end -0.1778 -0.2794)
						)
						(arc
							(start 0.1778 -0.2794)
							(mid 0.249642 -0.249642)
							(end 0.2794 -0.1778)
						)
						(arc
							(start 0.2794 0.1778)
							(mid 0.249642 0.249642)
							(end 0.1778 0.2794)
						)
					)
					(width 0)
					(fill yes)
				)
			)
		)
	)
	(footprint ""
		(layer "B.Cu")
		(at 144.332706 -117.160294 90)
		(property "Reference" "R539"
			(at 0 0 90)
			(layer "B.SilkS")
			(hide yes)
			(effects
				(font
					(size 1.27 1.27)
				)
				(justify mirror)
			)
		)
		(property "Value" "0R2J-2-GP"
			(at -0.064008 -3.993896 90)
			(unlocked yes)
			(layer "B.Fab")
			(hide yes)
			(effects
				(font
					(size 1.016 1.016)
					(thickness 0.1524)
				)
				(justify mirror)
			)
		)
		(property "Device Type" "R402H16"
			(at -0.064008 -5.517896 90)
			(unlocked yes)
			(layer "B.Fab")
			(hide yes)
			(effects
				(font
					(size 1.016 1.016)
					(thickness 0.1524)
				)
				(justify mirror)
			)
		)
		(duplicate_pad_numbers_are_jumpers no)
		(fp_line
			(start 0.508 -0.9398)
			(end 0.508 0.9398)
			(stroke
				(width 0.1524)
				(type default)
			)
			(layer "B.SilkS")
		)
		(fp_line
			(start -0.508 -0.9398)
			(end 0.508 -0.9398)
			(stroke
				(width 0.1524)
				(type default)
			)
			(layer "B.SilkS")
		)
		(fp_rect
			(start 0.508 0.9398)
			(end -0.508 -0.9398)
			(stroke
				(width 0)
				(type default)
			)
			(fill no)
			(layer "B.CrtYd")
		)
		(fp_rect
			(start 0.508 0.9398)
			(end -0.508 -0.9398)
			(stroke
				(width 0)
				(type default)
			)
			(fill no)
			(layer "B.Fab")
		)
		(pad "1" smd custom
			(at 0 -0.4445 270)
			(size 0.1397 0.1397)
			(layers "B.Cu" "B.Mask" "B.Paste")
			(net "P1V5_C_S")
			(options
				(clearance outline)
				(anchor circle)
			)
			(primitives
				(gr_poly
					(pts
						(arc
							(start -0.1778 0.2794)
							(mid -0.249642 0.249642)
							(end -0.2794 0.1778)
						)
						(arc
							(start -0.2794 -0.1778)
							(mid -0.249642 -0.249642)
							(end -0.1778 -0.2794)
						)
						(arc
							(start 0.1778 -0.2794)
							(mid 0.249642 -0.249642)
							(end 0.2794 -0.1778)
						)
						(arc
							(start 0.2794 0.1778)
							(mid 0.249642 0.249642)
							(end 0.1778 0.2794)
						)
					)
					(width 0)
					(fill yes)
				)
			)
		)
		(pad "2" smd custom
			(at 0 0.4445 270)
			(size 0.1397 0.1397)
			(layers "B.Cu" "B.Mask" "B.Paste")
			(net "P1V8_C_PG")
			(options
				(clearance outline)
				(anchor circle)
			)
			(primitives
				(gr_poly
					(pts
						(arc
							(start -0.1778 0.2794)
							(mid -0.249642 0.249642)
							(end -0.2794 0.1778)
						)
						(arc
							(start -0.2794 -0.1778)
							(mid -0.249642 -0.249642)
							(end -0.1778 -0.2794)
						)
						(arc
							(start 0.1778 -0.2794)
							(mid 0.249642 -0.249642)
							(end 0.2794 -0.1778)
						)
						(arc
							(start 0.2794 0.1778)
							(mid 0.249642 0.249642)
							(end 0.1778 0.2794)
						)
					)
					(width 0)
					(fill yes)
				)
			)
		)
	)
	(footprint ""
		(layer "B.Cu")
		(at 155.327604 -66.866008)
		(property "Reference" "R278"
			(at 0 0 0)
			(layer "B.SilkS")
			(hide yes)
			(effects
				(font
					(size 1.27 1.27)
				)
				(justify mirror)
			)
		)
		(property "Value" "10R2F-L-GP"
			(at -0.064008 -3.993896 0)
			(unlocked yes)
			(layer "B.Fab")
			(hide yes)
			(effects
				(font
					(size 1.016 1.016)
					(thickness 0.1524)
				)
				(justify mirror)
			)
		)
		(property "Device Type" "R402H14"
			(at -0.064008 -5.517896 0)
			(unlocked yes)
			(layer "B.Fab")
			(hide yes)
			(effects
				(font
					(size 1.016 1.016)
					(thickness 0.1524)
				)
				(justify mirror)
			)
		)
		(duplicate_pad_numbers_are_jumpers no)
		(fp_line
			(start -0.508 -0.9398)
			(end 0.508 -0.9398)
			(stroke
				(width 0.1524)
				(type default)
			)
			(layer "B.SilkS")
		)
		(fp_line
			(start 0.508 -0.9398)
			(end 0.508 0.9398)
			(stroke
				(width 0.1524)
				(type default)
			)
			(layer "B.SilkS")
		)
		(fp_rect
			(start 0.508 0.9398)
			(end -0.508 -0.9398)
			(stroke
				(width 0)
				(type default)
			)
			(fill no)
			(layer "B.CrtYd")
		)
		(fp_rect
			(start 0.508 0.9398)
			(end -0.508 -0.9398)
			(stroke
				(width 0)
				(type default)
			)
			(fill no)
			(layer "B.Fab")
		)
		(pad "1" smd custom
			(at 0 -0.4445 180)
			(size 0.1397 0.1397)
			(layers "B.Cu" "B.Mask" "B.Paste")
			(net "P1V8_C")
			(options
				(clearance outline)
				(anchor circle)
			)
			(primitives
				(gr_poly
					(pts
						(arc
							(start -0.1778 0.2794)
							(mid -0.249642 0.249642)
							(end -0.2794 0.1778)
						)
						(arc
							(start -0.2794 -0.1778)
							(mid -0.249642 -0.249642)
							(end -0.1778 -0.2794)
						)
						(arc
							(start 0.1778 -0.2794)
							(mid 0.249642 -0.249642)
							(end 0.2794 -0.1778)
						)
						(arc
							(start 0.2794 0.1778)
							(mid 0.249642 0.249642)
							(end 0.1778 0.2794)
						)
					)
					(width 0)
					(fill yes)
				)
			)
		)
		(pad "2" smd custom
			(at 0 0.4445 180)
			(size 0.1397 0.1397)
			(layers "B.Cu" "B.Mask" "B.Paste")
			(net "SYS_PLL_VDD")
			(options
				(clearance outline)
				(anchor circle)
			)
			(primitives
				(gr_poly
					(pts
						(arc
							(start -0.1778 0.2794)
							(mid -0.249642 0.249642)
							(end -0.2794 0.1778)
						)
						(arc
							(start -0.2794 -0.1778)
							(mid -0.249642 -0.249642)
							(end -0.1778 -0.2794)
						)
						(arc
							(start 0.1778 -0.2794)
							(mid 0.249642 -0.249642)
							(end 0.2794 -0.1778)
						)
						(arc
							(start 0.2794 0.1778)
							(mid 0.249642 0.249642)
							(end 0.1778 0.2794)
						)
					)
					(width 0)
					(fill yes)
				)
			)
		)
	)
	(footprint ""
		(layer "B.Cu")
		(at 187.599066 -38.582346 -90)
		(property "Reference" "R176"
			(at 0 0 90)
			(layer "B.SilkS")
			(hide yes)
			(effects
				(font
					(size 1.27 1.27)
				)
				(justify mirror)
			)
		)
		(property "Value" "10KR2F-2-GP"
			(at -0.064008 -3.993896 270)
			(unlocked yes)
			(layer "B.Fab")
			(hide yes)
			(effects
				(font
					(size 1.016 1.016)
					(thickness 0.1524)
				)
				(justify mirror)
			)
		)
		(property "Device Type" "R402H16"
			(at -0.064008 -5.517896 270)
			(unlocked yes)
			(layer "B.Fab")
			(hide yes)
			(effects
				(font
					(size 1.016 1.016)
					(thickness 0.1524)
				)
				(justify mirror)
			)
		)
		(duplicate_pad_numbers_are_jumpers no)
		(fp_line
			(start -0.508 -0.9398)
			(end 0.508 -0.9398)
			(stroke
				(width 0.1524)
				(type default)
			)
			(layer "B.SilkS")
		)
		(fp_line
			(start 0.508 -0.9398)
			(end 0.508 0.9398)
			(stroke
				(width 0.1524)
				(type default)
			)
			(layer "B.SilkS")
		)
		(fp_rect
			(start 0.508 0.9398)
			(end -0.508 -0.9398)
			(stroke
				(width 0)
				(type default)
			)
			(fill no)
			(layer "B.CrtYd")
		)
		(fp_rect
			(start 0.508 0.9398)
			(end -0.508 -0.9398)
			(stroke
				(width 0)
				(type default)
			)
			(fill no)
			(layer "B.Fab")
		)
		(pad "1" smd custom
			(at 0 -0.4445 90)
			(size 0.1397 0.1397)
			(layers "B.Cu" "B.Mask" "B.Paste")
			(net "GND")
			(options
				(clearance outline)
				(anchor circle)
			)
			(primitives
				(gr_poly
					(pts
						(arc
							(start -0.1778 0.2794)
							(mid -0.249642 0.249642)
							(end -0.2794 0.1778)
						)
						(arc
							(start -0.2794 -0.1778)
							(mid -0.249642 -0.249642)
							(end -0.1778 -0.2794)
						)
						(arc
							(start 0.1778 -0.2794)
							(mid 0.249642 -0.249642)
							(end 0.2794 -0.1778)
						)
						(arc
							(start 0.2794 0.1778)
							(mid 0.249642 0.249642)
							(end 0.1778 0.2794)
						)
					)
					(width 0)
					(fill yes)
				)
			)
		)
		(pad "2" smd custom
			(at 0 0.4445 90)
			(size 0.1397 0.1397)
			(layers "B.Cu" "B.Mask" "B.Paste")
			(net "IOC_CLK_SEL1")
			(options
				(clearance outline)
				(anchor circle)
			)
			(primitives
				(gr_poly
					(pts
						(arc
							(start -0.1778 0.2794)
							(mid -0.249642 0.249642)
							(end -0.2794 0.1778)
						)
						(arc
							(start -0.2794 -0.1778)
							(mid -0.249642 -0.249642)
							(end -0.1778 -0.2794)
						)
						(arc
							(start 0.1778 -0.2794)
							(mid 0.249642 -0.249642)
							(end 0.2794 -0.1778)
						)
						(arc
							(start 0.2794 0.1778)
							(mid 0.249642 0.249642)
							(end 0.1778 0.2794)
						)
					)
					(width 0)
					(fill yes)
				)
			)
		)
	)
	(footprint ""
		(layer "B.Cu")
		(at 163.75634 -6.240018 180)
		(property "Reference" "R578"
			(at 0 0 0)
			(layer "B.SilkS")
			(hide yes)
			(effects
				(font
					(size 1.27 1.27)
				)
				(justify mirror)
			)
		)
		(property "Value" "0R2J-2-GP"
			(at -0.064008 -3.993896 180)
			(unlocked yes)
			(layer "B.Fab")
			(hide yes)
			(effects
				(font
					(size 1.016 1.016)
					(thickness 0.1524)
				)
				(justify mirror)
			)
		)
		(property "Device Type" "R402H16"
			(at -0.064008 -5.517896 180)
			(unlocked yes)
			(layer "B.Fab")
			(hide yes)
			(effects
				(font
					(size 1.016 1.016)
					(thickness 0.1524)
				)
				(justify mirror)
			)
		)
		(duplicate_pad_numbers_are_jumpers no)
		(fp_line
			(start 0.508 -0.9398)
			(end 0.508 0.9398)
			(stroke
				(width 0.1524)
				(type default)
			)
			(layer "B.SilkS")
		)
		(fp_line
			(start -0.508 -0.9398)
			(end 0.508 -0.9398)
			(stroke
				(width 0.1524)
				(type default)
			)
			(layer "B.SilkS")
		)
		(fp_rect
			(start 0.508 0.9398)
			(end -0.508 -0.9398)
			(stroke
				(width 0)
				(type default)
			)
			(fill no)
			(layer "B.CrtYd")
		)
		(fp_rect
			(start 0.508 0.9398)
			(end -0.508 -0.9398)
			(stroke
				(width 0)
				(type default)
			)
			(fill no)
			(layer "B.Fab")
		)
		(pad "1" smd custom
			(at 0 -0.4445)
			(size 0.1397 0.1397)
			(layers "B.Cu" "B.Mask" "B.Paste")
			(net "SCC_RESET_N")
			(options
				(clearance outline)
				(anchor circle)
			)
			(primitives
				(gr_poly
					(pts
						(arc
							(start -0.1778 0.2794)
							(mid -0.249642 0.249642)
							(end -0.2794 0.1778)
						)
						(arc
							(start -0.2794 -0.1778)
							(mid -0.249642 -0.249642)
							(end -0.1778 -0.2794)
						)
						(arc
							(start 0.1778 -0.2794)
							(mid 0.249642 -0.249642)
							(end 0.2794 -0.1778)
						)
						(arc
							(start 0.2794 0.1778)
							(mid 0.249642 0.249642)
							(end 0.1778 0.2794)
						)
					)
					(width 0)
					(fill yes)
				)
			)
		)
		(pad "2" smd custom
			(at 0 0.4445)
			(size 0.1397 0.1397)
			(layers "B.Cu" "B.Mask" "B.Paste")
			(net "SCC_RESET_BUF_N")
			(options
				(clearance outline)
				(anchor circle)
			)
			(primitives
				(gr_poly
					(pts
						(arc
							(start -0.1778 0.2794)
							(mid -0.249642 0.249642)
							(end -0.2794 0.1778)
						)
						(arc
							(start -0.2794 -0.1778)
							(mid -0.249642 -0.249642)
							(end -0.1778 -0.2794)
						)
						(arc
							(start 0.1778 -0.2794)
							(mid 0.249642 -0.249642)
							(end 0.2794 -0.1778)
						)
						(arc
							(start 0.2794 0.1778)
							(mid 0.249642 0.249642)
							(end 0.1778 0.2794)
						)
					)
					(width 0)
					(fill yes)
				)
			)
		)
	)
	(footprint ""
		(layer "B.Cu")
		(at 137.4648 -66.8274 -90)
		(property "Reference" "C19"
			(at 0 0 90)
			(layer "B.SilkS")
			(hide yes)
			(effects
				(font
					(size 1.27 1.27)
				)
				(justify mirror)
			)
		)
		(property "Value" "SCD01U16V1KX-GP"
			(at 2.8321 -1.7399 270)
			(unlocked yes)
			(layer "B.Fab")
			(hide yes)
			(effects
				(font
					(size 1.016 1.016)
					(thickness 0.1524)
				)
				(justify mirror)
			)
		)
		(property "Device Type" "C0201H13"
			(at 2.8321 -3.2639 270)
			(unlocked yes)
			(layer "B.Fab")
			(hide yes)
			(effects
				(font
					(size 1.016 1.016)
					(thickness 0.1524)
				)
				(justify mirror)
			)
		)
		(duplicate_pad_numbers_are_jumpers no)
		(fp_rect
			(start 0.2794 0.6477)
			(end -0.2794 -0.6477)
			(stroke
				(width 0)
				(type default)
			)
			(fill no)
			(layer "B.CrtYd")
		)
		(fp_rect
			(start 0.2794 0.6477)
			(end -0.2794 -0.6477)
			(stroke
				(width 0)
				(type default)
			)
			(fill no)
			(layer "B.Fab")
		)
		(pad "1" smd custom
			(at 0 -0.2794 90)
			(size 0.0762 0.0762)
			(layers "B.Cu" "B.Mask" "B.Paste")
			(net "PHY_DPB_TO_SCC_2_DP")
			(options
				(clearance outline)
				(anchor circle)
			)
			(primitives
				(gr_poly
					(pts
						(arc
							(start 0.1524 0.127)
							(mid 0.137521 0.162921)
							(end 0.1016 0.1778)
						)
						(arc
							(start -0.1016 0.1778)
							(mid -0.137521 0.162921)
							(end -0.1524 0.127)
						)
						(arc
							(start -0.1524 -0.127)
							(mid -0.137521 -0.162921)
							(end -0.1016 -0.1778)
						)
						(arc
							(start 0.1016 -0.1778)
							(mid 0.137521 -0.162921)
							(end 0.1524 -0.127)
						)
					)
					(width 0)
					(fill yes)
				)
			)
		)
		(pad "2" smd custom
			(at 0 0.2794 90)
			(size 0.0762 0.0762)
			(layers "B.Cu" "B.Mask" "B.Paste")
			(net "PHY_DPB_TO_SCC_C_2_DP")
			(options
				(clearance outline)
				(anchor circle)
			)
			(primitives
				(gr_poly
					(pts
						(arc
							(start 0.1524 0.127)
							(mid 0.137521 0.162921)
							(end 0.1016 0.1778)
						)
						(arc
							(start -0.1016 0.1778)
							(mid -0.137521 0.162921)
							(end -0.1524 0.127)
						)
						(arc
							(start -0.1524 -0.127)
							(mid -0.137521 -0.162921)
							(end -0.1016 -0.1778)
						)
						(arc
							(start 0.1016 -0.1778)
							(mid 0.137521 -0.162921)
							(end 0.1524 -0.127)
						)
					)
					(width 0)
					(fill yes)
				)
			)
		)
	)
	(footprint ""
		(layer "B.Cu")
		(at 73.66 -41.148 180)
		(property "Reference" "C305"
			(at 0 0 0)
			(layer "B.SilkS")
			(hide yes)
			(effects
				(font
					(size 1.27 1.27)
				)
				(justify mirror)
			)
		)
		(property "Value" "SC100U6D3V6MX-GP"
			(at 0.0762 -5.1308 180)
			(unlocked yes)
			(layer "B.Fab")
			(hide yes)
			(effects
				(font
					(size 1.016 1.016)
					(thickness 0.1524)
				)
				(justify mirror)
			)
		)
		(property "Device Type" "C1206H71"
			(at 0.127 -6.6548 180)
			(unlocked yes)
			(layer "B.Fab")
			(hide yes)
			(effects
				(font
					(size 1.016 1.016)
					(thickness 0.1524)
				)
				(justify mirror)
			)
		)
		(duplicate_pad_numbers_are_jumpers no)
		(fp_line
			(start 1.016 2.2352)
			(end 1.016 0.8382)
			(stroke
				(width 0.1524)
				(type default)
			)
			(layer "B.SilkS")
		)
		(fp_line
			(start 1.016 -0.8382)
			(end 1.016 -2.2352)
			(stroke
				(width 0.1524)
				(type default)
			)
			(layer "B.SilkS")
		)
		(fp_line
			(start 1.016 -2.2352)
			(end -1.016 -2.2352)
			(stroke
				(width 0.1524)
				(type default)
			)
			(layer "B.SilkS")
		)
		(fp_line
			(start -1.016 2.2352)
			(end 1.016 2.2352)
			(stroke
				(width 0.1524)
				(type default)
			)
			(layer "B.SilkS")
		)
		(fp_line
			(start -1.016 0.8382)
			(end -1.016 2.2352)
			(stroke
				(width 0.1524)
				(type default)
			)
			(layer "B.SilkS")
		)
		(fp_line
			(start -1.016 -2.2352)
			(end -1.016 -0.8382)
			(stroke
				(width 0.1524)
				(type default)
			)
			(layer "B.SilkS")
		)
		(fp_rect
			(start 1.0922 2.3114)
			(end -1.0922 -2.3114)
			(stroke
				(width 0)
				(type default)
			)
			(fill no)
			(layer "B.CrtYd")
		)
		(fp_poly
			(pts
				(xy -1.0922 -2.3114) (xy -1.0922 2.3114) (xy 1.0922 2.3114) (xy 1.0922 -2.3114)
			)
			(stroke
				(width 0)
				(type default)
			)
			(fill no)
			(layer "B.Fab")
		)
		(pad "1" smd rect
			(at 0 -1.397)
			(size 1.651 1.27)
			(layers "B.Cu" "B.Mask" "B.Paste")
			(net "GB_VDDA")
		)
		(pad "2" smd rect
			(at 0 1.397)
			(size 1.651 1.27)
			(layers "B.Cu" "B.Mask" "B.Paste")
			(net "GND")
		)
	)
	(footprint ""
		(layer "B.Cu")
		(at 166.751 -61.976 90)
		(property "Reference" "C352"
			(at 0 0 90)
			(layer "B.SilkS")
			(hide yes)
			(effects
				(font
					(size 1.27 1.27)
				)
				(justify mirror)
			)
		)
		(property "Value" "SC10U6D3V5KX-4GP"
			(at 0.0762 -6.1214 90)
			(unlocked yes)
			(layer "B.Fab")
			(hide yes)
			(effects
				(font
					(size 1.016 1.016)
					(thickness 0.1524)
				)
				(justify mirror)
			)
		)
		(property "Device Type" "C805H58"
			(at 0.0762 -8.1534 90)
			(unlocked yes)
			(layer "B.Fab")
			(hide yes)
			(effects
				(font
					(size 1.016 1.016)
					(thickness 0.1524)
				)
				(justify mirror)
			)
		)
		(duplicate_pad_numbers_are_jumpers no)
		(fp_line
			(start -0.635 0)
			(end 0.635 0)
			(stroke
				(width 0.508)
				(type default)
			)
			(layer "B.SilkS")
		)
		(fp_rect
			(start 0.9652 1.778)
			(end -0.9652 -1.778)
			(stroke
				(width 0)
				(type default)
			)
			(fill no)
			(layer "B.CrtYd")
		)
		(fp_poly
			(pts
				(xy 0.9652 -1.778) (xy -0.9652 -1.778) (xy -0.9652 1.778) (xy 0.9652 1.778)
			)
			(stroke
				(width 0)
				(type default)
			)
			(fill no)
			(layer "B.Fab")
		)
		(pad "1" smd rect
			(at 0 -0.9652 270)
			(size 1.397 1.143)
			(layers "B.Cu" "B.Mask" "B.Paste")
			(net "HM40ADC_VDDA")
		)
		(pad "2" smd rect
			(at 0 0.9652 270)
			(size 1.397 1.143)
			(layers "B.Cu" "B.Mask" "B.Paste")
			(net "GND")
		)
	)
	(footprint ""
		(layer "B.Cu")
		(at 136.2456 -80.5688 -90)
		(property "Reference" "C1"
			(at 0 0 90)
			(layer "B.SilkS")
			(hide yes)
			(effects
				(font
					(size 1.27 1.27)
				)
				(justify mirror)
			)
		)
		(property "Value" "SCD01U16V1KX-GP"
			(at 2.8321 -1.7399 270)
			(unlocked yes)
			(layer "B.Fab")
			(hide yes)
			(effects
				(font
					(size 1.016 1.016)
					(thickness 0.1524)
				)
				(justify mirror)
			)
		)
		(property "Device Type" "C0201H13"
			(at 2.8321 -3.2639 270)
			(unlocked yes)
			(layer "B.Fab")
			(hide yes)
			(effects
				(font
					(size 1.016 1.016)
					(thickness 0.1524)
				)
				(justify mirror)
			)
		)
		(duplicate_pad_numbers_are_jumpers no)
		(fp_rect
			(start 0.2794 0.6477)
			(end -0.2794 -0.6477)
			(stroke
				(width 0)
				(type default)
			)
			(fill no)
			(layer "B.CrtYd")
		)
		(fp_rect
			(start 0.2794 0.6477)
			(end -0.2794 -0.6477)
			(stroke
				(width 0)
				(type default)
			)
			(fill no)
			(layer "B.Fab")
		)
		(pad "1" smd custom
			(at 0 -0.2794 90)
			(size 0.0762 0.0762)
			(layers "B.Cu" "B.Mask" "B.Paste")
			(net "PHY_CONN_TO_EXP_11_DP")
			(options
				(clearance outline)
				(anchor circle)
			)
			(primitives
				(gr_poly
					(pts
						(arc
							(start 0.1524 0.127)
							(mid 0.137521 0.162921)
							(end 0.1016 0.1778)
						)
						(arc
							(start -0.1016 0.1778)
							(mid -0.137521 0.162921)
							(end -0.1524 0.127)
						)
						(arc
							(start -0.1524 -0.127)
							(mid -0.137521 -0.162921)
							(end -0.1016 -0.1778)
						)
						(arc
							(start 0.1016 -0.1778)
							(mid 0.137521 -0.162921)
							(end 0.1524 -0.127)
						)
					)
					(width 0)
					(fill yes)
				)
			)
		)
		(pad "2" smd custom
			(at 0 0.2794 90)
			(size 0.0762 0.0762)
			(layers "B.Cu" "B.Mask" "B.Paste")
			(net "PHY_CONN_TO_EXP_C_11_DP")
			(options
				(clearance outline)
				(anchor circle)
			)
			(primitives
				(gr_poly
					(pts
						(arc
							(start 0.1524 0.127)
							(mid 0.137521 0.162921)
							(end 0.1016 0.1778)
						)
						(arc
							(start -0.1016 0.1778)
							(mid -0.137521 0.162921)
							(end -0.1524 0.127)
						)
						(arc
							(start -0.1524 -0.127)
							(mid -0.137521 -0.162921)
							(end -0.1016 -0.1778)
						)
						(arc
							(start 0.1016 -0.1778)
							(mid 0.137521 -0.162921)
							(end 0.1524 -0.127)
						)
					)
					(width 0)
					(fill yes)
				)
			)
		)
	)
	(footprint ""
		(layer "B.Cu")
		(at 136.1948 -89.6874)
		(property "Reference" "R56"
			(at 0 0 0)
			(layer "B.SilkS")
			(hide yes)
			(effects
				(font
					(size 1.27 1.27)
				)
				(justify mirror)
			)
		)
		(property "Value" "4K7R2F-GP"
			(at -0.064008 -3.993896 0)
			(unlocked yes)
			(layer "B.Fab")
			(hide yes)
			(effects
				(font
					(size 1.016 1.016)
					(thickness 0.1524)
				)
				(justify mirror)
			)
		)
		(property "Device Type" "R402H16"
			(at -0.064008 -5.517896 0)
			(unlocked yes)
			(layer "B.Fab")
			(hide yes)
			(effects
				(font
					(size 1.016 1.016)
					(thickness 0.1524)
				)
				(justify mirror)
			)
		)
		(duplicate_pad_numbers_are_jumpers no)
		(fp_line
			(start -0.508 -0.9398)
			(end 0.508 -0.9398)
			(stroke
				(width 0.1524)
				(type default)
			)
			(layer "B.SilkS")
		)
		(fp_line
			(start 0.508 -0.9398)
			(end 0.508 0.9398)
			(stroke
				(width 0.1524)
				(type default)
			)
			(layer "B.SilkS")
		)
		(fp_rect
			(start 0.508 0.9398)
			(end -0.508 -0.9398)
			(stroke
				(width 0)
				(type default)
			)
			(fill no)
			(layer "B.CrtYd")
		)
		(fp_rect
			(start 0.508 0.9398)
			(end -0.508 -0.9398)
			(stroke
				(width 0)
				(type default)
			)
			(fill no)
			(layer "B.Fab")
		)
		(pad "1" smd custom
			(at 0 -0.4445 180)
			(size 0.1397 0.1397)
			(layers "B.Cu" "B.Mask" "B.Paste")
			(net "P1V8_E")
			(options
				(clearance outline)
				(anchor circle)
			)
			(primitives
				(gr_poly
					(pts
						(arc
							(start -0.1778 0.2794)
							(mid -0.249642 0.249642)
							(end -0.2794 0.1778)
						)
						(arc
							(start -0.2794 -0.1778)
							(mid -0.249642 -0.249642)
							(end -0.1778 -0.2794)
						)
						(arc
							(start 0.1778 -0.2794)
							(mid 0.249642 -0.249642)
							(end 0.2794 -0.1778)
						)
						(arc
							(start 0.2794 0.1778)
							(mid 0.249642 0.249642)
							(end 0.1778 0.2794)
						)
					)
					(width 0)
					(fill yes)
				)
			)
		)
		(pad "2" smd custom
			(at 0 0.4445 180)
			(size 0.1397 0.1397)
			(layers "B.Cu" "B.Mask" "B.Paste")
			(net "I2C_DRIVE_PWR_SCL4_LS")
			(options
				(clearance outline)
				(anchor circle)
			)
			(primitives
				(gr_poly
					(pts
						(arc
							(start -0.1778 0.2794)
							(mid -0.249642 0.249642)
							(end -0.2794 0.1778)
						)
						(arc
							(start -0.2794 -0.1778)
							(mid -0.249642 -0.249642)
							(end -0.1778 -0.2794)
						)
						(arc
							(start 0.1778 -0.2794)
							(mid 0.249642 -0.249642)
							(end 0.2794 -0.1778)
						)
						(arc
							(start 0.2794 0.1778)
							(mid 0.249642 0.249642)
							(end 0.1778 0.2794)
						)
					)
					(width 0)
					(fill yes)
				)
			)
		)
	)
	(footprint ""
		(layer "B.Cu")
		(at 91.007692 -64.044576 180)
		(property "Reference" "R151"
			(at 0 0 0)
			(layer "B.SilkS")
			(hide yes)
			(effects
				(font
					(size 1.27 1.27)
				)
				(justify mirror)
			)
		)
		(property "Value" "10R2F-L-GP"
			(at -0.064008 -3.993896 180)
			(unlocked yes)
			(layer "B.Fab")
			(hide yes)
			(effects
				(font
					(size 1.016 1.016)
					(thickness 0.1524)
				)
				(justify mirror)
			)
		)
		(property "Device Type" "R402H14"
			(at -0.064008 -5.517896 180)
			(unlocked yes)
			(layer "B.Fab")
			(hide yes)
			(effects
				(font
					(size 1.016 1.016)
					(thickness 0.1524)
				)
				(justify mirror)
			)
		)
		(duplicate_pad_numbers_are_jumpers no)
		(fp_line
			(start 0.508 -0.9398)
			(end 0.508 0.9398)
			(stroke
				(width 0.1524)
				(type default)
			)
			(layer "B.SilkS")
		)
		(fp_line
			(start -0.508 -0.9398)
			(end 0.508 -0.9398)
			(stroke
				(width 0.1524)
				(type default)
			)
			(layer "B.SilkS")
		)
		(fp_rect
			(start 0.508 0.9398)
			(end -0.508 -0.9398)
			(stroke
				(width 0)
				(type default)
			)
			(fill no)
			(layer "B.CrtYd")
		)
		(fp_rect
			(start 0.508 0.9398)
			(end -0.508 -0.9398)
			(stroke
				(width 0)
				(type default)
			)
			(fill no)
			(layer "B.Fab")
		)
		(pad "1" smd custom
			(at 0 -0.4445)
			(size 0.1397 0.1397)
			(layers "B.Cu" "B.Mask" "B.Paste")
			(net "P1V8_E")
			(options
				(clearance outline)
				(anchor circle)
			)
			(primitives
				(gr_poly
					(pts
						(arc
							(start -0.1778 0.2794)
							(mid -0.249642 0.249642)
							(end -0.2794 0.1778)
						)
						(arc
							(start -0.2794 -0.1778)
							(mid -0.249642 -0.249642)
							(end -0.1778 -0.2794)
						)
						(arc
							(start 0.1778 -0.2794)
							(mid 0.249642 -0.249642)
							(end 0.2794 -0.1778)
						)
						(arc
							(start 0.2794 0.1778)
							(mid 0.249642 0.249642)
							(end 0.1778 0.2794)
						)
					)
					(width 0)
					(fill yes)
				)
			)
		)
		(pad "2" smd custom
			(at 0 0.4445)
			(size 0.1397 0.1397)
			(layers "B.Cu" "B.Mask" "B.Paste")
			(net "XTAL_VDDA18")
			(options
				(clearance outline)
				(anchor circle)
			)
			(primitives
				(gr_poly
					(pts
						(arc
							(start -0.1778 0.2794)
							(mid -0.249642 0.249642)
							(end -0.2794 0.1778)
						)
						(arc
							(start -0.2794 -0.1778)
							(mid -0.249642 -0.249642)
							(end -0.1778 -0.2794)
						)
						(arc
							(start 0.1778 -0.2794)
							(mid 0.249642 -0.249642)
							(end 0.2794 -0.1778)
						)
						(arc
							(start 0.2794 0.1778)
							(mid 0.249642 0.249642)
							(end 0.1778 0.2794)
						)
					)
					(width 0)
					(fill yes)
				)
			)
		)
	)
	(footprint ""
		(layer "B.Cu")
		(at 119.50446 -71.9582)
		(property "Reference" "C123"
			(at 0 0 0)
			(layer "B.SilkS")
			(hide yes)
			(effects
				(font
					(size 1.27 1.27)
				)
				(justify mirror)
			)
		)
		(property "Value" "SC1KP25V1KX-GP"
			(at 2.8321 -1.7399 0)
			(unlocked yes)
			(layer "B.Fab")
			(hide yes)
			(effects
				(font
					(size 1.016 1.016)
					(thickness 0.1524)
				)
				(justify mirror)
			)
		)
		(property "Device Type" "C0201H13"
			(at 2.8321 -3.2639 0)
			(unlocked yes)
			(layer "B.Fab")
			(hide yes)
			(effects
				(font
					(size 1.016 1.016)
					(thickness 0.1524)
				)
				(justify mirror)
			)
		)
		(duplicate_pad_numbers_are_jumpers no)
		(fp_rect
			(start 0.2794 0.6477)
			(end -0.2794 -0.6477)
			(stroke
				(width 0)
				(type default)
			)
			(fill no)
			(layer "B.CrtYd")
		)
		(fp_rect
			(start 0.2794 0.6477)
			(end -0.2794 -0.6477)
			(stroke
				(width 0)
				(type default)
			)
			(fill no)
			(layer "B.Fab")
		)
		(pad "1" smd custom
			(at 0 -0.2794 180)
			(size 0.0762 0.0762)
			(layers "B.Cu" "B.Mask" "B.Paste")
			(net "P1V8_E")
			(options
				(clearance outline)
				(anchor circle)
			)
			(primitives
				(gr_poly
					(pts
						(arc
							(start 0.1524 0.127)
							(mid 0.137521 0.162921)
							(end 0.1016 0.1778)
						)
						(arc
							(start -0.1016 0.1778)
							(mid -0.137521 0.162921)
							(end -0.1524 0.127)
						)
						(arc
							(start -0.1524 -0.127)
							(mid -0.137521 -0.162921)
							(end -0.1016 -0.1778)
						)
						(arc
							(start 0.1016 -0.1778)
							(mid 0.137521 -0.162921)
							(end 0.1524 -0.127)
						)
					)
					(width 0)
					(fill yes)
				)
			)
		)
		(pad "2" smd custom
			(at 0 0.2794 180)
			(size 0.0762 0.0762)
			(layers "B.Cu" "B.Mask" "B.Paste")
			(net "GND")
			(options
				(clearance outline)
				(anchor circle)
			)
			(primitives
				(gr_poly
					(pts
						(arc
							(start 0.1524 0.127)
							(mid 0.137521 0.162921)
							(end 0.1016 0.1778)
						)
						(arc
							(start -0.1016 0.1778)
							(mid -0.137521 0.162921)
							(end -0.1524 0.127)
						)
						(arc
							(start -0.1524 -0.127)
							(mid -0.137521 -0.162921)
							(end -0.1016 -0.1778)
						)
						(arc
							(start 0.1016 -0.1778)
							(mid 0.137521 -0.162921)
							(end 0.1524 -0.127)
						)
					)
					(width 0)
					(fill yes)
				)
			)
		)
	)
	(footprint ""
		(layer "B.Cu")
		(at 200.66 -24.257 180)
		(property "Reference" "LED2"
			(at 0 0 0)
			(layer "B.SilkS")
			(hide yes)
			(effects
				(font
					(size 1.27 1.27)
				)
				(justify mirror)
			)
		)
		(property "Value" "LED-YG-51-GP"
			(at 2.6924 -1.4224 180)
			(unlocked yes)
			(layer "B.Fab")
			(hide yes)
			(effects
				(font
					(size 1.016 1.016)
					(thickness 0.1524)
				)
				(justify mirror)
			)
		)
		(property "Device Type" "LED1608AKH40"
			(at 2.6924 -2.9464 180)
			(unlocked yes)
			(layer "B.Fab")
			(hide yes)
			(effects
				(font
					(size 1.016 1.016)
					(thickness 0.1524)
				)
				(justify mirror)
			)
		)
		(duplicate_pad_numbers_are_jumpers no)
		(fp_line
			(start 0.7493 1.651)
			(end 0.7493 1.1811)
			(stroke
				(width 0.3302)
				(type default)
			)
			(layer "B.SilkS")
		)
		(fp_line
			(start 0.6604 1.3716)
			(end 0.6604 -1.3716)
			(stroke
				(width 0.1524)
				(type default)
			)
			(layer "B.SilkS")
		)
		(fp_line
			(start 0.6604 -1.3716)
			(end -0.6604 -1.3716)
			(stroke
				(width 0.1524)
				(type default)
			)
			(layer "B.SilkS")
		)
		(fp_line
			(start 0.5969 1.5494)
			(end -0.5842 1.5494)
			(stroke
				(width 0.508)
				(type default)
			)
			(layer "B.SilkS")
		)
		(fp_line
			(start -0.6604 1.3716)
			(end 0.6604 1.3716)
			(stroke
				(width 0.1524)
				(type default)
			)
			(layer "B.SilkS")
		)
		(fp_line
			(start -0.6604 -1.3716)
			(end -0.6604 1.3716)
			(stroke
				(width 0.1524)
				(type default)
			)
			(layer "B.SilkS")
		)
		(fp_line
			(start -0.7493 1.651)
			(end -0.7493 1.1811)
			(stroke
				(width 0.3302)
				(type default)
			)
			(layer "B.SilkS")
		)
		(fp_rect
			(start 0.6223 1.3335)
			(end -0.6223 -1.3335)
			(stroke
				(width 0)
				(type default)
			)
			(fill no)
			(layer "B.CrtYd")
		)
		(fp_rect
			(start 0.6223 1.3335)
			(end -0.6223 -1.3335)
			(stroke
				(width 0)
				(type default)
			)
			(fill no)
			(layer "B.Fab")
		)
		(pad "A" smd custom
			(at 0 -0.762)
			(size 0.2159 0.2159)
			(layers "B.Cu" "B.Mask" "B.Paste")
			(net "SYS_ERROR_LED_R")
			(options
				(clearance outline)
				(anchor circle)
			)
			(primitives
				(gr_poly
					(pts
						(arc
							(start -0.3302 0.4318)
							(mid -0.402042 0.402042)
							(end -0.4318 0.3302)
						)
						(arc
							(start -0.4318 -0.3302)
							(mid -0.402042 -0.402042)
							(end -0.3302 -0.4318)
						)
						(arc
							(start 0.3302 -0.4318)
							(mid 0.402042 -0.402042)
							(end 0.4318 -0.3302)
						)
						(arc
							(start 0.4318 0.3302)
							(mid 0.402042 0.402042)
							(end 0.3302 0.4318)
						)
					)
					(width 0)
					(fill yes)
				)
			)
		)
		(pad "K" smd custom
			(at 0 0.762)
			(size 0.2159 0.2159)
			(layers "B.Cu" "B.Mask" "B.Paste")
			(net "SYS_ERROR_LED_D")
			(options
				(clearance outline)
				(anchor circle)
			)
			(primitives
				(gr_poly
					(pts
						(arc
							(start -0.3302 0.4318)
							(mid -0.402042 0.402042)
							(end -0.4318 0.3302)
						)
						(arc
							(start -0.4318 -0.3302)
							(mid -0.402042 -0.402042)
							(end -0.3302 -0.4318)
						)
						(arc
							(start 0.3302 -0.4318)
							(mid 0.402042 -0.402042)
							(end 0.4318 -0.3302)
						)
						(arc
							(start 0.4318 0.3302)
							(mid 0.402042 0.402042)
							(end 0.3302 0.4318)
						)
					)
					(width 0)
					(fill yes)
				)
			)
		)
	)
	(footprint ""
		(layer "B.Cu")
		(at 196.088 -28.321 180)
		(property "Reference" "C379"
			(at 0 0 0)
			(layer "B.SilkS")
			(hide yes)
			(effects
				(font
					(size 1.27 1.27)
				)
				(justify mirror)
			)
		)
		(property "Value" "SC1U16V2KX-7-GP"
			(at -1.7526 -1.6002 180)
			(unlocked yes)
			(layer "B.Fab")
			(hide yes)
			(effects
				(font
					(size 1.016 1.016)
					(thickness 0.1524)
				)
				(justify mirror)
			)
		)
		(property "Device Type" "C402-TO0D2H24"
			(at -1.7526 -3.1242 180)
			(unlocked yes)
			(layer "B.Fab")
			(hide yes)
			(effects
				(font
					(size 1.016 1.016)
					(thickness 0.1524)
				)
				(justify mirror)
			)
		)
		(duplicate_pad_numbers_are_jumpers no)
		(fp_rect
			(start 0.4826 0.889)
			(end -0.4826 -0.889)
			(stroke
				(width 0)
				(type default)
			)
			(fill no)
			(layer "B.CrtYd")
		)
		(fp_rect
			(start 0.4826 0.889)
			(end -0.4826 -0.889)
			(stroke
				(width 0)
				(type default)
			)
			(fill no)
			(layer "B.Fab")
		)
		(pad "1" smd custom
			(at 0 -0.4572)
			(size 0.1524 0.1524)
			(layers "B.Cu" "B.Mask" "B.Paste")
			(net "PCE_VDDH")
			(options
				(clearance outline)
				(anchor circle)
			)
			(primitives
				(gr_poly
					(pts
						(arc
							(start -0.254 -0.3048)
							(mid -0.325842 -0.275042)
							(end -0.3556 -0.2032)
						)
						(arc
							(start -0.3556 0.2032)
							(mid -0.325842 0.275042)
							(end -0.254 0.3048)
						)
						(arc
							(start 0.254 0.3048)
							(mid 0.325842 0.275042)
							(end 0.3556 0.2032)
						)
						(arc
							(start 0.3556 -0.2032)
							(mid 0.325842 -0.275042)
							(end 0.254 -0.3048)
						)
					)
					(width 0)
					(fill yes)
				)
			)
		)
		(pad "2" smd custom
			(at 0 0.4572)
			(size 0.1524 0.1524)
			(layers "B.Cu" "B.Mask" "B.Paste")
			(net "GND")
			(options
				(clearance outline)
				(anchor circle)
			)
			(primitives
				(gr_poly
					(pts
						(arc
							(start -0.254 -0.3048)
							(mid -0.325842 -0.275042)
							(end -0.3556 -0.2032)
						)
						(arc
							(start -0.3556 0.2032)
							(mid -0.325842 0.275042)
							(end -0.254 0.3048)
						)
						(arc
							(start 0.254 0.3048)
							(mid 0.325842 0.275042)
							(end 0.3556 0.2032)
						)
						(arc
							(start 0.3556 -0.2032)
							(mid 0.325842 -0.275042)
							(end 0.254 -0.3048)
						)
					)
					(width 0)
					(fill yes)
				)
			)
		)
	)
	(footprint ""
		(layer "B.Cu")
		(at 137.414 -74.041 -90)
		(property "Reference" "C10"
			(at 0 0 90)
			(layer "B.SilkS")
			(hide yes)
			(effects
				(font
					(size 1.27 1.27)
				)
				(justify mirror)
			)
		)
		(property "Value" "SCD01U16V1KX-GP"
			(at 2.8321 -1.7399 270)
			(unlocked yes)
			(layer "B.Fab")
			(hide yes)
			(effects
				(font
					(size 1.016 1.016)
					(thickness 0.1524)
				)
				(justify mirror)
			)
		)
		(property "Device Type" "C0201H13"
			(at 2.8321 -3.2639 270)
			(unlocked yes)
			(layer "B.Fab")
			(hide yes)
			(effects
				(font
					(size 1.016 1.016)
					(thickness 0.1524)
				)
				(justify mirror)
			)
		)
		(duplicate_pad_numbers_are_jumpers no)
		(fp_rect
			(start 0.2794 0.6477)
			(end -0.2794 -0.6477)
			(stroke
				(width 0)
				(type default)
			)
			(fill no)
			(layer "B.CrtYd")
		)
		(fp_rect
			(start 0.2794 0.6477)
			(end -0.2794 -0.6477)
			(stroke
				(width 0)
				(type default)
			)
			(fill no)
			(layer "B.Fab")
		)
		(pad "1" smd custom
			(at 0 -0.2794 90)
			(size 0.0762 0.0762)
			(layers "B.Cu" "B.Mask" "B.Paste")
			(net "PHY_DPB_TO_SCC_7_DN")
			(options
				(clearance outline)
				(anchor circle)
			)
			(primitives
				(gr_poly
					(pts
						(arc
							(start 0.1524 0.127)
							(mid 0.137521 0.162921)
							(end 0.1016 0.1778)
						)
						(arc
							(start -0.1016 0.1778)
							(mid -0.137521 0.162921)
							(end -0.1524 0.127)
						)
						(arc
							(start -0.1524 -0.127)
							(mid -0.137521 -0.162921)
							(end -0.1016 -0.1778)
						)
						(arc
							(start 0.1016 -0.1778)
							(mid 0.137521 -0.162921)
							(end 0.1524 -0.127)
						)
					)
					(width 0)
					(fill yes)
				)
			)
		)
		(pad "2" smd custom
			(at 0 0.2794 90)
			(size 0.0762 0.0762)
			(layers "B.Cu" "B.Mask" "B.Paste")
			(net "PHY_DPB_TO_SCC_C_7_DN")
			(options
				(clearance outline)
				(anchor circle)
			)
			(primitives
				(gr_poly
					(pts
						(arc
							(start 0.1524 0.127)
							(mid 0.137521 0.162921)
							(end 0.1016 0.1778)
						)
						(arc
							(start -0.1016 0.1778)
							(mid -0.137521 0.162921)
							(end -0.1524 0.127)
						)
						(arc
							(start -0.1524 -0.127)
							(mid -0.137521 -0.162921)
							(end -0.1016 -0.1778)
						)
						(arc
							(start 0.1016 -0.1778)
							(mid 0.137521 -0.162921)
							(end 0.1524 -0.127)
						)
					)
					(width 0)
					(fill yes)
				)
			)
		)
	)
	(footprint ""
		(layer "B.Cu")
		(at 104.8258 -44.2214 180)
		(property "Reference" "C78"
			(at 0 0 0)
			(layer "B.SilkS")
			(hide yes)
			(effects
				(font
					(size 1.27 1.27)
				)
				(justify mirror)
			)
		)
		(property "Value" "SCD01U16V1KX-GP"
			(at 2.8321 -1.7399 180)
			(unlocked yes)
			(layer "B.Fab")
			(hide yes)
			(effects
				(font
					(size 1.016 1.016)
					(thickness 0.1524)
				)
				(justify mirror)
			)
		)
		(property "Device Type" "C0201H13"
			(at 2.8321 -3.2639 180)
			(unlocked yes)
			(layer "B.Fab")
			(hide yes)
			(effects
				(font
					(size 1.016 1.016)
					(thickness 0.1524)
				)
				(justify mirror)
			)
		)
		(duplicate_pad_numbers_are_jumpers no)
		(fp_rect
			(start 0.2794 0.6477)
			(end -0.2794 -0.6477)
			(stroke
				(width 0)
				(type default)
			)
			(fill no)
			(layer "B.CrtYd")
		)
		(fp_rect
			(start 0.2794 0.6477)
			(end -0.2794 -0.6477)
			(stroke
				(width 0)
				(type default)
			)
			(fill no)
			(layer "B.Fab")
		)
		(pad "1" smd custom
			(at 0 -0.2794)
			(size 0.0762 0.0762)
			(layers "B.Cu" "B.Mask" "B.Paste")
			(net "PHY_DPB_TO_SCC_21_DP")
			(options
				(clearance outline)
				(anchor circle)
			)
			(primitives
				(gr_poly
					(pts
						(arc
							(start 0.1524 0.127)
							(mid 0.137521 0.162921)
							(end 0.1016 0.1778)
						)
						(arc
							(start -0.1016 0.1778)
							(mid -0.137521 0.162921)
							(end -0.1524 0.127)
						)
						(arc
							(start -0.1524 -0.127)
							(mid -0.137521 -0.162921)
							(end -0.1016 -0.1778)
						)
						(arc
							(start 0.1016 -0.1778)
							(mid 0.137521 -0.162921)
							(end 0.1524 -0.127)
						)
					)
					(width 0)
					(fill yes)
				)
			)
		)
		(pad "2" smd custom
			(at 0 0.2794)
			(size 0.0762 0.0762)
			(layers "B.Cu" "B.Mask" "B.Paste")
			(net "PHY_DPB_TO_SCC_C_21_DP")
			(options
				(clearance outline)
				(anchor circle)
			)
			(primitives
				(gr_poly
					(pts
						(arc
							(start 0.1524 0.127)
							(mid 0.137521 0.162921)
							(end 0.1016 0.1778)
						)
						(arc
							(start -0.1016 0.1778)
							(mid -0.137521 0.162921)
							(end -0.1524 0.127)
						)
						(arc
							(start -0.1524 -0.127)
							(mid -0.137521 -0.162921)
							(end -0.1016 -0.1778)
						)
						(arc
							(start 0.1016 -0.1778)
							(mid 0.137521 -0.162921)
							(end 0.1524 -0.127)
						)
					)
					(width 0)
					(fill yes)
				)
			)
		)
	)
	(footprint ""
		(layer "B.Cu")
		(at 138.50493 -119.731282 -90)
		(property "Reference" "C608"
			(at 0 0 90)
			(layer "B.SilkS")
			(hide yes)
			(effects
				(font
					(size 1.27 1.27)
				)
				(justify mirror)
			)
		)
		(property "Value" "SCD47U25V3KX-3-GP"
			(at 0 -2.8194 270)
			(unlocked yes)
			(layer "B.Fab")
			(hide yes)
			(effects
				(font
					(size 1.016 1.016)
					(thickness 0.1524)
				)
				(justify mirror)
			)
		)
		(property "Device Type" "C603H36"
			(at 0 -4.3434 270)
			(unlocked yes)
			(layer "B.Fab")
			(hide yes)
			(effects
				(font
					(size 1.016 1.016)
					(thickness 0.1524)
				)
				(justify mirror)
			)
		)
		(duplicate_pad_numbers_are_jumpers no)
		(fp_line
			(start -0.508 0)
			(end 0.508 0)
			(stroke
				(width 0.2032)
				(type default)
			)
			(layer "B.SilkS")
		)
		(fp_rect
			(start 0.5842 1.3335)
			(end -0.5842 -1.3335)
			(stroke
				(width 0)
				(type default)
			)
			(fill no)
			(layer "B.CrtYd")
		)
		(fp_rect
			(start 0.5842 1.3335)
			(end -0.5842 -1.3335)
			(stroke
				(width 0)
				(type default)
			)
			(fill no)
			(layer "B.Fab")
		)
		(pad "1" smd custom
			(at 0 -0.762 90)
			(size 0.2159 0.2159)
			(layers "B.Cu" "B.Mask" "B.Paste")
			(net "P1V5_C_PG_G")
			(options
				(clearance outline)
				(anchor circle)
			)
			(primitives
				(gr_poly
					(pts
						(arc
							(start -0.3302 0.4318)
							(mid -0.402042 0.402042)
							(end -0.4318 0.3302)
						)
						(arc
							(start -0.4318 -0.3302)
							(mid -0.402042 -0.402042)
							(end -0.3302 -0.4318)
						)
						(arc
							(start 0.3302 -0.4318)
							(mid 0.402042 -0.402042)
							(end 0.4318 -0.3302)
						)
						(arc
							(start 0.4318 0.3302)
							(mid 0.402042 0.402042)
							(end 0.3302 0.4318)
						)
					)
					(width 0)
					(fill yes)
				)
			)
		)
		(pad "2" smd custom
			(at 0 0.762 90)
			(size 0.2159 0.2159)
			(layers "B.Cu" "B.Mask" "B.Paste")
			(net "P1V5_C")
			(options
				(clearance outline)
				(anchor circle)
			)
			(primitives
				(gr_poly
					(pts
						(arc
							(start -0.3302 0.4318)
							(mid -0.402042 0.402042)
							(end -0.4318 0.3302)
						)
						(arc
							(start -0.4318 -0.3302)
							(mid -0.402042 -0.402042)
							(end -0.3302 -0.4318)
						)
						(arc
							(start 0.3302 -0.4318)
							(mid 0.402042 -0.402042)
							(end 0.4318 -0.3302)
						)
						(arc
							(start 0.4318 0.3302)
							(mid 0.402042 0.402042)
							(end 0.3302 0.4318)
						)
					)
					(width 0)
					(fill yes)
				)
			)
		)
	)
	(footprint ""
		(layer "B.Cu")
		(at 171.167298 -34.108644 180)
		(property "Reference" "C390"
			(at 0 0 0)
			(layer "B.SilkS")
			(hide yes)
			(effects
				(font
					(size 1.27 1.27)
				)
				(justify mirror)
			)
		)
		(property "Value" "SCD1U6D3V1KX-GP"
			(at 2.8321 -1.7399 180)
			(unlocked yes)
			(layer "B.Fab")
			(hide yes)
			(effects
				(font
					(size 1.016 1.016)
					(thickness 0.1524)
				)
				(justify mirror)
			)
		)
		(property "Device Type" "C0201H13"
			(at 2.8321 -3.2639 180)
			(unlocked yes)
			(layer "B.Fab")
			(hide yes)
			(effects
				(font
					(size 1.016 1.016)
					(thickness 0.1524)
				)
				(justify mirror)
			)
		)
		(duplicate_pad_numbers_are_jumpers no)
		(fp_rect
			(start 0.2794 0.6477)
			(end -0.2794 -0.6477)
			(stroke
				(width 0)
				(type default)
			)
			(fill no)
			(layer "B.CrtYd")
		)
		(fp_rect
			(start 0.2794 0.6477)
			(end -0.2794 -0.6477)
			(stroke
				(width 0)
				(type default)
			)
			(fill no)
			(layer "B.Fab")
		)
		(pad "1" smd custom
			(at 0 -0.2794)
			(size 0.0762 0.0762)
			(layers "B.Cu" "B.Mask" "B.Paste")
			(net "PCE_AVDD")
			(options
				(clearance outline)
				(anchor circle)
			)
			(primitives
				(gr_poly
					(pts
						(arc
							(start 0.1524 0.127)
							(mid 0.137521 0.162921)
							(end 0.1016 0.1778)
						)
						(arc
							(start -0.1016 0.1778)
							(mid -0.137521 0.162921)
							(end -0.1524 0.127)
						)
						(arc
							(start -0.1524 -0.127)
							(mid -0.137521 -0.162921)
							(end -0.1016 -0.1778)
						)
						(arc
							(start 0.1016 -0.1778)
							(mid 0.137521 -0.162921)
							(end 0.1524 -0.127)
						)
					)
					(width 0)
					(fill yes)
				)
			)
		)
		(pad "2" smd custom
			(at 0 0.2794)
			(size 0.0762 0.0762)
			(layers "B.Cu" "B.Mask" "B.Paste")
			(net "GND")
			(options
				(clearance outline)
				(anchor circle)
			)
			(primitives
				(gr_poly
					(pts
						(arc
							(start 0.1524 0.127)
							(mid 0.137521 0.162921)
							(end 0.1016 0.1778)
						)
						(arc
							(start -0.1016 0.1778)
							(mid -0.137521 0.162921)
							(end -0.1524 0.127)
						)
						(arc
							(start -0.1524 -0.127)
							(mid -0.137521 -0.162921)
							(end -0.1016 -0.1778)
						)
						(arc
							(start 0.1016 -0.1778)
							(mid 0.137521 -0.162921)
							(end 0.1524 -0.127)
						)
					)
					(width 0)
					(fill yes)
				)
			)
		)
	)
	(footprint ""
		(layer "B.Cu")
		(at 191.953134 -36.8427 -90)
		(property "Reference" "R185"
			(at 0 0 90)
			(layer "B.SilkS")
			(hide yes)
			(effects
				(font
					(size 1.27 1.27)
				)
				(justify mirror)
			)
		)
		(property "Value" "2K2R2F-GP"
			(at -0.064008 -3.993896 270)
			(unlocked yes)
			(layer "B.Fab")
			(hide yes)
			(effects
				(font
					(size 1.016 1.016)
					(thickness 0.1524)
				)
				(justify mirror)
			)
		)
		(property "Device Type" "R402H16"
			(at -0.064008 -5.517896 270)
			(unlocked yes)
			(layer "B.Fab")
			(hide yes)
			(effects
				(font
					(size 1.016 1.016)
					(thickness 0.1524)
				)
				(justify mirror)
			)
		)
		(duplicate_pad_numbers_are_jumpers no)
		(fp_line
			(start -0.508 -0.9398)
			(end 0.508 -0.9398)
			(stroke
				(width 0.1524)
				(type default)
			)
			(layer "B.SilkS")
		)
		(fp_line
			(start 0.508 -0.9398)
			(end 0.508 0.9398)
			(stroke
				(width 0.1524)
				(type default)
			)
			(layer "B.SilkS")
		)
		(fp_rect
			(start 0.508 0.9398)
			(end -0.508 -0.9398)
			(stroke
				(width 0)
				(type default)
			)
			(fill no)
			(layer "B.CrtYd")
		)
		(fp_rect
			(start 0.508 0.9398)
			(end -0.508 -0.9398)
			(stroke
				(width 0)
				(type default)
			)
			(fill no)
			(layer "B.Fab")
		)
		(pad "1" smd custom
			(at 0 -0.4445 90)
			(size 0.1397 0.1397)
			(layers "B.Cu" "B.Mask" "B.Paste")
			(net "P1V8_C")
			(options
				(clearance outline)
				(anchor circle)
			)
			(primitives
				(gr_poly
					(pts
						(arc
							(start -0.1778 0.2794)
							(mid -0.249642 0.249642)
							(end -0.2794 0.1778)
						)
						(arc
							(start -0.2794 -0.1778)
							(mid -0.249642 -0.249642)
							(end -0.1778 -0.2794)
						)
						(arc
							(start 0.1778 -0.2794)
							(mid 0.249642 -0.249642)
							(end 0.2794 -0.1778)
						)
						(arc
							(start 0.2794 0.1778)
							(mid 0.249642 0.249642)
							(end 0.1778 0.2794)
						)
					)
					(width 0)
					(fill yes)
				)
			)
		)
		(pad "2" smd custom
			(at 0 0.4445 90)
			(size 0.1397 0.1397)
			(layers "B.Cu" "B.Mask" "B.Paste")
			(net "I2C_IOC_2_SCL")
			(options
				(clearance outline)
				(anchor circle)
			)
			(primitives
				(gr_poly
					(pts
						(arc
							(start -0.1778 0.2794)
							(mid -0.249642 0.249642)
							(end -0.2794 0.1778)
						)
						(arc
							(start -0.2794 -0.1778)
							(mid -0.249642 -0.249642)
							(end -0.1778 -0.2794)
						)
						(arc
							(start 0.1778 -0.2794)
							(mid 0.249642 -0.249642)
							(end 0.2794 -0.1778)
						)
						(arc
							(start 0.2794 0.1778)
							(mid 0.249642 0.249642)
							(end 0.1778 0.2794)
						)
					)
					(width 0)
					(fill yes)
				)
			)
		)
	)
	(footprint ""
		(layer "B.Cu")
		(at 188.341 -37.211 90)
		(property "Reference" "TP77"
			(at 0 0 90)
			(layer "B.SilkS")
			(hide yes)
			(effects
				(font
					(size 1.27 1.27)
				)
				(justify mirror)
			)
		)
		(property "Value" "TPAD28-2-GP"
			(at 0.0127 -1.6637 90)
			(unlocked yes)
			(layer "B.Fab")
			(hide yes)
			(effects
				(font
					(size 1.016 1.016)
					(thickness 0.1524)
				)
				(justify mirror)
			)
		)
		(property "Device Type" "TPAD28"
			(at 0.0127 -3.1877 90)
			(unlocked yes)
			(layer "B.Fab")
			(hide yes)
			(effects
				(font
					(size 1.016 1.016)
					(thickness 0.1524)
				)
				(justify mirror)
			)
		)
		(duplicate_pad_numbers_are_jumpers no)
		(fp_poly
			(pts
				(arc
					(start 0 0.3556)
					(mid 0 -0.3556)
					(end 0 0.3556)
				)
			)
			(stroke
				(width 0)
				(type default)
			)
			(fill no)
			(layer "B.CrtYd")
		)
		(fp_poly
			(pts
				(arc
					(start 0 0.6096)
					(mid 0 -0.6096)
					(end 0 0.6096)
				)
			)
			(stroke
				(width 0)
				(type default)
			)
			(fill no)
			(layer "B.Fab")
		)
		(pad "1" smd circle
			(at 0 0 270)
			(size 0.7112 0.7112)
			(layers "B.Cu" "B.Mask" "B.Paste")
			(net "IOC_GPIO_24")
		)
	)
	(footprint ""
		(layer "B.Cu")
		(at 169.5577 -21.004276)
		(property "Reference" "C316"
			(at 0 0 0)
			(layer "B.SilkS")
			(hide yes)
			(effects
				(font
					(size 1.27 1.27)
				)
				(justify mirror)
			)
		)
		(property "Value" "SCD22U10V1KX-GP"
			(at 2.8321 -1.7399 0)
			(unlocked yes)
			(layer "B.Fab")
			(hide yes)
			(effects
				(font
					(size 1.016 1.016)
					(thickness 0.1524)
				)
				(justify mirror)
			)
		)
		(property "Device Type" "C0201H13"
			(at 2.8321 -3.2639 0)
			(unlocked yes)
			(layer "B.Fab")
			(hide yes)
			(effects
				(font
					(size 1.016 1.016)
					(thickness 0.1524)
				)
				(justify mirror)
			)
		)
		(duplicate_pad_numbers_are_jumpers no)
		(fp_rect
			(start 0.2794 0.6477)
			(end -0.2794 -0.6477)
			(stroke
				(width 0)
				(type default)
			)
			(fill no)
			(layer "B.CrtYd")
		)
		(fp_rect
			(start 0.2794 0.6477)
			(end -0.2794 -0.6477)
			(stroke
				(width 0)
				(type default)
			)
			(fill no)
			(layer "B.Fab")
		)
		(pad "1" smd custom
			(at 0 -0.2794 180)
			(size 0.0762 0.0762)
			(layers "B.Cu" "B.Mask" "B.Paste")
			(net "PCIE_SCC_TO_COMP_C_2_DN")
			(options
				(clearance outline)
				(anchor circle)
			)
			(primitives
				(gr_poly
					(pts
						(arc
							(start 0.1524 0.127)
							(mid 0.137521 0.162921)
							(end 0.1016 0.1778)
						)
						(arc
							(start -0.1016 0.1778)
							(mid -0.137521 0.162921)
							(end -0.1524 0.127)
						)
						(arc
							(start -0.1524 -0.127)
							(mid -0.137521 -0.162921)
							(end -0.1016 -0.1778)
						)
						(arc
							(start 0.1016 -0.1778)
							(mid 0.137521 -0.162921)
							(end 0.1524 -0.127)
						)
					)
					(width 0)
					(fill yes)
				)
			)
		)
		(pad "2" smd custom
			(at 0 0.2794 180)
			(size 0.0762 0.0762)
			(layers "B.Cu" "B.Mask" "B.Paste")
			(net "PCIE_SCC_TO_COMP_2_DN")
			(options
				(clearance outline)
				(anchor circle)
			)
			(primitives
				(gr_poly
					(pts
						(arc
							(start 0.1524 0.127)
							(mid 0.137521 0.162921)
							(end 0.1016 0.1778)
						)
						(arc
							(start -0.1016 0.1778)
							(mid -0.137521 0.162921)
							(end -0.1524 0.127)
						)
						(arc
							(start -0.1524 -0.127)
							(mid -0.137521 -0.162921)
							(end -0.1016 -0.1778)
						)
						(arc
							(start 0.1016 -0.1778)
							(mid 0.137521 -0.162921)
							(end 0.1524 -0.127)
						)
					)
					(width 0)
					(fill yes)
				)
			)
		)
	)
	(footprint ""
		(layer "B.Cu")
		(at 139.168632 -84.691728)
		(property "Reference" "R49"
			(at 0 0 0)
			(layer "B.SilkS")
			(hide yes)
			(effects
				(font
					(size 1.27 1.27)
				)
				(justify mirror)
			)
		)
		(property "Value" "4K7R2F-GP"
			(at -0.064008 -3.993896 0)
			(unlocked yes)
			(layer "B.Fab")
			(hide yes)
			(effects
				(font
					(size 1.016 1.016)
					(thickness 0.1524)
				)
				(justify mirror)
			)
		)
		(property "Device Type" "R402H16"
			(at -0.064008 -5.517896 0)
			(unlocked yes)
			(layer "B.Fab")
			(hide yes)
			(effects
				(font
					(size 1.016 1.016)
					(thickness 0.1524)
				)
				(justify mirror)
			)
		)
		(duplicate_pad_numbers_are_jumpers no)
		(fp_line
			(start -0.508 -0.9398)
			(end 0.508 -0.9398)
			(stroke
				(width 0.1524)
				(type default)
			)
			(layer "B.SilkS")
		)
		(fp_line
			(start 0.508 -0.9398)
			(end 0.508 0.9398)
			(stroke
				(width 0.1524)
				(type default)
			)
			(layer "B.SilkS")
		)
		(fp_rect
			(start 0.508 0.9398)
			(end -0.508 -0.9398)
			(stroke
				(width 0)
				(type default)
			)
			(fill no)
			(layer "B.CrtYd")
		)
		(fp_rect
			(start 0.508 0.9398)
			(end -0.508 -0.9398)
			(stroke
				(width 0)
				(type default)
			)
			(fill no)
			(layer "B.Fab")
		)
		(pad "1" smd custom
			(at 0 -0.4445 180)
			(size 0.1397 0.1397)
			(layers "B.Cu" "B.Mask" "B.Paste")
			(net "P1V8_E")
			(options
				(clearance outline)
				(anchor circle)
			)
			(primitives
				(gr_poly
					(pts
						(arc
							(start -0.1778 0.2794)
							(mid -0.249642 0.249642)
							(end -0.2794 0.1778)
						)
						(arc
							(start -0.2794 -0.1778)
							(mid -0.249642 -0.249642)
							(end -0.1778 -0.2794)
						)
						(arc
							(start 0.1778 -0.2794)
							(mid 0.249642 -0.249642)
							(end 0.2794 -0.1778)
						)
						(arc
							(start 0.2794 0.1778)
							(mid 0.249642 0.249642)
							(end 0.1778 0.2794)
						)
					)
					(width 0)
					(fill yes)
				)
			)
		)
		(pad "2" smd custom
			(at 0 0.4445 180)
			(size 0.1397 0.1397)
			(layers "B.Cu" "B.Mask" "B.Paste")
			(net "I2C_BMC_LOC_SDA0_LS")
			(options
				(clearance outline)
				(anchor circle)
			)
			(primitives
				(gr_poly
					(pts
						(arc
							(start -0.1778 0.2794)
							(mid -0.249642 0.249642)
							(end -0.2794 0.1778)
						)
						(arc
							(start -0.2794 -0.1778)
							(mid -0.249642 -0.249642)
							(end -0.1778 -0.2794)
						)
						(arc
							(start 0.1778 -0.2794)
							(mid 0.249642 -0.249642)
							(end 0.2794 -0.1778)
						)
						(arc
							(start 0.2794 0.1778)
							(mid 0.249642 0.249642)
							(end 0.1778 0.2794)
						)
					)
					(width 0)
					(fill yes)
				)
			)
		)
	)
	(footprint ""
		(layer "B.Cu")
		(at 92.168472 -67.625214 180)
		(property "Reference" "C200"
			(at 0 0 0)
			(layer "B.SilkS")
			(hide yes)
			(effects
				(font
					(size 1.27 1.27)
				)
				(justify mirror)
			)
		)
		(property "Value" "SC22U6D3V3MX-9-GP-U"
			(at 0 -2.8194 180)
			(unlocked yes)
			(layer "B.Fab")
			(hide yes)
			(effects
				(font
					(size 1.016 1.016)
					(thickness 0.1524)
				)
				(justify mirror)
			)
		)
		(property "Device Type" "C603H40"
			(at 0 -4.3434 180)
			(unlocked yes)
			(layer "B.Fab")
			(hide yes)
			(effects
				(font
					(size 1.016 1.016)
					(thickness 0.1524)
				)
				(justify mirror)
			)
		)
		(duplicate_pad_numbers_are_jumpers no)
		(fp_line
			(start -0.508 0)
			(end 0.508 0)
			(stroke
				(width 0.2032)
				(type default)
			)
			(layer "B.SilkS")
		)
		(fp_rect
			(start 0.5842 1.3335)
			(end -0.5842 -1.3335)
			(stroke
				(width 0)
				(type default)
			)
			(fill no)
			(layer "B.CrtYd")
		)
		(fp_rect
			(start 0.5842 1.3335)
			(end -0.5842 -1.3335)
			(stroke
				(width 0)
				(type default)
			)
			(fill no)
			(layer "B.Fab")
		)
		(pad "1" smd custom
			(at 0 -0.762)
			(size 0.2159 0.2159)
			(layers "B.Cu" "B.Mask" "B.Paste")
			(net "PLLDDR_VDDA18")
			(options
				(clearance outline)
				(anchor circle)
			)
			(primitives
				(gr_poly
					(pts
						(arc
							(start -0.3302 0.4318)
							(mid -0.402042 0.402042)
							(end -0.4318 0.3302)
						)
						(arc
							(start -0.4318 -0.3302)
							(mid -0.402042 -0.402042)
							(end -0.3302 -0.4318)
						)
						(arc
							(start 0.3302 -0.4318)
							(mid 0.402042 -0.402042)
							(end 0.4318 -0.3302)
						)
						(arc
							(start 0.4318 0.3302)
							(mid 0.402042 0.402042)
							(end 0.3302 0.4318)
						)
					)
					(width 0)
					(fill yes)
				)
			)
		)
		(pad "2" smd custom
			(at 0 0.762)
			(size 0.2159 0.2159)
			(layers "B.Cu" "B.Mask" "B.Paste")
			(net "GND")
			(options
				(clearance outline)
				(anchor circle)
			)
			(primitives
				(gr_poly
					(pts
						(arc
							(start -0.3302 0.4318)
							(mid -0.402042 0.402042)
							(end -0.4318 0.3302)
						)
						(arc
							(start -0.4318 -0.3302)
							(mid -0.402042 -0.402042)
							(end -0.3302 -0.4318)
						)
						(arc
							(start 0.3302 -0.4318)
							(mid 0.402042 -0.402042)
							(end 0.4318 -0.3302)
						)
						(arc
							(start 0.4318 0.3302)
							(mid 0.402042 0.402042)
							(end 0.3302 0.4318)
						)
					)
					(width 0)
					(fill yes)
				)
			)
		)
	)
	(footprint ""
		(layer "B.Cu")
		(at 162.56 -52.07)
		(property "Reference" "R204"
			(at 0 0 0)
			(layer "B.SilkS")
			(hide yes)
			(effects
				(font
					(size 1.27 1.27)
				)
				(justify mirror)
			)
		)
		(property "Value" "2K2R2F-GP"
			(at -0.064008 -3.993896 0)
			(unlocked yes)
			(layer "B.Fab")
			(hide yes)
			(effects
				(font
					(size 1.016 1.016)
					(thickness 0.1524)
				)
				(justify mirror)
			)
		)
		(property "Device Type" "R402H16"
			(at -0.064008 -5.517896 0)
			(unlocked yes)
			(layer "B.Fab")
			(hide yes)
			(effects
				(font
					(size 1.016 1.016)
					(thickness 0.1524)
				)
				(justify mirror)
			)
		)
		(duplicate_pad_numbers_are_jumpers no)
		(fp_line
			(start -0.508 -0.9398)
			(end 0.508 -0.9398)
			(stroke
				(width 0.1524)
				(type default)
			)
			(layer "B.SilkS")
		)
		(fp_line
			(start 0.508 -0.9398)
			(end 0.508 0.9398)
			(stroke
				(width 0.1524)
				(type default)
			)
			(layer "B.SilkS")
		)
		(fp_rect
			(start 0.508 0.9398)
			(end -0.508 -0.9398)
			(stroke
				(width 0)
				(type default)
			)
			(fill no)
			(layer "B.CrtYd")
		)
		(fp_rect
			(start 0.508 0.9398)
			(end -0.508 -0.9398)
			(stroke
				(width 0)
				(type default)
			)
			(fill no)
			(layer "B.Fab")
		)
		(pad "1" smd custom
			(at 0 -0.4445 180)
			(size 0.1397 0.1397)
			(layers "B.Cu" "B.Mask" "B.Paste")
			(net "P1V8_C")
			(options
				(clearance outline)
				(anchor circle)
			)
			(primitives
				(gr_poly
					(pts
						(arc
							(start -0.1778 0.2794)
							(mid -0.249642 0.249642)
							(end -0.2794 0.1778)
						)
						(arc
							(start -0.2794 -0.1778)
							(mid -0.249642 -0.249642)
							(end -0.1778 -0.2794)
						)
						(arc
							(start 0.1778 -0.2794)
							(mid 0.249642 -0.249642)
							(end 0.2794 -0.1778)
						)
						(arc
							(start 0.2794 0.1778)
							(mid 0.249642 0.249642)
							(end 0.1778 0.2794)
						)
					)
					(width 0)
					(fill yes)
				)
			)
		)
		(pad "2" smd custom
			(at 0 0.4445 180)
			(size 0.1397 0.1397)
			(layers "B.Cu" "B.Mask" "B.Paste")
			(net "SIO_LOAD_1")
			(options
				(clearance outline)
				(anchor circle)
			)
			(primitives
				(gr_poly
					(pts
						(arc
							(start -0.1778 0.2794)
							(mid -0.249642 0.249642)
							(end -0.2794 0.1778)
						)
						(arc
							(start -0.2794 -0.1778)
							(mid -0.249642 -0.249642)
							(end -0.1778 -0.2794)
						)
						(arc
							(start 0.1778 -0.2794)
							(mid 0.249642 -0.249642)
							(end 0.2794 -0.1778)
						)
						(arc
							(start 0.2794 0.1778)
							(mid 0.249642 0.249642)
							(end 0.1778 0.2794)
						)
					)
					(width 0)
					(fill yes)
				)
			)
		)
	)
	(footprint ""
		(layer "B.Cu")
		(at 76.454 -57.404)
		(property "Reference" "C249"
			(at 0 0 0)
			(layer "B.SilkS")
			(hide yes)
			(effects
				(font
					(size 1.27 1.27)
				)
				(justify mirror)
			)
		)
		(property "Value" "SC22U6D3V3MX-9-GP-U"
			(at 0 -2.8194 0)
			(unlocked yes)
			(layer "B.Fab")
			(hide yes)
			(effects
				(font
					(size 1.016 1.016)
					(thickness 0.1524)
				)
				(justify mirror)
			)
		)
		(property "Device Type" "C603H40"
			(at 0 -4.3434 0)
			(unlocked yes)
			(layer "B.Fab")
			(hide yes)
			(effects
				(font
					(size 1.016 1.016)
					(thickness 0.1524)
				)
				(justify mirror)
			)
		)
		(duplicate_pad_numbers_are_jumpers no)
		(fp_line
			(start -0.508 0)
			(end 0.508 0)
			(stroke
				(width 0.2032)
				(type default)
			)
			(layer "B.SilkS")
		)
		(fp_rect
			(start 0.5842 1.3335)
			(end -0.5842 -1.3335)
			(stroke
				(width 0)
				(type default)
			)
			(fill no)
			(layer "B.CrtYd")
		)
		(fp_rect
			(start 0.5842 1.3335)
			(end -0.5842 -1.3335)
			(stroke
				(width 0)
				(type default)
			)
			(fill no)
			(layer "B.Fab")
		)
		(pad "1" smd custom
			(at 0 -0.762 180)
			(size 0.2159 0.2159)
			(layers "B.Cu" "B.Mask" "B.Paste")
			(net "GB_VDDA")
			(options
				(clearance outline)
				(anchor circle)
			)
			(primitives
				(gr_poly
					(pts
						(arc
							(start -0.3302 0.4318)
							(mid -0.402042 0.402042)
							(end -0.4318 0.3302)
						)
						(arc
							(start -0.4318 -0.3302)
							(mid -0.402042 -0.402042)
							(end -0.3302 -0.4318)
						)
						(arc
							(start 0.3302 -0.4318)
							(mid 0.402042 -0.402042)
							(end 0.4318 -0.3302)
						)
						(arc
							(start 0.4318 0.3302)
							(mid 0.402042 0.402042)
							(end 0.3302 0.4318)
						)
					)
					(width 0)
					(fill yes)
				)
			)
		)
		(pad "2" smd custom
			(at 0 0.762 180)
			(size 0.2159 0.2159)
			(layers "B.Cu" "B.Mask" "B.Paste")
			(net "GND")
			(options
				(clearance outline)
				(anchor circle)
			)
			(primitives
				(gr_poly
					(pts
						(arc
							(start -0.3302 0.4318)
							(mid -0.402042 0.402042)
							(end -0.4318 0.3302)
						)
						(arc
							(start -0.4318 -0.3302)
							(mid -0.402042 -0.402042)
							(end -0.3302 -0.4318)
						)
						(arc
							(start 0.3302 -0.4318)
							(mid 0.402042 -0.402042)
							(end 0.4318 -0.3302)
						)
						(arc
							(start 0.4318 0.3302)
							(mid 0.402042 0.402042)
							(end 0.3302 0.4318)
						)
					)
					(width 0)
					(fill yes)
				)
			)
		)
	)
	(footprint ""
		(layer "B.Cu")
		(at 124.4981 -53.5051 90)
		(property "Reference" "C281"
			(at 0 0 90)
			(layer "B.SilkS")
			(hide yes)
			(effects
				(font
					(size 1.27 1.27)
				)
				(justify mirror)
			)
		)
		(property "Value" "SC1U6D3V1MX-GP"
			(at -1.9177 2.0193 90)
			(unlocked yes)
			(layer "B.Fab")
			(hide yes)
			(effects
				(font
					(size 1.016 1.016)
					(thickness 0.1524)
				)
				(justify mirror)
			)
		)
		(property "Device Type" "C0201H14"
			(at -1.9177 0.4953 90)
			(unlocked yes)
			(layer "B.Fab")
			(hide yes)
			(effects
				(font
					(size 1.016 1.016)
					(thickness 0.1524)
				)
				(justify mirror)
			)
		)
		(duplicate_pad_numbers_are_jumpers no)
		(fp_rect
			(start 0.1524 0.3048)
			(end -0.1524 -0.3048)
			(stroke
				(width 0)
				(type default)
			)
			(fill no)
			(layer "B.CrtYd")
		)
		(fp_poly
			(pts
				(xy 0.2794 0.6477) (xy 0.2794 -0.6477) (xy -0.2794 -0.6477) (xy -0.2794 -0.1905) (xy -0.1524 -0.1905)
				(xy -0.1524 -0.3048) (xy 0.1524 -0.3048) (xy 0.1524 0.3048) (xy -0.1524 0.3048) (xy -0.1524 -0.1778)
				(xy -0.2794 -0.1778) (xy -0.2794 0.6477)
			)
			(stroke
				(width 0)
				(type default)
			)
			(fill no)
			(layer "B.CrtYd")
		)
		(fp_rect
			(start 0.2794 0.6477)
			(end -0.2794 -0.6477)
			(stroke
				(width 0)
				(type default)
			)
			(fill no)
			(layer "B.Fab")
		)
		(pad "1" smd custom
			(at 0 -0.2794 270)
			(size 0.0762 0.0762)
			(layers "B.Cu" "B.Mask" "B.Paste")
			(net "GB_VDDA")
			(options
				(clearance outline)
				(anchor circle)
			)
			(primitives
				(gr_poly
					(pts
						(arc
							(start 0.1524 0.127)
							(mid 0.137521 0.162921)
							(end 0.1016 0.1778)
						)
						(arc
							(start -0.1016 0.1778)
							(mid -0.137521 0.162921)
							(end -0.1524 0.127)
						)
						(arc
							(start -0.1524 -0.127)
							(mid -0.137521 -0.162921)
							(end -0.1016 -0.1778)
						)
						(arc
							(start 0.1016 -0.1778)
							(mid 0.137521 -0.162921)
							(end 0.1524 -0.127)
						)
					)
					(width 0)
					(fill yes)
				)
			)
		)
		(pad "2" smd custom
			(at 0 0.2794 270)
			(size 0.0762 0.0762)
			(layers "B.Cu" "B.Mask" "B.Paste")
			(net "GND")
			(options
				(clearance outline)
				(anchor circle)
			)
			(primitives
				(gr_poly
					(pts
						(arc
							(start 0.1524 0.127)
							(mid 0.137521 0.162921)
							(end 0.1016 0.1778)
						)
						(arc
							(start -0.1016 0.1778)
							(mid -0.137521 0.162921)
							(end -0.1524 0.127)
						)
						(arc
							(start -0.1524 -0.127)
							(mid -0.137521 -0.162921)
							(end -0.1016 -0.1778)
						)
						(arc
							(start 0.1016 -0.1778)
							(mid 0.137521 -0.162921)
							(end 0.1524 -0.127)
						)
					)
					(width 0)
					(fill yes)
				)
			)
		)
	)
	(footprint ""
		(layer "B.Cu")
		(at 123.665742 -88.558624 180)
		(property "Reference" "R156"
			(at 0 0 0)
			(layer "B.SilkS")
			(hide yes)
			(effects
				(font
					(size 1.27 1.27)
				)
				(justify mirror)
			)
		)
		(property "Value" "0R2J-2-GP"
			(at -0.064008 -3.993896 180)
			(unlocked yes)
			(layer "B.Fab")
			(hide yes)
			(effects
				(font
					(size 1.016 1.016)
					(thickness 0.1524)
				)
				(justify mirror)
			)
		)
		(property "Device Type" "R402H16"
			(at -0.064008 -5.517896 180)
			(unlocked yes)
			(layer "B.Fab")
			(hide yes)
			(effects
				(font
					(size 1.016 1.016)
					(thickness 0.1524)
				)
				(justify mirror)
			)
		)
		(duplicate_pad_numbers_are_jumpers no)
		(fp_line
			(start 0.508 -0.9398)
			(end 0.508 0.9398)
			(stroke
				(width 0.1524)
				(type default)
			)
			(layer "B.SilkS")
		)
		(fp_line
			(start -0.508 -0.9398)
			(end 0.508 -0.9398)
			(stroke
				(width 0.1524)
				(type default)
			)
			(layer "B.SilkS")
		)
		(fp_rect
			(start 0.508 0.9398)
			(end -0.508 -0.9398)
			(stroke
				(width 0)
				(type default)
			)
			(fill no)
			(layer "B.CrtYd")
		)
		(fp_rect
			(start 0.508 0.9398)
			(end -0.508 -0.9398)
			(stroke
				(width 0)
				(type default)
			)
			(fill no)
			(layer "B.Fab")
		)
		(pad "1" smd custom
			(at 0 -0.4445)
			(size 0.1397 0.1397)
			(layers "B.Cu" "B.Mask" "B.Paste")
			(net "BMC_EXP_SPARE_0_R_LS")
			(options
				(clearance outline)
				(anchor circle)
			)
			(primitives
				(gr_poly
					(pts
						(arc
							(start -0.1778 0.2794)
							(mid -0.249642 0.249642)
							(end -0.2794 0.1778)
						)
						(arc
							(start -0.2794 -0.1778)
							(mid -0.249642 -0.249642)
							(end -0.1778 -0.2794)
						)
						(arc
							(start 0.1778 -0.2794)
							(mid 0.249642 -0.249642)
							(end 0.2794 -0.1778)
						)
						(arc
							(start 0.2794 0.1778)
							(mid 0.249642 0.249642)
							(end 0.1778 0.2794)
						)
					)
					(width 0)
					(fill yes)
				)
			)
		)
		(pad "2" smd custom
			(at 0 0.4445)
			(size 0.1397 0.1397)
			(layers "B.Cu" "B.Mask" "B.Paste")
			(net "BMC_SPARE_0_LS")
			(options
				(clearance outline)
				(anchor circle)
			)
			(primitives
				(gr_poly
					(pts
						(arc
							(start -0.1778 0.2794)
							(mid -0.249642 0.249642)
							(end -0.2794 0.1778)
						)
						(arc
							(start -0.2794 -0.1778)
							(mid -0.249642 -0.249642)
							(end -0.1778 -0.2794)
						)
						(arc
							(start 0.1778 -0.2794)
							(mid 0.249642 -0.249642)
							(end 0.2794 -0.1778)
						)
						(arc
							(start 0.2794 0.1778)
							(mid 0.249642 0.249642)
							(end 0.1778 0.2794)
						)
					)
					(width 0)
					(fill yes)
				)
			)
		)
	)
	(footprint ""
		(layer "B.Cu")
		(at 177.811176 -39.711122 90)
		(property "Reference" "C421"
			(at 0 0 90)
			(layer "B.SilkS")
			(hide yes)
			(effects
				(font
					(size 1.27 1.27)
				)
				(justify mirror)
			)
		)
		(property "Value" "SCD1U6D3V1KX-GP"
			(at 2.8321 -1.7399 90)
			(unlocked yes)
			(layer "B.Fab")
			(hide yes)
			(effects
				(font
					(size 1.016 1.016)
					(thickness 0.1524)
				)
				(justify mirror)
			)
		)
		(property "Device Type" "C0201H13"
			(at 2.8321 -3.2639 90)
			(unlocked yes)
			(layer "B.Fab")
			(hide yes)
			(effects
				(font
					(size 1.016 1.016)
					(thickness 0.1524)
				)
				(justify mirror)
			)
		)
		(duplicate_pad_numbers_are_jumpers no)
		(fp_rect
			(start 0.2794 0.6477)
			(end -0.2794 -0.6477)
			(stroke
				(width 0)
				(type default)
			)
			(fill no)
			(layer "B.CrtYd")
		)
		(fp_rect
			(start 0.2794 0.6477)
			(end -0.2794 -0.6477)
			(stroke
				(width 0)
				(type default)
			)
			(fill no)
			(layer "B.Fab")
		)
		(pad "1" smd custom
			(at 0 -0.2794 270)
			(size 0.0762 0.0762)
			(layers "B.Cu" "B.Mask" "B.Paste")
			(net "P0V975")
			(options
				(clearance outline)
				(anchor circle)
			)
			(primitives
				(gr_poly
					(pts
						(arc
							(start 0.1524 0.127)
							(mid 0.137521 0.162921)
							(end 0.1016 0.1778)
						)
						(arc
							(start -0.1016 0.1778)
							(mid -0.137521 0.162921)
							(end -0.1524 0.127)
						)
						(arc
							(start -0.1524 -0.127)
							(mid -0.137521 -0.162921)
							(end -0.1016 -0.1778)
						)
						(arc
							(start 0.1016 -0.1778)
							(mid 0.137521 -0.162921)
							(end 0.1524 -0.127)
						)
					)
					(width 0)
					(fill yes)
				)
			)
		)
		(pad "2" smd custom
			(at 0 0.2794 270)
			(size 0.0762 0.0762)
			(layers "B.Cu" "B.Mask" "B.Paste")
			(net "GND")
			(options
				(clearance outline)
				(anchor circle)
			)
			(primitives
				(gr_poly
					(pts
						(arc
							(start 0.1524 0.127)
							(mid 0.137521 0.162921)
							(end 0.1016 0.1778)
						)
						(arc
							(start -0.1016 0.1778)
							(mid -0.137521 0.162921)
							(end -0.1524 0.127)
						)
						(arc
							(start -0.1524 -0.127)
							(mid -0.137521 -0.162921)
							(end -0.1016 -0.1778)
						)
						(arc
							(start 0.1016 -0.1778)
							(mid 0.137521 -0.162921)
							(end 0.1524 -0.127)
						)
					)
					(width 0)
					(fill yes)
				)
			)
		)
	)
	(footprint ""
		(layer "B.Cu")
		(at 177.813208 -37.04971 90)
		(property "Reference" "C433"
			(at 0 0 90)
			(layer "B.SilkS")
			(hide yes)
			(effects
				(font
					(size 1.27 1.27)
				)
				(justify mirror)
			)
		)
		(property "Value" "SCD1U6D3V1KX-GP"
			(at 2.8321 -1.7399 90)
			(unlocked yes)
			(layer "B.Fab")
			(hide yes)
			(effects
				(font
					(size 1.016 1.016)
					(thickness 0.1524)
				)
				(justify mirror)
			)
		)
		(property "Device Type" "C0201H13"
			(at 2.8321 -3.2639 90)
			(unlocked yes)
			(layer "B.Fab")
			(hide yes)
			(effects
				(font
					(size 1.016 1.016)
					(thickness 0.1524)
				)
				(justify mirror)
			)
		)
		(duplicate_pad_numbers_are_jumpers no)
		(fp_rect
			(start 0.2794 0.6477)
			(end -0.2794 -0.6477)
			(stroke
				(width 0)
				(type default)
			)
			(fill no)
			(layer "B.CrtYd")
		)
		(fp_rect
			(start 0.2794 0.6477)
			(end -0.2794 -0.6477)
			(stroke
				(width 0)
				(type default)
			)
			(fill no)
			(layer "B.Fab")
		)
		(pad "1" smd custom
			(at 0 -0.2794 270)
			(size 0.0762 0.0762)
			(layers "B.Cu" "B.Mask" "B.Paste")
			(net "P0V975")
			(options
				(clearance outline)
				(anchor circle)
			)
			(primitives
				(gr_poly
					(pts
						(arc
							(start 0.1524 0.127)
							(mid 0.137521 0.162921)
							(end 0.1016 0.1778)
						)
						(arc
							(start -0.1016 0.1778)
							(mid -0.137521 0.162921)
							(end -0.1524 0.127)
						)
						(arc
							(start -0.1524 -0.127)
							(mid -0.137521 -0.162921)
							(end -0.1016 -0.1778)
						)
						(arc
							(start 0.1016 -0.1778)
							(mid 0.137521 -0.162921)
							(end 0.1524 -0.127)
						)
					)
					(width 0)
					(fill yes)
				)
			)
		)
		(pad "2" smd custom
			(at 0 0.2794 270)
			(size 0.0762 0.0762)
			(layers "B.Cu" "B.Mask" "B.Paste")
			(net "GND")
			(options
				(clearance outline)
				(anchor circle)
			)
			(primitives
				(gr_poly
					(pts
						(arc
							(start 0.1524 0.127)
							(mid 0.137521 0.162921)
							(end 0.1016 0.1778)
						)
						(arc
							(start -0.1016 0.1778)
							(mid -0.137521 0.162921)
							(end -0.1524 0.127)
						)
						(arc
							(start -0.1524 -0.127)
							(mid -0.137521 -0.162921)
							(end -0.1016 -0.1778)
						)
						(arc
							(start 0.1016 -0.1778)
							(mid 0.137521 -0.162921)
							(end 0.1524 -0.127)
						)
					)
					(width 0)
					(fill yes)
				)
			)
		)
	)
	(footprint ""
		(layer "B.Cu")
		(at 197.104 -20.828)
		(property "Reference" "Q5"
			(at 0 0 0)
			(layer "B.SilkS")
			(hide yes)
			(effects
				(font
					(size 1.27 1.27)
				)
				(justify mirror)
			)
		)
		(property "Value" "2N7002K-1-GP"
			(at -0.127 -8.9662 0)
			(unlocked yes)
			(layer "B.Fab")
			(hide yes)
			(effects
				(font
					(size 1.016 1.016)
					(thickness 0.1524)
				)
				(justify mirror)
			)
		)
		(property "Device Type" "SOT23DGS2D4H44"
			(at -0.127 -10.4902 0)
			(unlocked yes)
			(layer "B.Fab")
			(hide yes)
			(effects
				(font
					(size 1.016 1.016)
					(thickness 0.1524)
				)
				(justify mirror)
			)
		)
		(duplicate_pad_numbers_are_jumpers no)
		(fp_line
			(start -1.651 -1.778)
			(end 1.651 -1.778)
			(stroke
				(width 0.1524)
				(type default)
			)
			(layer "B.SilkS")
		)
		(fp_line
			(start -1.651 1.778)
			(end -1.651 -1.778)
			(stroke
				(width 0.1524)
				(type default)
			)
			(layer "B.SilkS")
		)
		(fp_line
			(start 1.651 -1.778)
			(end 1.651 1.778)
			(stroke
				(width 0.1524)
				(type default)
			)
			(layer "B.SilkS")
		)
		(fp_line
			(start 1.651 1.778)
			(end -1.651 1.778)
			(stroke
				(width 0.1524)
				(type default)
			)
			(layer "B.SilkS")
		)
		(fp_poly
			(pts
				(xy 1.778 1.8796) (xy 1.778 -1.8796) (xy -1.778 -1.8796) (xy -1.778 1.8796)
			)
			(stroke
				(width 0)
				(type default)
			)
			(fill no)
			(layer "B.CrtYd")
		)
		(fp_poly
			(pts
				(xy 1.778 1.8796) (xy 1.778 -1.8796) (xy -1.778 -1.8796) (xy -1.778 1.8796)
			)
			(stroke
				(width 0)
				(type default)
			)
			(fill no)
			(layer "B.Fab")
		)
		(pad "D" smd custom
			(at 0 -0.9525 180)
			(size 0.1905 0.1905)
			(layers "B.Cu" "B.Mask" "B.Paste")
			(net "SYS_RST")
			(options
				(clearance outline)
				(anchor circle)
			)
			(primitives
				(gr_poly
					(pts
						(arc
							(start -0.1778 -0.5715)
							(mid -0.321484 -0.511984)
							(end -0.381 -0.3683)
						)
						(arc
							(start -0.381 0.3683)
							(mid -0.321484 0.511984)
							(end -0.1778 0.5715)
						)
						(arc
							(start 0.1778 0.5715)
							(mid 0.321484 0.511984)
							(end 0.381 0.3683)
						)
						(arc
							(start 0.381 -0.3683)
							(mid 0.321484 -0.511984)
							(end 0.1778 -0.5715)
						)
					)
					(width 0)
					(fill yes)
				)
			)
		)
		(pad "G" smd custom
			(at 0.98425 0.9525 180)
			(size 0.1905 0.1905)
			(layers "B.Cu" "B.Mask" "B.Paste")
			(net "P3V3_STBY_R")
			(options
				(clearance outline)
				(anchor circle)
			)
			(primitives
				(gr_poly
					(pts
						(arc
							(start -0.1778 -0.5715)
							(mid -0.321484 -0.511984)
							(end -0.381 -0.3683)
						)
						(arc
							(start -0.381 0.3683)
							(mid -0.321484 0.511984)
							(end -0.1778 0.5715)
						)
						(arc
							(start 0.1778 0.5715)
							(mid 0.321484 0.511984)
							(end 0.381 0.3683)
						)
						(arc
							(start 0.381 -0.3683)
							(mid 0.321484 -0.511984)
							(end 0.1778 -0.5715)
						)
					)
					(width 0)
					(fill yes)
				)
			)
		)
		(pad "S" smd custom
			(at -0.98425 0.9525 180)
			(size 0.1905 0.1905)
			(layers "B.Cu" "B.Mask" "B.Paste")
			(net "GND")
			(options
				(clearance outline)
				(anchor circle)
			)
			(primitives
				(gr_poly
					(pts
						(arc
							(start -0.1778 -0.5715)
							(mid -0.321484 -0.511984)
							(end -0.381 -0.3683)
						)
						(arc
							(start -0.381 0.3683)
							(mid -0.321484 0.511984)
							(end -0.1778 0.5715)
						)
						(arc
							(start 0.1778 0.5715)
							(mid 0.321484 0.511984)
							(end 0.381 0.3683)
						)
						(arc
							(start 0.381 -0.3683)
							(mid 0.321484 -0.511984)
							(end 0.1778 -0.5715)
						)
					)
					(width 0)
					(fill yes)
				)
			)
		)
	)
	(footprint ""
		(layer "B.Cu")
		(at 119.25046 -74.618088 180)
		(property "Reference" "C121"
			(at 0 0 0)
			(layer "B.SilkS")
			(hide yes)
			(effects
				(font
					(size 1.27 1.27)
				)
				(justify mirror)
			)
		)
		(property "Value" "SC10U6D3V2MX-GP-U"
			(at 1.524 -1.905 180)
			(unlocked yes)
			(layer "B.Fab")
			(hide yes)
			(effects
				(font
					(size 1.016 1.016)
					(thickness 0.1524)
				)
				(justify mirror)
			)
		)
		(property "Device Type" "C402-TO0D2H28"
			(at 1.524 -3.429 180)
			(unlocked yes)
			(layer "B.Fab")
			(hide yes)
			(effects
				(font
					(size 1.016 1.016)
					(thickness 0.1524)
				)
				(justify mirror)
			)
		)
		(duplicate_pad_numbers_are_jumpers no)
		(fp_rect
			(start 0.4826 0.889)
			(end -0.4826 -0.889)
			(stroke
				(width 0)
				(type default)
			)
			(fill no)
			(layer "B.CrtYd")
		)
		(fp_rect
			(start 0.4826 0.889)
			(end -0.4826 -0.889)
			(stroke
				(width 0)
				(type default)
			)
			(fill no)
			(layer "B.Fab")
		)
		(pad "1" smd custom
			(at 0 -0.4572)
			(size 0.1524 0.1524)
			(layers "B.Cu" "B.Mask" "B.Paste")
			(net "P1V8_E")
			(options
				(clearance outline)
				(anchor circle)
			)
			(primitives
				(gr_poly
					(pts
						(arc
							(start -0.254 -0.3048)
							(mid -0.325842 -0.275042)
							(end -0.3556 -0.2032)
						)
						(arc
							(start -0.3556 0.2032)
							(mid -0.325842 0.275042)
							(end -0.254 0.3048)
						)
						(arc
							(start 0.254 0.3048)
							(mid 0.325842 0.275042)
							(end 0.3556 0.2032)
						)
						(arc
							(start 0.3556 -0.2032)
							(mid 0.325842 -0.275042)
							(end 0.254 -0.3048)
						)
					)
					(width 0)
					(fill yes)
				)
			)
		)
		(pad "2" smd custom
			(at 0 0.4572)
			(size 0.1524 0.1524)
			(layers "B.Cu" "B.Mask" "B.Paste")
			(net "GND")
			(options
				(clearance outline)
				(anchor circle)
			)
			(primitives
				(gr_poly
					(pts
						(arc
							(start -0.254 -0.3048)
							(mid -0.325842 -0.275042)
							(end -0.3556 -0.2032)
						)
						(arc
							(start -0.3556 0.2032)
							(mid -0.325842 0.275042)
							(end -0.254 0.3048)
						)
						(arc
							(start 0.254 0.3048)
							(mid 0.325842 0.275042)
							(end 0.3556 0.2032)
						)
						(arc
							(start 0.3556 -0.2032)
							(mid 0.325842 -0.275042)
							(end 0.254 -0.3048)
						)
					)
					(width 0)
					(fill yes)
				)
			)
		)
	)
	(footprint ""
		(layer "B.Cu")
		(at 192.73901 -33.573974 -90)
		(property "Reference" "R233"
			(at 0 0 90)
			(layer "B.SilkS")
			(hide yes)
			(effects
				(font
					(size 1.27 1.27)
				)
				(justify mirror)
			)
		)
		(property "Value" "4K7R2F-GP"
			(at -0.064008 -3.993896 270)
			(unlocked yes)
			(layer "B.Fab")
			(hide yes)
			(effects
				(font
					(size 1.016 1.016)
					(thickness 0.1524)
				)
				(justify mirror)
			)
		)
		(property "Device Type" "R402H16"
			(at -0.064008 -5.517896 270)
			(unlocked yes)
			(layer "B.Fab")
			(hide yes)
			(effects
				(font
					(size 1.016 1.016)
					(thickness 0.1524)
				)
				(justify mirror)
			)
		)
		(duplicate_pad_numbers_are_jumpers no)
		(fp_line
			(start -0.508 -0.9398)
			(end 0.508 -0.9398)
			(stroke
				(width 0.1524)
				(type default)
			)
			(layer "B.SilkS")
		)
		(fp_line
			(start 0.508 -0.9398)
			(end 0.508 0.9398)
			(stroke
				(width 0.1524)
				(type default)
			)
			(layer "B.SilkS")
		)
		(fp_rect
			(start 0.508 0.9398)
			(end -0.508 -0.9398)
			(stroke
				(width 0)
				(type default)
			)
			(fill no)
			(layer "B.CrtYd")
		)
		(fp_rect
			(start 0.508 0.9398)
			(end -0.508 -0.9398)
			(stroke
				(width 0)
				(type default)
			)
			(fill no)
			(layer "B.Fab")
		)
		(pad "1" smd custom
			(at 0 -0.4445 90)
			(size 0.1397 0.1397)
			(layers "B.Cu" "B.Mask" "B.Paste")
			(net "P1V8_C")
			(options
				(clearance outline)
				(anchor circle)
			)
			(primitives
				(gr_poly
					(pts
						(arc
							(start -0.1778 0.2794)
							(mid -0.249642 0.249642)
							(end -0.2794 0.1778)
						)
						(arc
							(start -0.2794 -0.1778)
							(mid -0.249642 -0.249642)
							(end -0.1778 -0.2794)
						)
						(arc
							(start 0.1778 -0.2794)
							(mid 0.249642 -0.249642)
							(end 0.2794 -0.1778)
						)
						(arc
							(start 0.2794 0.1778)
							(mid 0.249642 0.249642)
							(end 0.1778 0.2794)
						)
					)
					(width 0)
					(fill yes)
				)
			)
		)
		(pad "2" smd custom
			(at 0 0.4445 90)
			(size 0.1397 0.1397)
			(layers "B.Cu" "B.Mask" "B.Paste")
			(net "UART_SERCLK")
			(options
				(clearance outline)
				(anchor circle)
			)
			(primitives
				(gr_poly
					(pts
						(arc
							(start -0.1778 0.2794)
							(mid -0.249642 0.249642)
							(end -0.2794 0.1778)
						)
						(arc
							(start -0.2794 -0.1778)
							(mid -0.249642 -0.249642)
							(end -0.1778 -0.2794)
						)
						(arc
							(start 0.1778 -0.2794)
							(mid 0.249642 -0.249642)
							(end 0.2794 -0.1778)
						)
						(arc
							(start 0.2794 0.1778)
							(mid 0.249642 0.249642)
							(end 0.1778 0.2794)
						)
					)
					(width 0)
					(fill yes)
				)
			)
		)
	)
	(footprint ""
		(layer "B.Cu")
		(at 110.469172 -65.488058 -90)
		(property "Reference" "C161"
			(at 0 0 90)
			(layer "B.SilkS")
			(hide yes)
			(effects
				(font
					(size 1.27 1.27)
				)
				(justify mirror)
			)
		)
		(property "Value" "SCD1U6D3V1KX-GP"
			(at 2.8321 -1.7399 270)
			(unlocked yes)
			(layer "B.Fab")
			(hide yes)
			(effects
				(font
					(size 1.016 1.016)
					(thickness 0.1524)
				)
				(justify mirror)
			)
		)
		(property "Device Type" "C0201H13"
			(at 2.8321 -3.2639 270)
			(unlocked yes)
			(layer "B.Fab")
			(hide yes)
			(effects
				(font
					(size 1.016 1.016)
					(thickness 0.1524)
				)
				(justify mirror)
			)
		)
		(duplicate_pad_numbers_are_jumpers no)
		(fp_rect
			(start 0.2794 0.6477)
			(end -0.2794 -0.6477)
			(stroke
				(width 0)
				(type default)
			)
			(fill no)
			(layer "B.CrtYd")
		)
		(fp_rect
			(start 0.2794 0.6477)
			(end -0.2794 -0.6477)
			(stroke
				(width 0)
				(type default)
			)
			(fill no)
			(layer "B.Fab")
		)
		(pad "1" smd custom
			(at 0 -0.2794 90)
			(size 0.0762 0.0762)
			(layers "B.Cu" "B.Mask" "B.Paste")
			(net "P0V9")
			(options
				(clearance outline)
				(anchor circle)
			)
			(primitives
				(gr_poly
					(pts
						(arc
							(start 0.1524 0.127)
							(mid 0.137521 0.162921)
							(end 0.1016 0.1778)
						)
						(arc
							(start -0.1016 0.1778)
							(mid -0.137521 0.162921)
							(end -0.1524 0.127)
						)
						(arc
							(start -0.1524 -0.127)
							(mid -0.137521 -0.162921)
							(end -0.1016 -0.1778)
						)
						(arc
							(start 0.1016 -0.1778)
							(mid 0.137521 -0.162921)
							(end 0.1524 -0.127)
						)
					)
					(width 0)
					(fill yes)
				)
			)
		)
		(pad "2" smd custom
			(at 0 0.2794 90)
			(size 0.0762 0.0762)
			(layers "B.Cu" "B.Mask" "B.Paste")
			(net "GND")
			(options
				(clearance outline)
				(anchor circle)
			)
			(primitives
				(gr_poly
					(pts
						(arc
							(start 0.1524 0.127)
							(mid 0.137521 0.162921)
							(end 0.1016 0.1778)
						)
						(arc
							(start -0.1016 0.1778)
							(mid -0.137521 0.162921)
							(end -0.1524 0.127)
						)
						(arc
							(start -0.1524 -0.127)
							(mid -0.137521 -0.162921)
							(end -0.1016 -0.1778)
						)
						(arc
							(start 0.1016 -0.1778)
							(mid 0.137521 -0.162921)
							(end 0.1524 -0.127)
						)
					)
					(width 0)
					(fill yes)
				)
			)
		)
	)
	(footprint ""
		(layer "B.Cu")
		(at 184.8358 -29.972)
		(property "Reference" "TP144"
			(at 0 0 0)
			(layer "B.SilkS")
			(hide yes)
			(effects
				(font
					(size 1.27 1.27)
				)
				(justify mirror)
			)
		)
		(property "Value" "TPAD28-2-GP"
			(at 0.0127 -1.6637 0)
			(unlocked yes)
			(layer "B.Fab")
			(hide yes)
			(effects
				(font
					(size 1.016 1.016)
					(thickness 0.1524)
				)
				(justify mirror)
			)
		)
		(property "Device Type" "TPAD28"
			(at 0.0127 -3.1877 0)
			(unlocked yes)
			(layer "B.Fab")
			(hide yes)
			(effects
				(font
					(size 1.016 1.016)
					(thickness 0.1524)
				)
				(justify mirror)
			)
		)
		(duplicate_pad_numbers_are_jumpers no)
		(fp_poly
			(pts
				(arc
					(start 0.3556 0)
					(mid -0.3556 0)
					(end 0.3556 0)
				)
			)
			(stroke
				(width 0)
				(type default)
			)
			(fill no)
			(layer "B.CrtYd")
		)
		(fp_poly
			(pts
				(arc
					(start 0.6096 0)
					(mid -0.6096 0)
					(end 0.6096 0)
				)
			)
			(stroke
				(width 0)
				(type default)
			)
			(fill no)
			(layer "B.Fab")
		)
		(pad "1" smd circle
			(at 0 0 180)
			(size 0.7112 0.7112)
			(layers "B.Cu" "B.Mask" "B.Paste")
			(net "SPARE0")
		)
	)
	(footprint ""
		(layer "B.Cu")
		(at 70.485 -50.292 90)
		(property "Reference" "L9"
			(at 0 0 90)
			(layer "B.SilkS")
			(hide yes)
			(effects
				(font
					(size 1.27 1.27)
				)
				(justify mirror)
			)
		)
		(property "Value" "MPZ2012S300AT-GP"
			(at 0 -4.2418 90)
			(unlocked yes)
			(layer "B.Fab")
			(hide yes)
			(effects
				(font
					(size 1.016 1.016)
					(thickness 0.1524)
				)
				(justify mirror)
			)
		)
		(property "Device Type" "L805H42"
			(at 0 -5.7912 90)
			(unlocked yes)
			(layer "B.Fab")
			(hide yes)
			(effects
				(font
					(size 1.016 1.016)
					(thickness 0.1524)
				)
				(justify mirror)
			)
		)
		(duplicate_pad_numbers_are_jumpers no)
		(fp_line
			(start 0.889 -1.7018)
			(end -0.889 -1.7018)
			(stroke
				(width 0.1524)
				(type default)
			)
			(layer "B.SilkS")
		)
		(fp_line
			(start -0.889 -1.7018)
			(end -0.889 1.7018)
			(stroke
				(width 0.1524)
				(type default)
			)
			(layer "B.SilkS")
		)
		(fp_line
			(start 0.889 1.7018)
			(end 0.889 -1.7018)
			(stroke
				(width 0.1524)
				(type default)
			)
			(layer "B.SilkS")
		)
		(fp_line
			(start -0.889 1.7018)
			(end 0.889 1.7018)
			(stroke
				(width 0.1524)
				(type default)
			)
			(layer "B.SilkS")
		)
		(fp_rect
			(start 0.9652 1.778)
			(end -0.9652 -1.778)
			(stroke
				(width 0)
				(type default)
			)
			(fill no)
			(layer "B.CrtYd")
		)
		(fp_rect
			(start 0.9652 1.778)
			(end -0.9652 -1.778)
			(stroke
				(width 0)
				(type default)
			)
			(fill no)
			(layer "B.Fab")
		)
		(pad "1" smd rect
			(at 0 -0.9652 270)
			(size 1.397 1.143)
			(layers "B.Cu" "B.Mask" "B.Paste")
			(net "P0V9")
		)
		(pad "2" smd rect
			(at 0 0.9652 270)
			(size 1.397 1.143)
			(layers "B.Cu" "B.Mask" "B.Paste")
			(net "GB_VDDA")
		)
	)
	(footprint ""
		(layer "B.Cu")
		(at 117.348 -66.3575)
		(property "Reference" "C158"
			(at 0 0 0)
			(layer "B.SilkS")
			(hide yes)
			(effects
				(font
					(size 1.27 1.27)
				)
				(justify mirror)
			)
		)
		(property "Value" "SCD1U6D3V1KX-GP"
			(at 2.8321 -1.7399 0)
			(unlocked yes)
			(layer "B.Fab")
			(hide yes)
			(effects
				(font
					(size 1.016 1.016)
					(thickness 0.1524)
				)
				(justify mirror)
			)
		)
		(property "Device Type" "C0201H13"
			(at 2.8321 -3.2639 0)
			(unlocked yes)
			(layer "B.Fab")
			(hide yes)
			(effects
				(font
					(size 1.016 1.016)
					(thickness 0.1524)
				)
				(justify mirror)
			)
		)
		(duplicate_pad_numbers_are_jumpers no)
		(fp_rect
			(start 0.2794 0.6477)
			(end -0.2794 -0.6477)
			(stroke
				(width 0)
				(type default)
			)
			(fill no)
			(layer "B.CrtYd")
		)
		(fp_rect
			(start 0.2794 0.6477)
			(end -0.2794 -0.6477)
			(stroke
				(width 0)
				(type default)
			)
			(fill no)
			(layer "B.Fab")
		)
		(pad "1" smd custom
			(at 0 -0.2794 180)
			(size 0.0762 0.0762)
			(layers "B.Cu" "B.Mask" "B.Paste")
			(net "P0V9")
			(options
				(clearance outline)
				(anchor circle)
			)
			(primitives
				(gr_poly
					(pts
						(arc
							(start 0.1524 0.127)
							(mid 0.137521 0.162921)
							(end 0.1016 0.1778)
						)
						(arc
							(start -0.1016 0.1778)
							(mid -0.137521 0.162921)
							(end -0.1524 0.127)
						)
						(arc
							(start -0.1524 -0.127)
							(mid -0.137521 -0.162921)
							(end -0.1016 -0.1778)
						)
						(arc
							(start 0.1016 -0.1778)
							(mid 0.137521 -0.162921)
							(end 0.1524 -0.127)
						)
					)
					(width 0)
					(fill yes)
				)
			)
		)
		(pad "2" smd custom
			(at 0 0.2794 180)
			(size 0.0762 0.0762)
			(layers "B.Cu" "B.Mask" "B.Paste")
			(net "GND")
			(options
				(clearance outline)
				(anchor circle)
			)
			(primitives
				(gr_poly
					(pts
						(arc
							(start 0.1524 0.127)
							(mid 0.137521 0.162921)
							(end 0.1016 0.1778)
						)
						(arc
							(start -0.1016 0.1778)
							(mid -0.137521 0.162921)
							(end -0.1524 0.127)
						)
						(arc
							(start -0.1524 -0.127)
							(mid -0.137521 -0.162921)
							(end -0.1016 -0.1778)
						)
						(arc
							(start 0.1016 -0.1778)
							(mid 0.137521 -0.162921)
							(end 0.1524 -0.127)
						)
					)
					(width 0)
					(fill yes)
				)
			)
		)
	)
	(footprint ""
		(layer "B.Cu")
		(at 186.383168 -44.545504 -90)
		(property "Reference" "TP109"
			(at 0 0 90)
			(layer "B.SilkS")
			(hide yes)
			(effects
				(font
					(size 1.27 1.27)
				)
				(justify mirror)
			)
		)
		(property "Value" "TPAD28-2-GP"
			(at 0.0127 -1.6637 270)
			(unlocked yes)
			(layer "B.Fab")
			(hide yes)
			(effects
				(font
					(size 1.016 1.016)
					(thickness 0.1524)
				)
				(justify mirror)
			)
		)
		(property "Device Type" "TPAD28"
			(at 0.0127 -3.1877 270)
			(unlocked yes)
			(layer "B.Fab")
			(hide yes)
			(effects
				(font
					(size 1.016 1.016)
					(thickness 0.1524)
				)
				(justify mirror)
			)
		)
		(duplicate_pad_numbers_are_jumpers no)
		(fp_poly
			(pts
				(arc
					(start 0 -0.3556)
					(mid 0 0.3556)
					(end 0 -0.3556)
				)
			)
			(stroke
				(width 0)
				(type default)
			)
			(fill no)
			(layer "B.CrtYd")
		)
		(fp_poly
			(pts
				(arc
					(start 0 -0.6096)
					(mid 0 0.6096)
					(end 0 -0.6096)
				)
			)
			(stroke
				(width 0)
				(type default)
			)
			(fill no)
			(layer "B.Fab")
		)
		(pad "1" smd circle
			(at 0 0 90)
			(size 0.7112 0.7112)
			(layers "B.Cu" "B.Mask" "B.Paste")
			(net "XM_ADDR_24")
		)
	)
	(footprint ""
		(layer "B.Cu")
		(at 108.5342 -65.5066 -90)
		(property "Reference" "C126"
			(at 0 0 90)
			(layer "B.SilkS")
			(hide yes)
			(effects
				(font
					(size 1.27 1.27)
				)
				(justify mirror)
			)
		)
		(property "Value" "SC1KP25V1KX-GP"
			(at 2.8321 -1.7399 270)
			(unlocked yes)
			(layer "B.Fab")
			(hide yes)
			(effects
				(font
					(size 1.016 1.016)
					(thickness 0.1524)
				)
				(justify mirror)
			)
		)
		(property "Device Type" "C0201H13"
			(at 2.8321 -3.2639 270)
			(unlocked yes)
			(layer "B.Fab")
			(hide yes)
			(effects
				(font
					(size 1.016 1.016)
					(thickness 0.1524)
				)
				(justify mirror)
			)
		)
		(duplicate_pad_numbers_are_jumpers no)
		(fp_rect
			(start 0.2794 0.6477)
			(end -0.2794 -0.6477)
			(stroke
				(width 0)
				(type default)
			)
			(fill no)
			(layer "B.CrtYd")
		)
		(fp_rect
			(start 0.2794 0.6477)
			(end -0.2794 -0.6477)
			(stroke
				(width 0)
				(type default)
			)
			(fill no)
			(layer "B.Fab")
		)
		(pad "1" smd custom
			(at 0 -0.2794 90)
			(size 0.0762 0.0762)
			(layers "B.Cu" "B.Mask" "B.Paste")
			(net "P1V8_E")
			(options
				(clearance outline)
				(anchor circle)
			)
			(primitives
				(gr_poly
					(pts
						(arc
							(start 0.1524 0.127)
							(mid 0.137521 0.162921)
							(end 0.1016 0.1778)
						)
						(arc
							(start -0.1016 0.1778)
							(mid -0.137521 0.162921)
							(end -0.1524 0.127)
						)
						(arc
							(start -0.1524 -0.127)
							(mid -0.137521 -0.162921)
							(end -0.1016 -0.1778)
						)
						(arc
							(start 0.1016 -0.1778)
							(mid 0.137521 -0.162921)
							(end 0.1524 -0.127)
						)
					)
					(width 0)
					(fill yes)
				)
			)
		)
		(pad "2" smd custom
			(at 0 0.2794 90)
			(size 0.0762 0.0762)
			(layers "B.Cu" "B.Mask" "B.Paste")
			(net "GND")
			(options
				(clearance outline)
				(anchor circle)
			)
			(primitives
				(gr_poly
					(pts
						(arc
							(start 0.1524 0.127)
							(mid 0.137521 0.162921)
							(end 0.1016 0.1778)
						)
						(arc
							(start -0.1016 0.1778)
							(mid -0.137521 0.162921)
							(end -0.1524 0.127)
						)
						(arc
							(start -0.1524 -0.127)
							(mid -0.137521 -0.162921)
							(end -0.1016 -0.1778)
						)
						(arc
							(start 0.1016 -0.1778)
							(mid 0.137521 -0.162921)
							(end 0.1524 -0.127)
						)
					)
					(width 0)
					(fill yes)
				)
			)
		)
	)
	(footprint ""
		(layer "B.Cu")
		(at 100.2538 -44.2214 180)
		(property "Reference" "C83"
			(at 0 0 0)
			(layer "B.SilkS")
			(hide yes)
			(effects
				(font
					(size 1.27 1.27)
				)
				(justify mirror)
			)
		)
		(property "Value" "SCD01U16V1KX-GP"
			(at 2.8321 -1.7399 180)
			(unlocked yes)
			(layer "B.Fab")
			(hide yes)
			(effects
				(font
					(size 1.016 1.016)
					(thickness 0.1524)
				)
				(justify mirror)
			)
		)
		(property "Device Type" "C0201H13"
			(at 2.8321 -3.2639 180)
			(unlocked yes)
			(layer "B.Fab")
			(hide yes)
			(effects
				(font
					(size 1.016 1.016)
					(thickness 0.1524)
				)
				(justify mirror)
			)
		)
		(duplicate_pad_numbers_are_jumpers no)
		(fp_rect
			(start 0.2794 0.6477)
			(end -0.2794 -0.6477)
			(stroke
				(width 0)
				(type default)
			)
			(fill no)
			(layer "B.CrtYd")
		)
		(fp_rect
			(start 0.2794 0.6477)
			(end -0.2794 -0.6477)
			(stroke
				(width 0)
				(type default)
			)
			(fill no)
			(layer "B.Fab")
		)
		(pad "1" smd custom
			(at 0 -0.2794)
			(size 0.0762 0.0762)
			(layers "B.Cu" "B.Mask" "B.Paste")
			(net "PHY_DPB_TO_SCC_18_DP")
			(options
				(clearance outline)
				(anchor circle)
			)
			(primitives
				(gr_poly
					(pts
						(arc
							(start 0.1524 0.127)
							(mid 0.137521 0.162921)
							(end 0.1016 0.1778)
						)
						(arc
							(start -0.1016 0.1778)
							(mid -0.137521 0.162921)
							(end -0.1524 0.127)
						)
						(arc
							(start -0.1524 -0.127)
							(mid -0.137521 -0.162921)
							(end -0.1016 -0.1778)
						)
						(arc
							(start 0.1016 -0.1778)
							(mid 0.137521 -0.162921)
							(end 0.1524 -0.127)
						)
					)
					(width 0)
					(fill yes)
				)
			)
		)
		(pad "2" smd custom
			(at 0 0.2794)
			(size 0.0762 0.0762)
			(layers "B.Cu" "B.Mask" "B.Paste")
			(net "PHY_DPB_TO_SCC_C_18_DP")
			(options
				(clearance outline)
				(anchor circle)
			)
			(primitives
				(gr_poly
					(pts
						(arc
							(start 0.1524 0.127)
							(mid 0.137521 0.162921)
							(end 0.1016 0.1778)
						)
						(arc
							(start -0.1016 0.1778)
							(mid -0.137521 0.162921)
							(end -0.1524 0.127)
						)
						(arc
							(start -0.1524 -0.127)
							(mid -0.137521 -0.162921)
							(end -0.1016 -0.1778)
						)
						(arc
							(start 0.1016 -0.1778)
							(mid 0.137521 -0.162921)
							(end 0.1524 -0.127)
						)
					)
					(width 0)
					(fill yes)
				)
			)
		)
	)
	(footprint ""
		(layer "B.Cu")
		(at 198.511414 -46.439074 -90)
		(property "Reference" "R205"
			(at 0 0 90)
			(layer "B.SilkS")
			(hide yes)
			(effects
				(font
					(size 1.27 1.27)
				)
				(justify mirror)
			)
		)
		(property "Value" "0R2J-2-GP"
			(at -0.064008 -3.993896 270)
			(unlocked yes)
			(layer "B.Fab")
			(hide yes)
			(effects
				(font
					(size 1.016 1.016)
					(thickness 0.1524)
				)
				(justify mirror)
			)
		)
		(property "Device Type" "R402H16"
			(at -0.064008 -5.517896 270)
			(unlocked yes)
			(layer "B.Fab")
			(hide yes)
			(effects
				(font
					(size 1.016 1.016)
					(thickness 0.1524)
				)
				(justify mirror)
			)
		)
		(duplicate_pad_numbers_are_jumpers no)
		(fp_line
			(start -0.508 -0.9398)
			(end 0.508 -0.9398)
			(stroke
				(width 0.1524)
				(type default)
			)
			(layer "B.SilkS")
		)
		(fp_line
			(start 0.508 -0.9398)
			(end 0.508 0.9398)
			(stroke
				(width 0.1524)
				(type default)
			)
			(layer "B.SilkS")
		)
		(fp_rect
			(start 0.508 0.9398)
			(end -0.508 -0.9398)
			(stroke
				(width 0)
				(type default)
			)
			(fill no)
			(layer "B.CrtYd")
		)
		(fp_rect
			(start 0.508 0.9398)
			(end -0.508 -0.9398)
			(stroke
				(width 0)
				(type default)
			)
			(fill no)
			(layer "B.Fab")
		)
		(pad "1" smd custom
			(at 0 -0.4445 90)
			(size 0.1397 0.1397)
			(layers "B.Cu" "B.Mask" "B.Paste")
			(net "IOC_EEPROM_SDA")
			(options
				(clearance outline)
				(anchor circle)
			)
			(primitives
				(gr_poly
					(pts
						(arc
							(start -0.1778 0.2794)
							(mid -0.249642 0.249642)
							(end -0.2794 0.1778)
						)
						(arc
							(start -0.2794 -0.1778)
							(mid -0.249642 -0.249642)
							(end -0.1778 -0.2794)
						)
						(arc
							(start 0.1778 -0.2794)
							(mid 0.249642 -0.249642)
							(end 0.2794 -0.1778)
						)
						(arc
							(start 0.2794 0.1778)
							(mid 0.249642 0.249642)
							(end 0.1778 0.2794)
						)
					)
					(width 0)
					(fill yes)
				)
			)
		)
		(pad "2" smd custom
			(at 0 0.4445 90)
			(size 0.1397 0.1397)
			(layers "B.Cu" "B.Mask" "B.Paste")
			(net "SBL_SDA")
			(options
				(clearance outline)
				(anchor circle)
			)
			(primitives
				(gr_poly
					(pts
						(arc
							(start -0.1778 0.2794)
							(mid -0.249642 0.249642)
							(end -0.2794 0.1778)
						)
						(arc
							(start -0.2794 -0.1778)
							(mid -0.249642 -0.249642)
							(end -0.1778 -0.2794)
						)
						(arc
							(start 0.1778 -0.2794)
							(mid 0.249642 -0.249642)
							(end 0.2794 -0.1778)
						)
						(arc
							(start 0.2794 0.1778)
							(mid 0.249642 0.249642)
							(end 0.1778 0.2794)
						)
					)
					(width 0)
					(fill yes)
				)
			)
		)
	)
	(footprint ""
		(layer "B.Cu")
		(at 165.670992 -11.70813)
		(property "Reference" "C509"
			(at 0 0 0)
			(layer "B.SilkS")
			(hide yes)
			(effects
				(font
					(size 1.27 1.27)
				)
				(justify mirror)
			)
		)
		(property "Value" "SCD1U16V2KX-3GP"
			(at -1.1811 -2.7051 0)
			(unlocked yes)
			(layer "B.Fab")
			(hide yes)
			(effects
				(font
					(size 1.016 1.016)
					(thickness 0.1524)
				)
				(justify mirror)
			)
		)
		(property "Device Type" "C402H22"
			(at -1.1811 -4.2291 0)
			(unlocked yes)
			(layer "B.Fab")
			(hide yes)
			(effects
				(font
					(size 1.016 1.016)
					(thickness 0.1524)
				)
				(justify mirror)
			)
		)
		(duplicate_pad_numbers_are_jumpers no)
		(fp_rect
			(start 0.4318 0.9525)
			(end -0.4318 -0.9525)
			(stroke
				(width 0)
				(type default)
			)
			(fill no)
			(layer "B.CrtYd")
		)
		(fp_rect
			(start 0.4318 0.9525)
			(end -0.4318 -0.9525)
			(stroke
				(width 0)
				(type default)
			)
			(fill no)
			(layer "B.Fab")
		)
		(pad "1" smd custom
			(at 0 -0.4445 180)
			(size 0.1524 0.1524)
			(layers "B.Cu" "B.Mask" "B.Paste")
			(net "P3V3")
			(options
				(clearance outline)
				(anchor circle)
			)
			(primitives
				(gr_poly
					(pts
						(arc
							(start 0.3048 0.2032)
							(mid 0.275042 0.275042)
							(end 0.2032 0.3048)
						)
						(arc
							(start -0.2032 0.3048)
							(mid -0.275042 0.275042)
							(end -0.3048 0.2032)
						)
						(arc
							(start -0.3048 -0.2032)
							(mid -0.275042 -0.275042)
							(end -0.2032 -0.3048)
						)
						(arc
							(start 0.2032 -0.3048)
							(mid 0.275042 -0.275042)
							(end 0.3048 -0.2032)
						)
					)
					(width 0)
					(fill yes)
				)
			)
		)
		(pad "2" smd custom
			(at 0 0.4445 180)
			(size 0.1524 0.1524)
			(layers "B.Cu" "B.Mask" "B.Paste")
			(net "GND")
			(options
				(clearance outline)
				(anchor circle)
			)
			(primitives
				(gr_poly
					(pts
						(arc
							(start 0.3048 0.2032)
							(mid 0.275042 0.275042)
							(end 0.2032 0.3048)
						)
						(arc
							(start -0.2032 0.3048)
							(mid -0.275042 0.275042)
							(end -0.3048 0.2032)
						)
						(arc
							(start -0.3048 -0.2032)
							(mid -0.275042 -0.275042)
							(end -0.2032 -0.3048)
						)
						(arc
							(start 0.2032 -0.3048)
							(mid 0.275042 -0.275042)
							(end 0.3048 -0.2032)
						)
					)
					(width 0)
					(fill yes)
				)
			)
		)
	)
	(footprint ""
		(layer "B.Cu")
		(at 165.608 -66.7766)
		(property "Reference" "R277"
			(at 0 0 0)
			(layer "B.SilkS")
			(hide yes)
			(effects
				(font
					(size 1.27 1.27)
				)
				(justify mirror)
			)
		)
		(property "Value" "10R2F-L-GP"
			(at -0.064008 -3.993896 0)
			(unlocked yes)
			(layer "B.Fab")
			(hide yes)
			(effects
				(font
					(size 1.016 1.016)
					(thickness 0.1524)
				)
				(justify mirror)
			)
		)
		(property "Device Type" "R402H14"
			(at -0.064008 -5.517896 0)
			(unlocked yes)
			(layer "B.Fab")
			(hide yes)
			(effects
				(font
					(size 1.016 1.016)
					(thickness 0.1524)
				)
				(justify mirror)
			)
		)
		(duplicate_pad_numbers_are_jumpers no)
		(fp_line
			(start -0.508 -0.9398)
			(end 0.508 -0.9398)
			(stroke
				(width 0.1524)
				(type default)
			)
			(layer "B.SilkS")
		)
		(fp_line
			(start 0.508 -0.9398)
			(end 0.508 0.9398)
			(stroke
				(width 0.1524)
				(type default)
			)
			(layer "B.SilkS")
		)
		(fp_rect
			(start 0.508 0.9398)
			(end -0.508 -0.9398)
			(stroke
				(width 0)
				(type default)
			)
			(fill no)
			(layer "B.CrtYd")
		)
		(fp_rect
			(start 0.508 0.9398)
			(end -0.508 -0.9398)
			(stroke
				(width 0)
				(type default)
			)
			(fill no)
			(layer "B.Fab")
		)
		(pad "1" smd custom
			(at 0 -0.4445 180)
			(size 0.1397 0.1397)
			(layers "B.Cu" "B.Mask" "B.Paste")
			(net "P1V8_C")
			(options
				(clearance outline)
				(anchor circle)
			)
			(primitives
				(gr_poly
					(pts
						(arc
							(start -0.1778 0.2794)
							(mid -0.249642 0.249642)
							(end -0.2794 0.1778)
						)
						(arc
							(start -0.2794 -0.1778)
							(mid -0.249642 -0.249642)
							(end -0.1778 -0.2794)
						)
						(arc
							(start 0.1778 -0.2794)
							(mid 0.249642 -0.249642)
							(end 0.2794 -0.1778)
						)
						(arc
							(start 0.2794 0.1778)
							(mid 0.249642 0.249642)
							(end 0.1778 0.2794)
						)
					)
					(width 0)
					(fill yes)
				)
			)
		)
		(pad "2" smd custom
			(at 0 0.4445 180)
			(size 0.1397 0.1397)
			(layers "B.Cu" "B.Mask" "B.Paste")
			(net "HM40ADC_VDDA")
			(options
				(clearance outline)
				(anchor circle)
			)
			(primitives
				(gr_poly
					(pts
						(arc
							(start -0.1778 0.2794)
							(mid -0.249642 0.249642)
							(end -0.2794 0.1778)
						)
						(arc
							(start -0.2794 -0.1778)
							(mid -0.249642 -0.249642)
							(end -0.1778 -0.2794)
						)
						(arc
							(start 0.1778 -0.2794)
							(mid 0.249642 -0.249642)
							(end 0.2794 -0.1778)
						)
						(arc
							(start 0.2794 0.1778)
							(mid 0.249642 0.249642)
							(end 0.1778 0.2794)
						)
					)
					(width 0)
					(fill yes)
				)
			)
		)
	)
	(footprint ""
		(layer "B.Cu")
		(at 164.084 -47.2186)
		(property "Reference" "TP83"
			(at 0 0 0)
			(layer "B.SilkS")
			(hide yes)
			(effects
				(font
					(size 1.27 1.27)
				)
				(justify mirror)
			)
		)
		(property "Value" "TPAD28-2-GP"
			(at 0.0127 -1.6637 0)
			(unlocked yes)
			(layer "B.Fab")
			(hide yes)
			(effects
				(font
					(size 1.016 1.016)
					(thickness 0.1524)
				)
				(justify mirror)
			)
		)
		(property "Device Type" "TPAD28"
			(at 0.0127 -3.1877 0)
			(unlocked yes)
			(layer "B.Fab")
			(hide yes)
			(effects
				(font
					(size 1.016 1.016)
					(thickness 0.1524)
				)
				(justify mirror)
			)
		)
		(duplicate_pad_numbers_are_jumpers no)
		(fp_poly
			(pts
				(arc
					(start 0.3556 0)
					(mid -0.3556 0)
					(end 0.3556 0)
				)
			)
			(stroke
				(width 0)
				(type default)
			)
			(fill no)
			(layer "B.CrtYd")
		)
		(fp_poly
			(pts
				(arc
					(start 0.6096 0)
					(mid -0.6096 0)
					(end 0.6096 0)
				)
			)
			(stroke
				(width 0)
				(type default)
			)
			(fill no)
			(layer "B.Fab")
		)
		(pad "1" smd circle
			(at 0 0 180)
			(size 0.7112 0.7112)
			(layers "B.Cu" "B.Mask" "B.Paste")
			(net "SIO_DOUT_0")
		)
	)
	(footprint ""
		(layer "B.Cu")
		(at 101.7778 -44.2214 180)
		(property "Reference" "C81"
			(at 0 0 0)
			(layer "B.SilkS")
			(hide yes)
			(effects
				(font
					(size 1.27 1.27)
				)
				(justify mirror)
			)
		)
		(property "Value" "SCD01U16V1KX-GP"
			(at 2.8321 -1.7399 180)
			(unlocked yes)
			(layer "B.Fab")
			(hide yes)
			(effects
				(font
					(size 1.016 1.016)
					(thickness 0.1524)
				)
				(justify mirror)
			)
		)
		(property "Device Type" "C0201H13"
			(at 2.8321 -3.2639 180)
			(unlocked yes)
			(layer "B.Fab")
			(hide yes)
			(effects
				(font
					(size 1.016 1.016)
					(thickness 0.1524)
				)
				(justify mirror)
			)
		)
		(duplicate_pad_numbers_are_jumpers no)
		(fp_rect
			(start 0.2794 0.6477)
			(end -0.2794 -0.6477)
			(stroke
				(width 0)
				(type default)
			)
			(fill no)
			(layer "B.CrtYd")
		)
		(fp_rect
			(start 0.2794 0.6477)
			(end -0.2794 -0.6477)
			(stroke
				(width 0)
				(type default)
			)
			(fill no)
			(layer "B.Fab")
		)
		(pad "1" smd custom
			(at 0 -0.2794)
			(size 0.0762 0.0762)
			(layers "B.Cu" "B.Mask" "B.Paste")
			(net "PHY_DPB_TO_SCC_19_DP")
			(options
				(clearance outline)
				(anchor circle)
			)
			(primitives
				(gr_poly
					(pts
						(arc
							(start 0.1524 0.127)
							(mid 0.137521 0.162921)
							(end 0.1016 0.1778)
						)
						(arc
							(start -0.1016 0.1778)
							(mid -0.137521 0.162921)
							(end -0.1524 0.127)
						)
						(arc
							(start -0.1524 -0.127)
							(mid -0.137521 -0.162921)
							(end -0.1016 -0.1778)
						)
						(arc
							(start 0.1016 -0.1778)
							(mid 0.137521 -0.162921)
							(end 0.1524 -0.127)
						)
					)
					(width 0)
					(fill yes)
				)
			)
		)
		(pad "2" smd custom
			(at 0 0.2794)
			(size 0.0762 0.0762)
			(layers "B.Cu" "B.Mask" "B.Paste")
			(net "PHY_DPB_TO_SCC_C_19_DP")
			(options
				(clearance outline)
				(anchor circle)
			)
			(primitives
				(gr_poly
					(pts
						(arc
							(start 0.1524 0.127)
							(mid 0.137521 0.162921)
							(end 0.1016 0.1778)
						)
						(arc
							(start -0.1016 0.1778)
							(mid -0.137521 0.162921)
							(end -0.1524 0.127)
						)
						(arc
							(start -0.1524 -0.127)
							(mid -0.137521 -0.162921)
							(end -0.1016 -0.1778)
						)
						(arc
							(start 0.1016 -0.1778)
							(mid 0.137521 -0.162921)
							(end 0.1524 -0.127)
						)
					)
					(width 0)
					(fill yes)
				)
			)
		)
	)
	(footprint ""
		(layer "B.Cu")
		(at 92.123006 -74.762614 180)
		(property "Reference" "C204"
			(at 0 0 0)
			(layer "B.SilkS")
			(hide yes)
			(effects
				(font
					(size 1.27 1.27)
				)
				(justify mirror)
			)
		)
		(property "Value" "SC22U6D3V3MX-9-GP-U"
			(at 0 -2.8194 180)
			(unlocked yes)
			(layer "B.Fab")
			(hide yes)
			(effects
				(font
					(size 1.016 1.016)
					(thickness 0.1524)
				)
				(justify mirror)
			)
		)
		(property "Device Type" "C603H40"
			(at 0 -4.3434 180)
			(unlocked yes)
			(layer "B.Fab")
			(hide yes)
			(effects
				(font
					(size 1.016 1.016)
					(thickness 0.1524)
				)
				(justify mirror)
			)
		)
		(duplicate_pad_numbers_are_jumpers no)
		(fp_line
			(start -0.508 0)
			(end 0.508 0)
			(stroke
				(width 0.2032)
				(type default)
			)
			(layer "B.SilkS")
		)
		(fp_rect
			(start 0.5842 1.3335)
			(end -0.5842 -1.3335)
			(stroke
				(width 0)
				(type default)
			)
			(fill no)
			(layer "B.CrtYd")
		)
		(fp_rect
			(start 0.5842 1.3335)
			(end -0.5842 -1.3335)
			(stroke
				(width 0)
				(type default)
			)
			(fill no)
			(layer "B.Fab")
		)
		(pad "1" smd custom
			(at 0 -0.762)
			(size 0.2159 0.2159)
			(layers "B.Cu" "B.Mask" "B.Paste")
			(net "XTAL_VDDA09")
			(options
				(clearance outline)
				(anchor circle)
			)
			(primitives
				(gr_poly
					(pts
						(arc
							(start -0.3302 0.4318)
							(mid -0.402042 0.402042)
							(end -0.4318 0.3302)
						)
						(arc
							(start -0.4318 -0.3302)
							(mid -0.402042 -0.402042)
							(end -0.3302 -0.4318)
						)
						(arc
							(start 0.3302 -0.4318)
							(mid 0.402042 -0.402042)
							(end 0.4318 -0.3302)
						)
						(arc
							(start 0.4318 0.3302)
							(mid 0.402042 0.402042)
							(end 0.3302 0.4318)
						)
					)
					(width 0)
					(fill yes)
				)
			)
		)
		(pad "2" smd custom
			(at 0 0.762)
			(size 0.2159 0.2159)
			(layers "B.Cu" "B.Mask" "B.Paste")
			(net "GND")
			(options
				(clearance outline)
				(anchor circle)
			)
			(primitives
				(gr_poly
					(pts
						(arc
							(start -0.3302 0.4318)
							(mid -0.402042 0.402042)
							(end -0.4318 0.3302)
						)
						(arc
							(start -0.4318 -0.3302)
							(mid -0.402042 -0.402042)
							(end -0.3302 -0.4318)
						)
						(arc
							(start 0.3302 -0.4318)
							(mid 0.402042 -0.402042)
							(end 0.4318 -0.3302)
						)
						(arc
							(start 0.4318 0.3302)
							(mid 0.402042 0.402042)
							(end 0.3302 0.4318)
						)
					)
					(width 0)
					(fill yes)
				)
			)
		)
	)
	(footprint ""
		(layer "B.Cu")
		(at 134.846822 -56.379618 180)
		(property "Reference" "C26"
			(at 0 0 0)
			(layer "B.SilkS")
			(hide yes)
			(effects
				(font
					(size 1.27 1.27)
				)
				(justify mirror)
			)
		)
		(property "Value" "SCD01U16V1KX-GP"
			(at 2.8321 -1.7399 180)
			(unlocked yes)
			(layer "B.Fab")
			(hide yes)
			(effects
				(font
					(size 1.016 1.016)
					(thickness 0.1524)
				)
				(justify mirror)
			)
		)
		(property "Device Type" "C0201H13"
			(at 2.8321 -3.2639 180)
			(unlocked yes)
			(layer "B.Fab")
			(hide yes)
			(effects
				(font
					(size 1.016 1.016)
					(thickness 0.1524)
				)
				(justify mirror)
			)
		)
		(duplicate_pad_numbers_are_jumpers no)
		(fp_rect
			(start 0.2794 0.6477)
			(end -0.2794 -0.6477)
			(stroke
				(width 0)
				(type default)
			)
			(fill no)
			(layer "B.CrtYd")
		)
		(fp_rect
			(start 0.2794 0.6477)
			(end -0.2794 -0.6477)
			(stroke
				(width 0)
				(type default)
			)
			(fill no)
			(layer "B.Fab")
		)
		(pad "1" smd custom
			(at 0 -0.2794)
			(size 0.0762 0.0762)
			(layers "B.Cu" "B.Mask" "B.Paste")
			(net "PHY_DPB_TO_SCC_31_DN")
			(options
				(clearance outline)
				(anchor circle)
			)
			(primitives
				(gr_poly
					(pts
						(arc
							(start 0.1524 0.127)
							(mid 0.137521 0.162921)
							(end 0.1016 0.1778)
						)
						(arc
							(start -0.1016 0.1778)
							(mid -0.137521 0.162921)
							(end -0.1524 0.127)
						)
						(arc
							(start -0.1524 -0.127)
							(mid -0.137521 -0.162921)
							(end -0.1016 -0.1778)
						)
						(arc
							(start 0.1016 -0.1778)
							(mid 0.137521 -0.162921)
							(end 0.1524 -0.127)
						)
					)
					(width 0)
					(fill yes)
				)
			)
		)
		(pad "2" smd custom
			(at 0 0.2794)
			(size 0.0762 0.0762)
			(layers "B.Cu" "B.Mask" "B.Paste")
			(net "PHY_DPB_TO_SCC_C_31_DN")
			(options
				(clearance outline)
				(anchor circle)
			)
			(primitives
				(gr_poly
					(pts
						(arc
							(start 0.1524 0.127)
							(mid 0.137521 0.162921)
							(end 0.1016 0.1778)
						)
						(arc
							(start -0.1016 0.1778)
							(mid -0.137521 0.162921)
							(end -0.1524 0.127)
						)
						(arc
							(start -0.1524 -0.127)
							(mid -0.137521 -0.162921)
							(end -0.1016 -0.1778)
						)
						(arc
							(start 0.1016 -0.1778)
							(mid 0.137521 -0.162921)
							(end 0.1524 -0.127)
						)
					)
					(width 0)
					(fill yes)
				)
			)
		)
	)
	(footprint ""
		(layer "B.Cu")
		(at 181.6354 -27.2542 90)
		(property "Reference" "TP56"
			(at 0 0 90)
			(layer "B.SilkS")
			(hide yes)
			(effects
				(font
					(size 1.27 1.27)
				)
				(justify mirror)
			)
		)
		(property "Value" "TPAD28-2-GP"
			(at 0.0127 -1.6637 90)
			(unlocked yes)
			(layer "B.Fab")
			(hide yes)
			(effects
				(font
					(size 1.016 1.016)
					(thickness 0.1524)
				)
				(justify mirror)
			)
		)
		(property "Device Type" "TPAD28"
			(at 0.0127 -3.1877 90)
			(unlocked yes)
			(layer "B.Fab")
			(hide yes)
			(effects
				(font
					(size 1.016 1.016)
					(thickness 0.1524)
				)
				(justify mirror)
			)
		)
		(duplicate_pad_numbers_are_jumpers no)
		(fp_poly
			(pts
				(arc
					(start 0 0.3556)
					(mid 0 -0.3556)
					(end 0 0.3556)
				)
			)
			(stroke
				(width 0)
				(type default)
			)
			(fill no)
			(layer "B.CrtYd")
		)
		(fp_poly
			(pts
				(arc
					(start 0 0.6096)
					(mid 0 -0.6096)
					(end 0 0.6096)
				)
			)
			(stroke
				(width 0)
				(type default)
			)
			(fill no)
			(layer "B.Fab")
		)
		(pad "1" smd circle
			(at 0 0 270)
			(size 0.7112 0.7112)
			(layers "B.Cu" "B.Mask" "B.Paste")
			(net "IOC_GPIO_3")
		)
	)
	(footprint ""
		(layer "B.Cu")
		(at 113.411 -71.9074)
		(property "Reference" "C142"
			(at 0 0 0)
			(layer "B.SilkS")
			(hide yes)
			(effects
				(font
					(size 1.27 1.27)
				)
				(justify mirror)
			)
		)
		(property "Value" "SCD1U6D3V1KX-GP"
			(at 2.8321 -1.7399 0)
			(unlocked yes)
			(layer "B.Fab")
			(hide yes)
			(effects
				(font
					(size 1.016 1.016)
					(thickness 0.1524)
				)
				(justify mirror)
			)
		)
		(property "Device Type" "C0201H13"
			(at 2.8321 -3.2639 0)
			(unlocked yes)
			(layer "B.Fab")
			(hide yes)
			(effects
				(font
					(size 1.016 1.016)
					(thickness 0.1524)
				)
				(justify mirror)
			)
		)
		(duplicate_pad_numbers_are_jumpers no)
		(fp_rect
			(start 0.2794 0.6477)
			(end -0.2794 -0.6477)
			(stroke
				(width 0)
				(type default)
			)
			(fill no)
			(layer "B.CrtYd")
		)
		(fp_rect
			(start 0.2794 0.6477)
			(end -0.2794 -0.6477)
			(stroke
				(width 0)
				(type default)
			)
			(fill no)
			(layer "B.Fab")
		)
		(pad "1" smd custom
			(at 0 -0.2794 180)
			(size 0.0762 0.0762)
			(layers "B.Cu" "B.Mask" "B.Paste")
			(net "P1V8_E")
			(options
				(clearance outline)
				(anchor circle)
			)
			(primitives
				(gr_poly
					(pts
						(arc
							(start 0.1524 0.127)
							(mid 0.137521 0.162921)
							(end 0.1016 0.1778)
						)
						(arc
							(start -0.1016 0.1778)
							(mid -0.137521 0.162921)
							(end -0.1524 0.127)
						)
						(arc
							(start -0.1524 -0.127)
							(mid -0.137521 -0.162921)
							(end -0.1016 -0.1778)
						)
						(arc
							(start 0.1016 -0.1778)
							(mid 0.137521 -0.162921)
							(end 0.1524 -0.127)
						)
					)
					(width 0)
					(fill yes)
				)
			)
		)
		(pad "2" smd custom
			(at 0 0.2794 180)
			(size 0.0762 0.0762)
			(layers "B.Cu" "B.Mask" "B.Paste")
			(net "GND")
			(options
				(clearance outline)
				(anchor circle)
			)
			(primitives
				(gr_poly
					(pts
						(arc
							(start 0.1524 0.127)
							(mid 0.137521 0.162921)
							(end 0.1016 0.1778)
						)
						(arc
							(start -0.1016 0.1778)
							(mid -0.137521 0.162921)
							(end -0.1524 0.127)
						)
						(arc
							(start -0.1524 -0.127)
							(mid -0.137521 -0.162921)
							(end -0.1016 -0.1778)
						)
						(arc
							(start 0.1016 -0.1778)
							(mid 0.137521 -0.162921)
							(end 0.1524 -0.127)
						)
					)
					(width 0)
					(fill yes)
				)
			)
		)
	)
	(footprint ""
		(layer "B.Cu")
		(at 165.197282 -28.269184 -90)
		(property "Reference" "C392"
			(at 0 0 90)
			(layer "B.SilkS")
			(hide yes)
			(effects
				(font
					(size 1.27 1.27)
				)
				(justify mirror)
			)
		)
		(property "Value" "SCD1U6D3V1KX-GP"
			(at 2.8321 -1.7399 270)
			(unlocked yes)
			(layer "B.Fab")
			(hide yes)
			(effects
				(font
					(size 1.016 1.016)
					(thickness 0.1524)
				)
				(justify mirror)
			)
		)
		(property "Device Type" "C0201H13"
			(at 2.8321 -3.2639 270)
			(unlocked yes)
			(layer "B.Fab")
			(hide yes)
			(effects
				(font
					(size 1.016 1.016)
					(thickness 0.1524)
				)
				(justify mirror)
			)
		)
		(duplicate_pad_numbers_are_jumpers no)
		(fp_rect
			(start 0.2794 0.6477)
			(end -0.2794 -0.6477)
			(stroke
				(width 0)
				(type default)
			)
			(fill no)
			(layer "B.CrtYd")
		)
		(fp_rect
			(start 0.2794 0.6477)
			(end -0.2794 -0.6477)
			(stroke
				(width 0)
				(type default)
			)
			(fill no)
			(layer "B.Fab")
		)
		(pad "1" smd custom
			(at 0 -0.2794 90)
			(size 0.0762 0.0762)
			(layers "B.Cu" "B.Mask" "B.Paste")
			(net "PCE_AVDD")
			(options
				(clearance outline)
				(anchor circle)
			)
			(primitives
				(gr_poly
					(pts
						(arc
							(start 0.1524 0.127)
							(mid 0.137521 0.162921)
							(end 0.1016 0.1778)
						)
						(arc
							(start -0.1016 0.1778)
							(mid -0.137521 0.162921)
							(end -0.1524 0.127)
						)
						(arc
							(start -0.1524 -0.127)
							(mid -0.137521 -0.162921)
							(end -0.1016 -0.1778)
						)
						(arc
							(start 0.1016 -0.1778)
							(mid 0.137521 -0.162921)
							(end 0.1524 -0.127)
						)
					)
					(width 0)
					(fill yes)
				)
			)
		)
		(pad "2" smd custom
			(at 0 0.2794 90)
			(size 0.0762 0.0762)
			(layers "B.Cu" "B.Mask" "B.Paste")
			(net "GND")
			(options
				(clearance outline)
				(anchor circle)
			)
			(primitives
				(gr_poly
					(pts
						(arc
							(start 0.1524 0.127)
							(mid 0.137521 0.162921)
							(end 0.1016 0.1778)
						)
						(arc
							(start -0.1016 0.1778)
							(mid -0.137521 0.162921)
							(end -0.1524 0.127)
						)
						(arc
							(start -0.1524 -0.127)
							(mid -0.137521 -0.162921)
							(end -0.1016 -0.1778)
						)
						(arc
							(start 0.1016 -0.1778)
							(mid 0.137521 -0.162921)
							(end 0.1524 -0.127)
						)
					)
					(width 0)
					(fill yes)
				)
			)
		)
	)
	(footprint ""
		(layer "B.Cu")
		(at 183.3626 -41.7068 -90)
		(property "Reference" "C477"
			(at 0 0 90)
			(layer "B.SilkS")
			(hide yes)
			(effects
				(font
					(size 1.27 1.27)
				)
				(justify mirror)
			)
		)
		(property "Value" "SCD1U6D3V1KX-GP"
			(at 2.8321 -1.7399 270)
			(unlocked yes)
			(layer "B.Fab")
			(hide yes)
			(effects
				(font
					(size 1.016 1.016)
					(thickness 0.1524)
				)
				(justify mirror)
			)
		)
		(property "Device Type" "C0201H13"
			(at 2.8321 -3.2639 270)
			(unlocked yes)
			(layer "B.Fab")
			(hide yes)
			(effects
				(font
					(size 1.016 1.016)
					(thickness 0.1524)
				)
				(justify mirror)
			)
		)
		(duplicate_pad_numbers_are_jumpers no)
		(fp_rect
			(start 0.2794 0.6477)
			(end -0.2794 -0.6477)
			(stroke
				(width 0)
				(type default)
			)
			(fill no)
			(layer "B.CrtYd")
		)
		(fp_rect
			(start 0.2794 0.6477)
			(end -0.2794 -0.6477)
			(stroke
				(width 0)
				(type default)
			)
			(fill no)
			(layer "B.Fab")
		)
		(pad "1" smd custom
			(at 0 -0.2794 90)
			(size 0.0762 0.0762)
			(layers "B.Cu" "B.Mask" "B.Paste")
			(net "P1V8_C")
			(options
				(clearance outline)
				(anchor circle)
			)
			(primitives
				(gr_poly
					(pts
						(arc
							(start 0.1524 0.127)
							(mid 0.137521 0.162921)
							(end 0.1016 0.1778)
						)
						(arc
							(start -0.1016 0.1778)
							(mid -0.137521 0.162921)
							(end -0.1524 0.127)
						)
						(arc
							(start -0.1524 -0.127)
							(mid -0.137521 -0.162921)
							(end -0.1016 -0.1778)
						)
						(arc
							(start 0.1016 -0.1778)
							(mid 0.137521 -0.162921)
							(end 0.1524 -0.127)
						)
					)
					(width 0)
					(fill yes)
				)
			)
		)
		(pad "2" smd custom
			(at 0 0.2794 90)
			(size 0.0762 0.0762)
			(layers "B.Cu" "B.Mask" "B.Paste")
			(net "GND")
			(options
				(clearance outline)
				(anchor circle)
			)
			(primitives
				(gr_poly
					(pts
						(arc
							(start 0.1524 0.127)
							(mid 0.137521 0.162921)
							(end 0.1016 0.1778)
						)
						(arc
							(start -0.1016 0.1778)
							(mid -0.137521 0.162921)
							(end -0.1524 0.127)
						)
						(arc
							(start -0.1524 -0.127)
							(mid -0.137521 -0.162921)
							(end -0.1016 -0.1778)
						)
						(arc
							(start 0.1016 -0.1778)
							(mid 0.137521 -0.162921)
							(end 0.1524 -0.127)
						)
					)
					(width 0)
					(fill yes)
				)
			)
		)
	)
	(footprint ""
		(layer "B.Cu")
		(at 79.8322 -73.6854 -90)
		(property "Reference" "C117"
			(at 0 0 90)
			(layer "B.SilkS")
			(hide yes)
			(effects
				(font
					(size 1.27 1.27)
				)
				(justify mirror)
			)
		)
		(property "Value" "SCD1U16V2KX-3GP"
			(at -1.1811 -2.7051 270)
			(unlocked yes)
			(layer "B.Fab")
			(hide yes)
			(effects
				(font
					(size 1.016 1.016)
					(thickness 0.1524)
				)
				(justify mirror)
			)
		)
		(property "Device Type" "C402H22"
			(at -1.1811 -4.2291 270)
			(unlocked yes)
			(layer "B.Fab")
			(hide yes)
			(effects
				(font
					(size 1.016 1.016)
					(thickness 0.1524)
				)
				(justify mirror)
			)
		)
		(duplicate_pad_numbers_are_jumpers no)
		(fp_rect
			(start 0.4318 0.9525)
			(end -0.4318 -0.9525)
			(stroke
				(width 0)
				(type default)
			)
			(fill no)
			(layer "B.CrtYd")
		)
		(fp_rect
			(start 0.4318 0.9525)
			(end -0.4318 -0.9525)
			(stroke
				(width 0)
				(type default)
			)
			(fill no)
			(layer "B.Fab")
		)
		(pad "1" smd custom
			(at 0 -0.4445 90)
			(size 0.1524 0.1524)
			(layers "B.Cu" "B.Mask" "B.Paste")
			(net "P3V3")
			(options
				(clearance outline)
				(anchor circle)
			)
			(primitives
				(gr_poly
					(pts
						(arc
							(start 0.3048 0.2032)
							(mid 0.275042 0.275042)
							(end 0.2032 0.3048)
						)
						(arc
							(start -0.2032 0.3048)
							(mid -0.275042 0.275042)
							(end -0.3048 0.2032)
						)
						(arc
							(start -0.3048 -0.2032)
							(mid -0.275042 -0.275042)
							(end -0.2032 -0.3048)
						)
						(arc
							(start 0.2032 -0.3048)
							(mid 0.275042 -0.275042)
							(end 0.3048 -0.2032)
						)
					)
					(width 0)
					(fill yes)
				)
			)
		)
		(pad "2" smd custom
			(at 0 0.4445 90)
			(size 0.1524 0.1524)
			(layers "B.Cu" "B.Mask" "B.Paste")
			(net "GND")
			(options
				(clearance outline)
				(anchor circle)
			)
			(primitives
				(gr_poly
					(pts
						(arc
							(start 0.3048 0.2032)
							(mid 0.275042 0.275042)
							(end 0.2032 0.3048)
						)
						(arc
							(start -0.2032 0.3048)
							(mid -0.275042 0.275042)
							(end -0.3048 0.2032)
						)
						(arc
							(start -0.3048 -0.2032)
							(mid -0.275042 -0.275042)
							(end -0.2032 -0.3048)
						)
						(arc
							(start 0.2032 -0.3048)
							(mid 0.275042 -0.275042)
							(end 0.3048 -0.2032)
						)
					)
					(width 0)
					(fill yes)
				)
			)
		)
	)
	(footprint ""
		(layer "B.Cu")
		(at 202.820778 -31.646622 90)
		(property "Reference" "L22"
			(at 0 0 90)
			(layer "B.SilkS")
			(hide yes)
			(effects
				(font
					(size 1.27 1.27)
				)
				(justify mirror)
			)
		)
		(property "Value" "MPZ2012S601AT-GP"
			(at 0 -4.2418 90)
			(unlocked yes)
			(layer "B.Fab")
			(hide yes)
			(effects
				(font
					(size 1.016 1.016)
					(thickness 0.1524)
				)
				(justify mirror)
			)
		)
		(property "Device Type" "L805H42"
			(at 0 -5.7912 90)
			(unlocked yes)
			(layer "B.Fab")
			(hide yes)
			(effects
				(font
					(size 1.016 1.016)
					(thickness 0.1524)
				)
				(justify mirror)
			)
		)
		(duplicate_pad_numbers_are_jumpers no)
		(fp_line
			(start 0.889 -1.7018)
			(end -0.889 -1.7018)
			(stroke
				(width 0.1524)
				(type default)
			)
			(layer "B.SilkS")
		)
		(fp_line
			(start -0.889 -1.7018)
			(end -0.889 1.7018)
			(stroke
				(width 0.1524)
				(type default)
			)
			(layer "B.SilkS")
		)
		(fp_line
			(start 0.889 1.7018)
			(end 0.889 -1.7018)
			(stroke
				(width 0.1524)
				(type default)
			)
			(layer "B.SilkS")
		)
		(fp_line
			(start -0.889 1.7018)
			(end 0.889 1.7018)
			(stroke
				(width 0.1524)
				(type default)
			)
			(layer "B.SilkS")
		)
		(fp_rect
			(start 0.9652 1.778)
			(end -0.9652 -1.778)
			(stroke
				(width 0)
				(type default)
			)
			(fill no)
			(layer "B.CrtYd")
		)
		(fp_rect
			(start 0.9652 1.778)
			(end -0.9652 -1.778)
			(stroke
				(width 0)
				(type default)
			)
			(fill no)
			(layer "B.Fab")
		)
		(pad "1" smd rect
			(at 0 -0.9652 270)
			(size 1.397 1.143)
			(layers "B.Cu" "B.Mask" "B.Paste")
			(net "PLL_VDD")
		)
		(pad "2" smd rect
			(at 0 0.9652 270)
			(size 1.397 1.143)
			(layers "B.Cu" "B.Mask" "B.Paste")
			(net "P1V8_C")
		)
	)
	(footprint ""
		(layer "B.Cu")
		(at 131.829048 -119.398034 -90)
		(property "Reference" "C609"
			(at 0 0 90)
			(layer "B.SilkS")
			(hide yes)
			(effects
				(font
					(size 1.27 1.27)
				)
				(justify mirror)
			)
		)
		(property "Value" "SC10U6D3V5KX-4GP"
			(at 0.0762 -6.1214 270)
			(unlocked yes)
			(layer "B.Fab")
			(hide yes)
			(effects
				(font
					(size 1.016 1.016)
					(thickness 0.1524)
				)
				(justify mirror)
			)
		)
		(property "Device Type" "C805H58"
			(at 0.0762 -8.1534 270)
			(unlocked yes)
			(layer "B.Fab")
			(hide yes)
			(effects
				(font
					(size 1.016 1.016)
					(thickness 0.1524)
				)
				(justify mirror)
			)
		)
		(duplicate_pad_numbers_are_jumpers no)
		(fp_line
			(start -0.635 0)
			(end 0.635 0)
			(stroke
				(width 0.508)
				(type default)
			)
			(layer "B.SilkS")
		)
		(fp_rect
			(start 0.9652 1.778)
			(end -0.9652 -1.778)
			(stroke
				(width 0)
				(type default)
			)
			(fill no)
			(layer "B.CrtYd")
		)
		(fp_poly
			(pts
				(xy 0.9652 -1.778) (xy -0.9652 -1.778) (xy -0.9652 1.778) (xy 0.9652 1.778)
			)
			(stroke
				(width 0)
				(type default)
			)
			(fill no)
			(layer "B.Fab")
		)
		(pad "1" smd rect
			(at 0 -0.9652 90)
			(size 1.397 1.143)
			(layers "B.Cu" "B.Mask" "B.Paste")
			(net "P1V5_C")
		)
		(pad "2" smd rect
			(at 0 0.9652 90)
			(size 1.397 1.143)
			(layers "B.Cu" "B.Mask" "B.Paste")
			(net "GND")
		)
	)
	(footprint ""
		(layer "B.Cu")
		(at 186.563 -35.3568 90)
		(property "Reference" "TP98"
			(at 0 0 90)
			(layer "B.SilkS")
			(hide yes)
			(effects
				(font
					(size 1.27 1.27)
				)
				(justify mirror)
			)
		)
		(property "Value" "TPAD28-2-GP"
			(at 0.0127 -1.6637 90)
			(unlocked yes)
			(layer "B.Fab")
			(hide yes)
			(effects
				(font
					(size 1.016 1.016)
					(thickness 0.1524)
				)
				(justify mirror)
			)
		)
		(property "Device Type" "TPAD28"
			(at 0.0127 -3.1877 90)
			(unlocked yes)
			(layer "B.Fab")
			(hide yes)
			(effects
				(font
					(size 1.016 1.016)
					(thickness 0.1524)
				)
				(justify mirror)
			)
		)
		(duplicate_pad_numbers_are_jumpers no)
		(fp_poly
			(pts
				(arc
					(start 0 0.3556)
					(mid 0 -0.3556)
					(end 0 0.3556)
				)
			)
			(stroke
				(width 0)
				(type default)
			)
			(fill no)
			(layer "B.CrtYd")
		)
		(fp_poly
			(pts
				(arc
					(start 0 0.6096)
					(mid 0 -0.6096)
					(end 0 0.6096)
				)
			)
			(stroke
				(width 0)
				(type default)
			)
			(fill no)
			(layer "B.Fab")
		)
		(pad "1" smd circle
			(at 0 0 270)
			(size 0.7112 0.7112)
			(layers "B.Cu" "B.Mask" "B.Paste")
			(net "IOC_GPIO_36")
		)
	)
	(footprint ""
		(layer "B.Cu")
		(at 98.7298 -44.2214 180)
		(property "Reference" "C85"
			(at 0 0 0)
			(layer "B.SilkS")
			(hide yes)
			(effects
				(font
					(size 1.27 1.27)
				)
				(justify mirror)
			)
		)
		(property "Value" "SCD01U16V1KX-GP"
			(at 2.8321 -1.7399 180)
			(unlocked yes)
			(layer "B.Fab")
			(hide yes)
			(effects
				(font
					(size 1.016 1.016)
					(thickness 0.1524)
				)
				(justify mirror)
			)
		)
		(property "Device Type" "C0201H13"
			(at 2.8321 -3.2639 180)
			(unlocked yes)
			(layer "B.Fab")
			(hide yes)
			(effects
				(font
					(size 1.016 1.016)
					(thickness 0.1524)
				)
				(justify mirror)
			)
		)
		(duplicate_pad_numbers_are_jumpers no)
		(fp_rect
			(start 0.2794 0.6477)
			(end -0.2794 -0.6477)
			(stroke
				(width 0)
				(type default)
			)
			(fill no)
			(layer "B.CrtYd")
		)
		(fp_rect
			(start 0.2794 0.6477)
			(end -0.2794 -0.6477)
			(stroke
				(width 0)
				(type default)
			)
			(fill no)
			(layer "B.Fab")
		)
		(pad "1" smd custom
			(at 0 -0.2794)
			(size 0.0762 0.0762)
			(layers "B.Cu" "B.Mask" "B.Paste")
			(net "PHY_DPB_TO_SCC_17_DP")
			(options
				(clearance outline)
				(anchor circle)
			)
			(primitives
				(gr_poly
					(pts
						(arc
							(start 0.1524 0.127)
							(mid 0.137521 0.162921)
							(end 0.1016 0.1778)
						)
						(arc
							(start -0.1016 0.1778)
							(mid -0.137521 0.162921)
							(end -0.1524 0.127)
						)
						(arc
							(start -0.1524 -0.127)
							(mid -0.137521 -0.162921)
							(end -0.1016 -0.1778)
						)
						(arc
							(start 0.1016 -0.1778)
							(mid 0.137521 -0.162921)
							(end 0.1524 -0.127)
						)
					)
					(width 0)
					(fill yes)
				)
			)
		)
		(pad "2" smd custom
			(at 0 0.2794)
			(size 0.0762 0.0762)
			(layers "B.Cu" "B.Mask" "B.Paste")
			(net "PHY_DPB_TO_SCC_C_17_DP")
			(options
				(clearance outline)
				(anchor circle)
			)
			(primitives
				(gr_poly
					(pts
						(arc
							(start 0.1524 0.127)
							(mid 0.137521 0.162921)
							(end 0.1016 0.1778)
						)
						(arc
							(start -0.1016 0.1778)
							(mid -0.137521 0.162921)
							(end -0.1524 0.127)
						)
						(arc
							(start -0.1524 -0.127)
							(mid -0.137521 -0.162921)
							(end -0.1016 -0.1778)
						)
						(arc
							(start 0.1016 -0.1778)
							(mid 0.137521 -0.162921)
							(end 0.1524 -0.127)
						)
					)
					(width 0)
					(fill yes)
				)
			)
		)
	)
	(footprint ""
		(layer "B.Cu")
		(at 124.7267 -70.485 90)
		(property "Reference" "C279"
			(at 0 0 90)
			(layer "B.SilkS")
			(hide yes)
			(effects
				(font
					(size 1.27 1.27)
				)
				(justify mirror)
			)
		)
		(property "Value" "SCD1U6D3V1KX-GP"
			(at 2.8321 -1.7399 90)
			(unlocked yes)
			(layer "B.Fab")
			(hide yes)
			(effects
				(font
					(size 1.016 1.016)
					(thickness 0.1524)
				)
				(justify mirror)
			)
		)
		(property "Device Type" "C0201H13"
			(at 2.8321 -3.2639 90)
			(unlocked yes)
			(layer "B.Fab")
			(hide yes)
			(effects
				(font
					(size 1.016 1.016)
					(thickness 0.1524)
				)
				(justify mirror)
			)
		)
		(duplicate_pad_numbers_are_jumpers no)
		(fp_rect
			(start 0.2794 0.6477)
			(end -0.2794 -0.6477)
			(stroke
				(width 0)
				(type default)
			)
			(fill no)
			(layer "B.CrtYd")
		)
		(fp_rect
			(start 0.2794 0.6477)
			(end -0.2794 -0.6477)
			(stroke
				(width 0)
				(type default)
			)
			(fill no)
			(layer "B.Fab")
		)
		(pad "1" smd custom
			(at 0 -0.2794 270)
			(size 0.0762 0.0762)
			(layers "B.Cu" "B.Mask" "B.Paste")
			(net "GB_VDDA")
			(options
				(clearance outline)
				(anchor circle)
			)
			(primitives
				(gr_poly
					(pts
						(arc
							(start 0.1524 0.127)
							(mid 0.137521 0.162921)
							(end 0.1016 0.1778)
						)
						(arc
							(start -0.1016 0.1778)
							(mid -0.137521 0.162921)
							(end -0.1524 0.127)
						)
						(arc
							(start -0.1524 -0.127)
							(mid -0.137521 -0.162921)
							(end -0.1016 -0.1778)
						)
						(arc
							(start 0.1016 -0.1778)
							(mid 0.137521 -0.162921)
							(end 0.1524 -0.127)
						)
					)
					(width 0)
					(fill yes)
				)
			)
		)
		(pad "2" smd custom
			(at 0 0.2794 270)
			(size 0.0762 0.0762)
			(layers "B.Cu" "B.Mask" "B.Paste")
			(net "GND")
			(options
				(clearance outline)
				(anchor circle)
			)
			(primitives
				(gr_poly
					(pts
						(arc
							(start 0.1524 0.127)
							(mid 0.137521 0.162921)
							(end 0.1016 0.1778)
						)
						(arc
							(start -0.1016 0.1778)
							(mid -0.137521 0.162921)
							(end -0.1524 0.127)
						)
						(arc
							(start -0.1524 -0.127)
							(mid -0.137521 -0.162921)
							(end -0.1016 -0.1778)
						)
						(arc
							(start 0.1016 -0.1778)
							(mid 0.137521 -0.162921)
							(end 0.1524 -0.127)
						)
					)
					(width 0)
					(fill yes)
				)
			)
		)
	)
	(footprint ""
		(layer "B.Cu")
		(at 163.449 -42.164 -90)
		(property "Reference" "R178"
			(at 0 0 90)
			(layer "B.SilkS")
			(hide yes)
			(effects
				(font
					(size 1.27 1.27)
				)
				(justify mirror)
			)
		)
		(property "Value" "10KR2F-2-GP"
			(at -0.064008 -3.993896 270)
			(unlocked yes)
			(layer "B.Fab")
			(hide yes)
			(effects
				(font
					(size 1.016 1.016)
					(thickness 0.1524)
				)
				(justify mirror)
			)
		)
		(property "Device Type" "R402H16"
			(at -0.064008 -5.517896 270)
			(unlocked yes)
			(layer "B.Fab")
			(hide yes)
			(effects
				(font
					(size 1.016 1.016)
					(thickness 0.1524)
				)
				(justify mirror)
			)
		)
		(duplicate_pad_numbers_are_jumpers no)
		(fp_line
			(start -0.508 -0.9398)
			(end 0.508 -0.9398)
			(stroke
				(width 0.1524)
				(type default)
			)
			(layer "B.SilkS")
		)
		(fp_line
			(start 0.508 -0.9398)
			(end 0.508 0.9398)
			(stroke
				(width 0.1524)
				(type default)
			)
			(layer "B.SilkS")
		)
		(fp_rect
			(start 0.508 0.9398)
			(end -0.508 -0.9398)
			(stroke
				(width 0)
				(type default)
			)
			(fill no)
			(layer "B.CrtYd")
		)
		(fp_rect
			(start 0.508 0.9398)
			(end -0.508 -0.9398)
			(stroke
				(width 0)
				(type default)
			)
			(fill no)
			(layer "B.Fab")
		)
		(pad "1" smd custom
			(at 0 -0.4445 90)
			(size 0.1397 0.1397)
			(layers "B.Cu" "B.Mask" "B.Paste")
			(net "IOC_SIO_BLINK")
			(options
				(clearance outline)
				(anchor circle)
			)
			(primitives
				(gr_poly
					(pts
						(arc
							(start -0.1778 0.2794)
							(mid -0.249642 0.249642)
							(end -0.2794 0.1778)
						)
						(arc
							(start -0.2794 -0.1778)
							(mid -0.249642 -0.249642)
							(end -0.1778 -0.2794)
						)
						(arc
							(start 0.1778 -0.2794)
							(mid 0.249642 -0.249642)
							(end 0.2794 -0.1778)
						)
						(arc
							(start 0.2794 0.1778)
							(mid 0.249642 0.249642)
							(end 0.1778 0.2794)
						)
					)
					(width 0)
					(fill yes)
				)
			)
		)
		(pad "2" smd custom
			(at 0 0.4445 90)
			(size 0.1397 0.1397)
			(layers "B.Cu" "B.Mask" "B.Paste")
			(net "GND")
			(options
				(clearance outline)
				(anchor circle)
			)
			(primitives
				(gr_poly
					(pts
						(arc
							(start -0.1778 0.2794)
							(mid -0.249642 0.249642)
							(end -0.2794 0.1778)
						)
						(arc
							(start -0.2794 -0.1778)
							(mid -0.249642 -0.249642)
							(end -0.1778 -0.2794)
						)
						(arc
							(start 0.1778 -0.2794)
							(mid 0.249642 -0.249642)
							(end 0.2794 -0.1778)
						)
						(arc
							(start 0.2794 0.1778)
							(mid 0.249642 0.249642)
							(end 0.1778 0.2794)
						)
					)
					(width 0)
					(fill yes)
				)
			)
		)
	)
	(footprint ""
		(layer "B.Cu")
		(at 99.5426 -86.9696)
		(property "Reference" "R79"
			(at 0 0 0)
			(layer "B.SilkS")
			(hide yes)
			(effects
				(font
					(size 1.27 1.27)
				)
				(justify mirror)
			)
		)
		(property "Value" "4K7R2F-GP"
			(at -0.064008 -3.993896 0)
			(unlocked yes)
			(layer "B.Fab")
			(hide yes)
			(effects
				(font
					(size 1.016 1.016)
					(thickness 0.1524)
				)
				(justify mirror)
			)
		)
		(property "Device Type" "R402H16"
			(at -0.064008 -5.517896 0)
			(unlocked yes)
			(layer "B.Fab")
			(hide yes)
			(effects
				(font
					(size 1.016 1.016)
					(thickness 0.1524)
				)
				(justify mirror)
			)
		)
		(duplicate_pad_numbers_are_jumpers no)
		(fp_line
			(start -0.508 -0.9398)
			(end 0.508 -0.9398)
			(stroke
				(width 0.1524)
				(type default)
			)
			(layer "B.SilkS")
		)
		(fp_line
			(start 0.508 -0.9398)
			(end 0.508 0.9398)
			(stroke
				(width 0.1524)
				(type default)
			)
			(layer "B.SilkS")
		)
		(fp_rect
			(start 0.508 0.9398)
			(end -0.508 -0.9398)
			(stroke
				(width 0)
				(type default)
			)
			(fill no)
			(layer "B.CrtYd")
		)
		(fp_rect
			(start 0.508 0.9398)
			(end -0.508 -0.9398)
			(stroke
				(width 0)
				(type default)
			)
			(fill no)
			(layer "B.Fab")
		)
		(pad "1" smd custom
			(at 0 -0.4445 180)
			(size 0.1397 0.1397)
			(layers "B.Cu" "B.Mask" "B.Paste")
			(net "SCC_TYPE_0_LS")
			(options
				(clearance outline)
				(anchor circle)
			)
			(primitives
				(gr_poly
					(pts
						(arc
							(start -0.1778 0.2794)
							(mid -0.249642 0.249642)
							(end -0.2794 0.1778)
						)
						(arc
							(start -0.2794 -0.1778)
							(mid -0.249642 -0.249642)
							(end -0.1778 -0.2794)
						)
						(arc
							(start 0.1778 -0.2794)
							(mid 0.249642 -0.249642)
							(end 0.2794 -0.1778)
						)
						(arc
							(start 0.2794 0.1778)
							(mid 0.249642 0.249642)
							(end 0.1778 0.2794)
						)
					)
					(width 0)
					(fill yes)
				)
			)
		)
		(pad "2" smd custom
			(at 0 0.4445 180)
			(size 0.1397 0.1397)
			(layers "B.Cu" "B.Mask" "B.Paste")
			(net "GND")
			(options
				(clearance outline)
				(anchor circle)
			)
			(primitives
				(gr_poly
					(pts
						(arc
							(start -0.1778 0.2794)
							(mid -0.249642 0.249642)
							(end -0.2794 0.1778)
						)
						(arc
							(start -0.2794 -0.1778)
							(mid -0.249642 -0.249642)
							(end -0.1778 -0.2794)
						)
						(arc
							(start 0.1778 -0.2794)
							(mid 0.249642 -0.249642)
							(end 0.2794 -0.1778)
						)
						(arc
							(start 0.2794 0.1778)
							(mid 0.249642 0.249642)
							(end 0.1778 0.2794)
						)
					)
					(width 0)
					(fill yes)
				)
			)
		)
	)
	(footprint ""
		(layer "B.Cu")
		(at 178.1302 -31.75 -90)
		(property "Reference" "C471"
			(at 0 0 90)
			(layer "B.SilkS")
			(hide yes)
			(effects
				(font
					(size 1.27 1.27)
				)
				(justify mirror)
			)
		)
		(property "Value" "SCD1U6D3V1KX-GP"
			(at 2.8321 -1.7399 270)
			(unlocked yes)
			(layer "B.Fab")
			(hide yes)
			(effects
				(font
					(size 1.016 1.016)
					(thickness 0.1524)
				)
				(justify mirror)
			)
		)
		(property "Device Type" "C0201H13"
			(at 2.8321 -3.2639 270)
			(unlocked yes)
			(layer "B.Fab")
			(hide yes)
			(effects
				(font
					(size 1.016 1.016)
					(thickness 0.1524)
				)
				(justify mirror)
			)
		)
		(duplicate_pad_numbers_are_jumpers no)
		(fp_rect
			(start 0.2794 0.6477)
			(end -0.2794 -0.6477)
			(stroke
				(width 0)
				(type default)
			)
			(fill no)
			(layer "B.CrtYd")
		)
		(fp_rect
			(start 0.2794 0.6477)
			(end -0.2794 -0.6477)
			(stroke
				(width 0)
				(type default)
			)
			(fill no)
			(layer "B.Fab")
		)
		(pad "1" smd custom
			(at 0 -0.2794 90)
			(size 0.0762 0.0762)
			(layers "B.Cu" "B.Mask" "B.Paste")
			(net "P1V8_C")
			(options
				(clearance outline)
				(anchor circle)
			)
			(primitives
				(gr_poly
					(pts
						(arc
							(start 0.1524 0.127)
							(mid 0.137521 0.162921)
							(end 0.1016 0.1778)
						)
						(arc
							(start -0.1016 0.1778)
							(mid -0.137521 0.162921)
							(end -0.1524 0.127)
						)
						(arc
							(start -0.1524 -0.127)
							(mid -0.137521 -0.162921)
							(end -0.1016 -0.1778)
						)
						(arc
							(start 0.1016 -0.1778)
							(mid 0.137521 -0.162921)
							(end 0.1524 -0.127)
						)
					)
					(width 0)
					(fill yes)
				)
			)
		)
		(pad "2" smd custom
			(at 0 0.2794 90)
			(size 0.0762 0.0762)
			(layers "B.Cu" "B.Mask" "B.Paste")
			(net "GND")
			(options
				(clearance outline)
				(anchor circle)
			)
			(primitives
				(gr_poly
					(pts
						(arc
							(start 0.1524 0.127)
							(mid 0.137521 0.162921)
							(end 0.1016 0.1778)
						)
						(arc
							(start -0.1016 0.1778)
							(mid -0.137521 0.162921)
							(end -0.1524 0.127)
						)
						(arc
							(start -0.1524 -0.127)
							(mid -0.137521 -0.162921)
							(end -0.1016 -0.1778)
						)
						(arc
							(start 0.1016 -0.1778)
							(mid 0.137521 -0.162921)
							(end 0.1524 -0.127)
						)
					)
					(width 0)
					(fill yes)
				)
			)
		)
	)
	(footprint ""
		(layer "B.Cu")
		(at 128.524 -89.7382)
		(property "Reference" "R64"
			(at 0 0 0)
			(layer "B.SilkS")
			(hide yes)
			(effects
				(font
					(size 1.27 1.27)
				)
				(justify mirror)
			)
		)
		(property "Value" "4K7R2F-GP"
			(at -0.064008 -3.993896 0)
			(unlocked yes)
			(layer "B.Fab")
			(hide yes)
			(effects
				(font
					(size 1.016 1.016)
					(thickness 0.1524)
				)
				(justify mirror)
			)
		)
		(property "Device Type" "R402H16"
			(at -0.064008 -5.517896 0)
			(unlocked yes)
			(layer "B.Fab")
			(hide yes)
			(effects
				(font
					(size 1.016 1.016)
					(thickness 0.1524)
				)
				(justify mirror)
			)
		)
		(duplicate_pad_numbers_are_jumpers no)
		(fp_line
			(start -0.508 -0.9398)
			(end 0.508 -0.9398)
			(stroke
				(width 0.1524)
				(type default)
			)
			(layer "B.SilkS")
		)
		(fp_line
			(start 0.508 -0.9398)
			(end 0.508 0.9398)
			(stroke
				(width 0.1524)
				(type default)
			)
			(layer "B.SilkS")
		)
		(fp_rect
			(start 0.508 0.9398)
			(end -0.508 -0.9398)
			(stroke
				(width 0)
				(type default)
			)
			(fill no)
			(layer "B.CrtYd")
		)
		(fp_rect
			(start 0.508 0.9398)
			(end -0.508 -0.9398)
			(stroke
				(width 0)
				(type default)
			)
			(fill no)
			(layer "B.Fab")
		)
		(pad "1" smd custom
			(at 0 -0.4445 180)
			(size 0.1397 0.1397)
			(layers "B.Cu" "B.Mask" "B.Paste")
			(net "P1V8_E")
			(options
				(clearance outline)
				(anchor circle)
			)
			(primitives
				(gr_poly
					(pts
						(arc
							(start -0.1778 0.2794)
							(mid -0.249642 0.249642)
							(end -0.2794 0.1778)
						)
						(arc
							(start -0.2794 -0.1778)
							(mid -0.249642 -0.249642)
							(end -0.1778 -0.2794)
						)
						(arc
							(start 0.1778 -0.2794)
							(mid 0.249642 -0.249642)
							(end 0.2794 -0.1778)
						)
						(arc
							(start 0.2794 0.1778)
							(mid 0.249642 0.249642)
							(end 0.1778 0.2794)
						)
					)
					(width 0)
					(fill yes)
				)
			)
		)
		(pad "2" smd custom
			(at 0 0.4445 180)
			(size 0.1397 0.1397)
			(layers "B.Cu" "B.Mask" "B.Paste")
			(net "I2C_CLIP_SCL7_LS")
			(options
				(clearance outline)
				(anchor circle)
			)
			(primitives
				(gr_poly
					(pts
						(arc
							(start -0.1778 0.2794)
							(mid -0.249642 0.249642)
							(end -0.2794 0.1778)
						)
						(arc
							(start -0.2794 -0.1778)
							(mid -0.249642 -0.249642)
							(end -0.1778 -0.2794)
						)
						(arc
							(start 0.1778 -0.2794)
							(mid 0.249642 -0.249642)
							(end 0.2794 -0.1778)
						)
						(arc
							(start 0.2794 0.1778)
							(mid 0.249642 0.249642)
							(end 0.1778 0.2794)
						)
					)
					(width 0)
					(fill yes)
				)
			)
		)
	)
	(footprint ""
		(layer "B.Cu")
		(at 184.465468 -44.78401 90)
		(property "Reference" "C461"
			(at 0 0 90)
			(layer "B.SilkS")
			(hide yes)
			(effects
				(font
					(size 1.27 1.27)
				)
				(justify mirror)
			)
		)
		(property "Value" "SCD1U6D3V1KX-GP"
			(at 2.8321 -1.7399 90)
			(unlocked yes)
			(layer "B.Fab")
			(hide yes)
			(effects
				(font
					(size 1.016 1.016)
					(thickness 0.1524)
				)
				(justify mirror)
			)
		)
		(property "Device Type" "C0201H13"
			(at 2.8321 -3.2639 90)
			(unlocked yes)
			(layer "B.Fab")
			(hide yes)
			(effects
				(font
					(size 1.016 1.016)
					(thickness 0.1524)
				)
				(justify mirror)
			)
		)
		(duplicate_pad_numbers_are_jumpers no)
		(fp_rect
			(start 0.2794 0.6477)
			(end -0.2794 -0.6477)
			(stroke
				(width 0)
				(type default)
			)
			(fill no)
			(layer "B.CrtYd")
		)
		(fp_rect
			(start 0.2794 0.6477)
			(end -0.2794 -0.6477)
			(stroke
				(width 0)
				(type default)
			)
			(fill no)
			(layer "B.Fab")
		)
		(pad "1" smd custom
			(at 0 -0.2794 270)
			(size 0.0762 0.0762)
			(layers "B.Cu" "B.Mask" "B.Paste")
			(net "P1V8_C")
			(options
				(clearance outline)
				(anchor circle)
			)
			(primitives
				(gr_poly
					(pts
						(arc
							(start 0.1524 0.127)
							(mid 0.137521 0.162921)
							(end 0.1016 0.1778)
						)
						(arc
							(start -0.1016 0.1778)
							(mid -0.137521 0.162921)
							(end -0.1524 0.127)
						)
						(arc
							(start -0.1524 -0.127)
							(mid -0.137521 -0.162921)
							(end -0.1016 -0.1778)
						)
						(arc
							(start 0.1016 -0.1778)
							(mid 0.137521 -0.162921)
							(end 0.1524 -0.127)
						)
					)
					(width 0)
					(fill yes)
				)
			)
		)
		(pad "2" smd custom
			(at 0 0.2794 270)
			(size 0.0762 0.0762)
			(layers "B.Cu" "B.Mask" "B.Paste")
			(net "GND")
			(options
				(clearance outline)
				(anchor circle)
			)
			(primitives
				(gr_poly
					(pts
						(arc
							(start 0.1524 0.127)
							(mid 0.137521 0.162921)
							(end 0.1016 0.1778)
						)
						(arc
							(start -0.1016 0.1778)
							(mid -0.137521 0.162921)
							(end -0.1524 0.127)
						)
						(arc
							(start -0.1524 -0.127)
							(mid -0.137521 -0.162921)
							(end -0.1016 -0.1778)
						)
						(arc
							(start 0.1016 -0.1778)
							(mid 0.137521 -0.162921)
							(end 0.1524 -0.127)
						)
					)
					(width 0)
					(fill yes)
				)
			)
		)
	)
	(footprint ""
		(layer "B.Cu")
		(at 192.73901 -35.669982 -90)
		(property "Reference" "R187"
			(at 0 0 90)
			(layer "B.SilkS")
			(hide yes)
			(effects
				(font
					(size 1.27 1.27)
				)
				(justify mirror)
			)
		)
		(property "Value" "2K2R2F-GP"
			(at -0.064008 -3.993896 270)
			(unlocked yes)
			(layer "B.Fab")
			(hide yes)
			(effects
				(font
					(size 1.016 1.016)
					(thickness 0.1524)
				)
				(justify mirror)
			)
		)
		(property "Device Type" "R402H16"
			(at -0.064008 -5.517896 270)
			(unlocked yes)
			(layer "B.Fab")
			(hide yes)
			(effects
				(font
					(size 1.016 1.016)
					(thickness 0.1524)
				)
				(justify mirror)
			)
		)
		(duplicate_pad_numbers_are_jumpers no)
		(fp_line
			(start -0.508 -0.9398)
			(end 0.508 -0.9398)
			(stroke
				(width 0.1524)
				(type default)
			)
			(layer "B.SilkS")
		)
		(fp_line
			(start 0.508 -0.9398)
			(end 0.508 0.9398)
			(stroke
				(width 0.1524)
				(type default)
			)
			(layer "B.SilkS")
		)
		(fp_rect
			(start 0.508 0.9398)
			(end -0.508 -0.9398)
			(stroke
				(width 0)
				(type default)
			)
			(fill no)
			(layer "B.CrtYd")
		)
		(fp_rect
			(start 0.508 0.9398)
			(end -0.508 -0.9398)
			(stroke
				(width 0)
				(type default)
			)
			(fill no)
			(layer "B.Fab")
		)
		(pad "1" smd custom
			(at 0 -0.4445 90)
			(size 0.1397 0.1397)
			(layers "B.Cu" "B.Mask" "B.Paste")
			(net "P1V8_C")
			(options
				(clearance outline)
				(anchor circle)
			)
			(primitives
				(gr_poly
					(pts
						(arc
							(start -0.1778 0.2794)
							(mid -0.249642 0.249642)
							(end -0.2794 0.1778)
						)
						(arc
							(start -0.2794 -0.1778)
							(mid -0.249642 -0.249642)
							(end -0.1778 -0.2794)
						)
						(arc
							(start 0.1778 -0.2794)
							(mid 0.249642 -0.249642)
							(end 0.2794 -0.1778)
						)
						(arc
							(start 0.2794 0.1778)
							(mid 0.249642 0.249642)
							(end 0.1778 0.2794)
						)
					)
					(width 0)
					(fill yes)
				)
			)
		)
		(pad "2" smd custom
			(at 0 0.4445 90)
			(size 0.1397 0.1397)
			(layers "B.Cu" "B.Mask" "B.Paste")
			(net "I2C_IOC_2_SDA")
			(options
				(clearance outline)
				(anchor circle)
			)
			(primitives
				(gr_poly
					(pts
						(arc
							(start -0.1778 0.2794)
							(mid -0.249642 0.249642)
							(end -0.2794 0.1778)
						)
						(arc
							(start -0.2794 -0.1778)
							(mid -0.249642 -0.249642)
							(end -0.1778 -0.2794)
						)
						(arc
							(start 0.1778 -0.2794)
							(mid 0.249642 -0.249642)
							(end 0.2794 -0.1778)
						)
						(arc
							(start 0.2794 0.1778)
							(mid 0.249642 0.249642)
							(end 0.1778 0.2794)
						)
					)
					(width 0)
					(fill yes)
				)
			)
		)
	)
	(footprint ""
		(layer "B.Cu")
		(at 70.612 -57.023 90)
		(property "Reference" "R160"
			(at 0 0 90)
			(layer "B.SilkS")
			(hide yes)
			(effects
				(font
					(size 1.27 1.27)
				)
				(justify mirror)
			)
		)
		(property "Value" "D51R3F-2-GP"
			(at 0.0254 -2.5146 90)
			(unlocked yes)
			(layer "B.Fab")
			(hide yes)
			(effects
				(font
					(size 1.016 1.016)
					(thickness 0.1524)
				)
				(justify mirror)
			)
		)
		(property "Device Type" "R603H22"
			(at 0.0254 -4.0386 90)
			(unlocked yes)
			(layer "B.Fab")
			(hide yes)
			(effects
				(font
					(size 1.016 1.016)
					(thickness 0.1524)
				)
				(justify mirror)
			)
		)
		(duplicate_pad_numbers_are_jumpers no)
		(fp_line
			(start 0.4826 0)
			(end 0.2032 0)
			(stroke
				(width 0.2032)
				(type default)
			)
			(layer "B.SilkS")
		)
		(fp_line
			(start -0.2032 0)
			(end -0.4826 0)
			(stroke
				(width 0.2032)
				(type default)
			)
			(layer "B.SilkS")
		)
		(fp_rect
			(start 0.5842 1.3335)
			(end -0.5842 -1.3335)
			(stroke
				(width 0)
				(type default)
			)
			(fill no)
			(layer "B.CrtYd")
		)
		(fp_rect
			(start 0.5842 1.3335)
			(end -0.5842 -1.3335)
			(stroke
				(width 0)
				(type default)
			)
			(fill no)
			(layer "B.Fab")
		)
		(pad "1" smd custom
			(at 0 -0.762 270)
			(size 0.2159 0.2159)
			(layers "B.Cu" "B.Mask" "B.Paste")
			(net "P0V9")
			(options
				(clearance outline)
				(anchor circle)
			)
			(primitives
				(gr_poly
					(pts
						(arc
							(start -0.3302 0.4318)
							(mid -0.402042 0.402042)
							(end -0.4318 0.3302)
						)
						(arc
							(start -0.4318 -0.3302)
							(mid -0.402042 -0.402042)
							(end -0.3302 -0.4318)
						)
						(arc
							(start 0.3302 -0.4318)
							(mid 0.402042 -0.402042)
							(end 0.4318 -0.3302)
						)
						(arc
							(start 0.4318 0.3302)
							(mid 0.402042 0.402042)
							(end 0.3302 0.4318)
						)
					)
					(width 0)
					(fill yes)
				)
			)
		)
		(pad "2" smd custom
			(at 0 0.762 270)
			(size 0.2159 0.2159)
			(layers "B.Cu" "B.Mask" "B.Paste")
			(net "GB_VDDA")
			(options
				(clearance outline)
				(anchor circle)
			)
			(primitives
				(gr_poly
					(pts
						(arc
							(start -0.3302 0.4318)
							(mid -0.402042 0.402042)
							(end -0.4318 0.3302)
						)
						(arc
							(start -0.4318 -0.3302)
							(mid -0.402042 -0.402042)
							(end -0.3302 -0.4318)
						)
						(arc
							(start 0.3302 -0.4318)
							(mid 0.402042 -0.402042)
							(end 0.4318 -0.3302)
						)
						(arc
							(start 0.4318 0.3302)
							(mid 0.402042 0.402042)
							(end 0.3302 0.4318)
						)
					)
					(width 0)
					(fill yes)
				)
			)
		)
	)
	(footprint ""
		(layer "B.Cu")
		(at 165.608 -52.07)
		(property "Reference" "R196"
			(at 0 0 0)
			(layer "B.SilkS")
			(hide yes)
			(effects
				(font
					(size 1.27 1.27)
				)
				(justify mirror)
			)
		)
		(property "Value" "2K2R2F-GP"
			(at -0.064008 -3.993896 0)
			(unlocked yes)
			(layer "B.Fab")
			(hide yes)
			(effects
				(font
					(size 1.016 1.016)
					(thickness 0.1524)
				)
				(justify mirror)
			)
		)
		(property "Device Type" "R402H16"
			(at -0.064008 -5.517896 0)
			(unlocked yes)
			(layer "B.Fab")
			(hide yes)
			(effects
				(font
					(size 1.016 1.016)
					(thickness 0.1524)
				)
				(justify mirror)
			)
		)
		(duplicate_pad_numbers_are_jumpers no)
		(fp_line
			(start -0.508 -0.9398)
			(end 0.508 -0.9398)
			(stroke
				(width 0.1524)
				(type default)
			)
			(layer "B.SilkS")
		)
		(fp_line
			(start 0.508 -0.9398)
			(end 0.508 0.9398)
			(stroke
				(width 0.1524)
				(type default)
			)
			(layer "B.SilkS")
		)
		(fp_rect
			(start 0.508 0.9398)
			(end -0.508 -0.9398)
			(stroke
				(width 0)
				(type default)
			)
			(fill no)
			(layer "B.CrtYd")
		)
		(fp_rect
			(start 0.508 0.9398)
			(end -0.508 -0.9398)
			(stroke
				(width 0)
				(type default)
			)
			(fill no)
			(layer "B.Fab")
		)
		(pad "1" smd custom
			(at 0 -0.4445 180)
			(size 0.1397 0.1397)
			(layers "B.Cu" "B.Mask" "B.Paste")
			(net "P1V8_C")
			(options
				(clearance outline)
				(anchor circle)
			)
			(primitives
				(gr_poly
					(pts
						(arc
							(start -0.1778 0.2794)
							(mid -0.249642 0.249642)
							(end -0.2794 0.1778)
						)
						(arc
							(start -0.2794 -0.1778)
							(mid -0.249642 -0.249642)
							(end -0.1778 -0.2794)
						)
						(arc
							(start 0.1778 -0.2794)
							(mid 0.249642 -0.249642)
							(end 0.2794 -0.1778)
						)
						(arc
							(start 0.2794 0.1778)
							(mid 0.249642 0.249642)
							(end 0.1778 0.2794)
						)
					)
					(width 0)
					(fill yes)
				)
			)
		)
		(pad "2" smd custom
			(at 0 0.4445 180)
			(size 0.1397 0.1397)
			(layers "B.Cu" "B.Mask" "B.Paste")
			(net "SIO_LOAD_0")
			(options
				(clearance outline)
				(anchor circle)
			)
			(primitives
				(gr_poly
					(pts
						(arc
							(start -0.1778 0.2794)
							(mid -0.249642 0.249642)
							(end -0.2794 0.1778)
						)
						(arc
							(start -0.2794 -0.1778)
							(mid -0.249642 -0.249642)
							(end -0.1778 -0.2794)
						)
						(arc
							(start 0.1778 -0.2794)
							(mid 0.249642 -0.249642)
							(end 0.2794 -0.1778)
						)
						(arc
							(start 0.2794 0.1778)
							(mid 0.249642 0.249642)
							(end 0.1778 0.2794)
						)
					)
					(width 0)
					(fill yes)
				)
			)
		)
	)
	(footprint ""
		(layer "B.Cu")
		(at 121.9454 -92.3036 90)
		(property "Reference" "R560"
			(at 0 0 90)
			(layer "B.SilkS")
			(hide yes)
			(effects
				(font
					(size 1.27 1.27)
				)
				(justify mirror)
			)
		)
		(property "Value" "10KR2F-2-GP"
			(at -0.064008 -3.993896 90)
			(unlocked yes)
			(layer "B.Fab")
			(hide yes)
			(effects
				(font
					(size 1.016 1.016)
					(thickness 0.1524)
				)
				(justify mirror)
			)
		)
		(property "Device Type" "R402H16"
			(at -0.064008 -5.517896 90)
			(unlocked yes)
			(layer "B.Fab")
			(hide yes)
			(effects
				(font
					(size 1.016 1.016)
					(thickness 0.1524)
				)
				(justify mirror)
			)
		)
		(duplicate_pad_numbers_are_jumpers no)
		(fp_line
			(start 0.508 -0.9398)
			(end 0.508 0.9398)
			(stroke
				(width 0.1524)
				(type default)
			)
			(layer "B.SilkS")
		)
		(fp_line
			(start -0.508 -0.9398)
			(end 0.508 -0.9398)
			(stroke
				(width 0.1524)
				(type default)
			)
			(layer "B.SilkS")
		)
		(fp_rect
			(start 0.508 0.9398)
			(end -0.508 -0.9398)
			(stroke
				(width 0)
				(type default)
			)
			(fill no)
			(layer "B.CrtYd")
		)
		(fp_rect
			(start 0.508 0.9398)
			(end -0.508 -0.9398)
			(stroke
				(width 0)
				(type default)
			)
			(fill no)
			(layer "B.Fab")
		)
		(pad "1" smd custom
			(at 0 -0.4445 270)
			(size 0.1397 0.1397)
			(layers "B.Cu" "B.Mask" "B.Paste")
			(net "SCC_RMT_HEARTBEAT_LS")
			(options
				(clearance outline)
				(anchor circle)
			)
			(primitives
				(gr_poly
					(pts
						(arc
							(start -0.1778 0.2794)
							(mid -0.249642 0.249642)
							(end -0.2794 0.1778)
						)
						(arc
							(start -0.2794 -0.1778)
							(mid -0.249642 -0.249642)
							(end -0.1778 -0.2794)
						)
						(arc
							(start 0.1778 -0.2794)
							(mid 0.249642 -0.249642)
							(end 0.2794 -0.1778)
						)
						(arc
							(start 0.2794 0.1778)
							(mid 0.249642 0.249642)
							(end 0.1778 0.2794)
						)
					)
					(width 0)
					(fill yes)
				)
			)
		)
		(pad "2" smd custom
			(at 0 0.4445 270)
			(size 0.1397 0.1397)
			(layers "B.Cu" "B.Mask" "B.Paste")
			(net "P1V8_E")
			(options
				(clearance outline)
				(anchor circle)
			)
			(primitives
				(gr_poly
					(pts
						(arc
							(start -0.1778 0.2794)
							(mid -0.249642 0.249642)
							(end -0.2794 0.1778)
						)
						(arc
							(start -0.2794 -0.1778)
							(mid -0.249642 -0.249642)
							(end -0.1778 -0.2794)
						)
						(arc
							(start 0.1778 -0.2794)
							(mid 0.249642 -0.249642)
							(end 0.2794 -0.1778)
						)
						(arc
							(start 0.2794 0.1778)
							(mid 0.249642 0.249642)
							(end 0.1778 0.2794)
						)
					)
					(width 0)
					(fill yes)
				)
			)
		)
	)
	(footprint ""
		(layer "B.Cu")
		(at 167.132 -66.802 180)
		(property "Reference" "L19"
			(at 0 0 0)
			(layer "B.SilkS")
			(hide yes)
			(effects
				(font
					(size 1.27 1.27)
				)
				(justify mirror)
			)
		)
		(property "Value" "MPZ2012S601AT-GP"
			(at 0 -4.2418 180)
			(unlocked yes)
			(layer "B.Fab")
			(hide yes)
			(effects
				(font
					(size 1.016 1.016)
					(thickness 0.1524)
				)
				(justify mirror)
			)
		)
		(property "Device Type" "L805H42"
			(at 0 -5.7912 180)
			(unlocked yes)
			(layer "B.Fab")
			(hide yes)
			(effects
				(font
					(size 1.016 1.016)
					(thickness 0.1524)
				)
				(justify mirror)
			)
		)
		(duplicate_pad_numbers_are_jumpers no)
		(fp_line
			(start 0.889 1.7018)
			(end 0.889 -1.7018)
			(stroke
				(width 0.1524)
				(type default)
			)
			(layer "B.SilkS")
		)
		(fp_line
			(start 0.889 -1.7018)
			(end -0.889 -1.7018)
			(stroke
				(width 0.1524)
				(type default)
			)
			(layer "B.SilkS")
		)
		(fp_line
			(start -0.889 1.7018)
			(end 0.889 1.7018)
			(stroke
				(width 0.1524)
				(type default)
			)
			(layer "B.SilkS")
		)
		(fp_line
			(start -0.889 -1.7018)
			(end -0.889 1.7018)
			(stroke
				(width 0.1524)
				(type default)
			)
			(layer "B.SilkS")
		)
		(fp_rect
			(start 0.9652 1.778)
			(end -0.9652 -1.778)
			(stroke
				(width 0)
				(type default)
			)
			(fill no)
			(layer "B.CrtYd")
		)
		(fp_rect
			(start 0.9652 1.778)
			(end -0.9652 -1.778)
			(stroke
				(width 0)
				(type default)
			)
			(fill no)
			(layer "B.Fab")
		)
		(pad "1" smd rect
			(at 0 -0.9652)
			(size 1.397 1.143)
			(layers "B.Cu" "B.Mask" "B.Paste")
			(net "HM40ADC_VDDA")
		)
		(pad "2" smd rect
			(at 0 0.9652)
			(size 1.397 1.143)
			(layers "B.Cu" "B.Mask" "B.Paste")
			(net "P1V8_C")
		)
	)
	(footprint ""
		(layer "B.Cu")
		(at 110.363 -44.2214 180)
		(property "Reference" "C70"
			(at 0 0 0)
			(layer "B.SilkS")
			(hide yes)
			(effects
				(font
					(size 1.27 1.27)
				)
				(justify mirror)
			)
		)
		(property "Value" "SCD01U16V1KX-GP"
			(at 2.8321 -1.7399 180)
			(unlocked yes)
			(layer "B.Fab")
			(hide yes)
			(effects
				(font
					(size 1.016 1.016)
					(thickness 0.1524)
				)
				(justify mirror)
			)
		)
		(property "Device Type" "C0201H13"
			(at 2.8321 -3.2639 180)
			(unlocked yes)
			(layer "B.Fab")
			(hide yes)
			(effects
				(font
					(size 1.016 1.016)
					(thickness 0.1524)
				)
				(justify mirror)
			)
		)
		(duplicate_pad_numbers_are_jumpers no)
		(fp_rect
			(start 0.2794 0.6477)
			(end -0.2794 -0.6477)
			(stroke
				(width 0)
				(type default)
			)
			(fill no)
			(layer "B.CrtYd")
		)
		(fp_rect
			(start 0.2794 0.6477)
			(end -0.2794 -0.6477)
			(stroke
				(width 0)
				(type default)
			)
			(fill no)
			(layer "B.Fab")
		)
		(pad "1" smd custom
			(at 0 -0.2794)
			(size 0.0762 0.0762)
			(layers "B.Cu" "B.Mask" "B.Paste")
			(net "PHY_DPB_TO_SCC_25_DN")
			(options
				(clearance outline)
				(anchor circle)
			)
			(primitives
				(gr_poly
					(pts
						(arc
							(start 0.1524 0.127)
							(mid 0.137521 0.162921)
							(end 0.1016 0.1778)
						)
						(arc
							(start -0.1016 0.1778)
							(mid -0.137521 0.162921)
							(end -0.1524 0.127)
						)
						(arc
							(start -0.1524 -0.127)
							(mid -0.137521 -0.162921)
							(end -0.1016 -0.1778)
						)
						(arc
							(start 0.1016 -0.1778)
							(mid 0.137521 -0.162921)
							(end 0.1524 -0.127)
						)
					)
					(width 0)
					(fill yes)
				)
			)
		)
		(pad "2" smd custom
			(at 0 0.2794)
			(size 0.0762 0.0762)
			(layers "B.Cu" "B.Mask" "B.Paste")
			(net "PHY_DPB_TO_SCC_C_25_DN")
			(options
				(clearance outline)
				(anchor circle)
			)
			(primitives
				(gr_poly
					(pts
						(arc
							(start 0.1524 0.127)
							(mid 0.137521 0.162921)
							(end 0.1016 0.1778)
						)
						(arc
							(start -0.1016 0.1778)
							(mid -0.137521 0.162921)
							(end -0.1524 0.127)
						)
						(arc
							(start -0.1524 -0.127)
							(mid -0.137521 -0.162921)
							(end -0.1016 -0.1778)
						)
						(arc
							(start 0.1016 -0.1778)
							(mid 0.137521 -0.162921)
							(end 0.1524 -0.127)
						)
					)
					(width 0)
					(fill yes)
				)
			)
		)
	)
	(footprint ""
		(layer "B.Cu")
		(at 179.438808 -38.66769 90)
		(property "Reference" "C420"
			(at 0 0 90)
			(layer "B.SilkS")
			(hide yes)
			(effects
				(font
					(size 1.27 1.27)
				)
				(justify mirror)
			)
		)
		(property "Value" "SCD1U6D3V1KX-GP"
			(at 2.8321 -1.7399 90)
			(unlocked yes)
			(layer "B.Fab")
			(hide yes)
			(effects
				(font
					(size 1.016 1.016)
					(thickness 0.1524)
				)
				(justify mirror)
			)
		)
		(property "Device Type" "C0201H13"
			(at 2.8321 -3.2639 90)
			(unlocked yes)
			(layer "B.Fab")
			(hide yes)
			(effects
				(font
					(size 1.016 1.016)
					(thickness 0.1524)
				)
				(justify mirror)
			)
		)
		(duplicate_pad_numbers_are_jumpers no)
		(fp_rect
			(start 0.2794 0.6477)
			(end -0.2794 -0.6477)
			(stroke
				(width 0)
				(type default)
			)
			(fill no)
			(layer "B.CrtYd")
		)
		(fp_rect
			(start 0.2794 0.6477)
			(end -0.2794 -0.6477)
			(stroke
				(width 0)
				(type default)
			)
			(fill no)
			(layer "B.Fab")
		)
		(pad "1" smd custom
			(at 0 -0.2794 270)
			(size 0.0762 0.0762)
			(layers "B.Cu" "B.Mask" "B.Paste")
			(net "P0V975")
			(options
				(clearance outline)
				(anchor circle)
			)
			(primitives
				(gr_poly
					(pts
						(arc
							(start 0.1524 0.127)
							(mid 0.137521 0.162921)
							(end 0.1016 0.1778)
						)
						(arc
							(start -0.1016 0.1778)
							(mid -0.137521 0.162921)
							(end -0.1524 0.127)
						)
						(arc
							(start -0.1524 -0.127)
							(mid -0.137521 -0.162921)
							(end -0.1016 -0.1778)
						)
						(arc
							(start 0.1016 -0.1778)
							(mid 0.137521 -0.162921)
							(end 0.1524 -0.127)
						)
					)
					(width 0)
					(fill yes)
				)
			)
		)
		(pad "2" smd custom
			(at 0 0.2794 270)
			(size 0.0762 0.0762)
			(layers "B.Cu" "B.Mask" "B.Paste")
			(net "GND")
			(options
				(clearance outline)
				(anchor circle)
			)
			(primitives
				(gr_poly
					(pts
						(arc
							(start 0.1524 0.127)
							(mid 0.137521 0.162921)
							(end 0.1016 0.1778)
						)
						(arc
							(start -0.1016 0.1778)
							(mid -0.137521 0.162921)
							(end -0.1524 0.127)
						)
						(arc
							(start -0.1524 -0.127)
							(mid -0.137521 -0.162921)
							(end -0.1016 -0.1778)
						)
						(arc
							(start 0.1016 -0.1778)
							(mid 0.137521 -0.162921)
							(end 0.1524 -0.127)
						)
					)
					(width 0)
					(fill yes)
				)
			)
		)
	)
	(footprint ""
		(layer "B.Cu")
		(at 73.66 -51.689 180)
		(property "Reference" "C241"
			(at 0 0 0)
			(layer "B.SilkS")
			(hide yes)
			(effects
				(font
					(size 1.27 1.27)
				)
				(justify mirror)
			)
		)
		(property "Value" "SC100U6D3V6MX-GP"
			(at 0.0762 -5.1308 180)
			(unlocked yes)
			(layer "B.Fab")
			(hide yes)
			(effects
				(font
					(size 1.016 1.016)
					(thickness 0.1524)
				)
				(justify mirror)
			)
		)
		(property "Device Type" "C1206H71"
			(at 0.127 -6.6548 180)
			(unlocked yes)
			(layer "B.Fab")
			(hide yes)
			(effects
				(font
					(size 1.016 1.016)
					(thickness 0.1524)
				)
				(justify mirror)
			)
		)
		(duplicate_pad_numbers_are_jumpers no)
		(fp_line
			(start 1.016 2.2352)
			(end 1.016 0.8382)
			(stroke
				(width 0.1524)
				(type default)
			)
			(layer "B.SilkS")
		)
		(fp_line
			(start 1.016 -0.8382)
			(end 1.016 -2.2352)
			(stroke
				(width 0.1524)
				(type default)
			)
			(layer "B.SilkS")
		)
		(fp_line
			(start 1.016 -2.2352)
			(end -1.016 -2.2352)
			(stroke
				(width 0.1524)
				(type default)
			)
			(layer "B.SilkS")
		)
		(fp_line
			(start -1.016 2.2352)
			(end 1.016 2.2352)
			(stroke
				(width 0.1524)
				(type default)
			)
			(layer "B.SilkS")
		)
		(fp_line
			(start -1.016 0.8382)
			(end -1.016 2.2352)
			(stroke
				(width 0.1524)
				(type default)
			)
			(layer "B.SilkS")
		)
		(fp_line
			(start -1.016 -2.2352)
			(end -1.016 -0.8382)
			(stroke
				(width 0.1524)
				(type default)
			)
			(layer "B.SilkS")
		)
		(fp_rect
			(start 1.0922 2.3114)
			(end -1.0922 -2.3114)
			(stroke
				(width 0)
				(type default)
			)
			(fill no)
			(layer "B.CrtYd")
		)
		(fp_poly
			(pts
				(xy -1.0922 -2.3114) (xy -1.0922 2.3114) (xy 1.0922 2.3114) (xy 1.0922 -2.3114)
			)
			(stroke
				(width 0)
				(type default)
			)
			(fill no)
			(layer "B.Fab")
		)
		(pad "1" smd rect
			(at 0 -1.397)
			(size 1.651 1.27)
			(layers "B.Cu" "B.Mask" "B.Paste")
			(net "GB_VDDA")
		)
		(pad "2" smd rect
			(at 0 1.397)
			(size 1.651 1.27)
			(layers "B.Cu" "B.Mask" "B.Paste")
			(net "GND")
		)
	)
	(footprint ""
		(layer "B.Cu")
		(at 136.1948 -77.4954 -90)
		(property "Reference" "C5"
			(at 0 0 90)
			(layer "B.SilkS")
			(hide yes)
			(effects
				(font
					(size 1.27 1.27)
				)
				(justify mirror)
			)
		)
		(property "Value" "SCD01U16V1KX-GP"
			(at 2.8321 -1.7399 270)
			(unlocked yes)
			(layer "B.Fab")
			(hide yes)
			(effects
				(font
					(size 1.016 1.016)
					(thickness 0.1524)
				)
				(justify mirror)
			)
		)
		(property "Device Type" "C0201H13"
			(at 2.8321 -3.2639 270)
			(unlocked yes)
			(layer "B.Fab")
			(hide yes)
			(effects
				(font
					(size 1.016 1.016)
					(thickness 0.1524)
				)
				(justify mirror)
			)
		)
		(duplicate_pad_numbers_are_jumpers no)
		(fp_rect
			(start 0.2794 0.6477)
			(end -0.2794 -0.6477)
			(stroke
				(width 0)
				(type default)
			)
			(fill no)
			(layer "B.CrtYd")
		)
		(fp_rect
			(start 0.2794 0.6477)
			(end -0.2794 -0.6477)
			(stroke
				(width 0)
				(type default)
			)
			(fill no)
			(layer "B.Fab")
		)
		(pad "1" smd custom
			(at 0 -0.2794 90)
			(size 0.0762 0.0762)
			(layers "B.Cu" "B.Mask" "B.Paste")
			(net "PHY_CONN_TO_EXP_9_DP")
			(options
				(clearance outline)
				(anchor circle)
			)
			(primitives
				(gr_poly
					(pts
						(arc
							(start 0.1524 0.127)
							(mid 0.137521 0.162921)
							(end 0.1016 0.1778)
						)
						(arc
							(start -0.1016 0.1778)
							(mid -0.137521 0.162921)
							(end -0.1524 0.127)
						)
						(arc
							(start -0.1524 -0.127)
							(mid -0.137521 -0.162921)
							(end -0.1016 -0.1778)
						)
						(arc
							(start 0.1016 -0.1778)
							(mid 0.137521 -0.162921)
							(end 0.1524 -0.127)
						)
					)
					(width 0)
					(fill yes)
				)
			)
		)
		(pad "2" smd custom
			(at 0 0.2794 90)
			(size 0.0762 0.0762)
			(layers "B.Cu" "B.Mask" "B.Paste")
			(net "PHY_CONN_TO_EXP_C_9_DP")
			(options
				(clearance outline)
				(anchor circle)
			)
			(primitives
				(gr_poly
					(pts
						(arc
							(start 0.1524 0.127)
							(mid 0.137521 0.162921)
							(end 0.1016 0.1778)
						)
						(arc
							(start -0.1016 0.1778)
							(mid -0.137521 0.162921)
							(end -0.1524 0.127)
						)
						(arc
							(start -0.1524 -0.127)
							(mid -0.137521 -0.162921)
							(end -0.1016 -0.1778)
						)
						(arc
							(start 0.1016 -0.1778)
							(mid 0.137521 -0.162921)
							(end 0.1524 -0.127)
						)
					)
					(width 0)
					(fill yes)
				)
			)
		)
	)
	(footprint ""
		(layer "B.Cu")
		(at 203.073 -24.638)
		(property "Reference" "Q4"
			(at 0 0 0)
			(layer "B.SilkS")
			(hide yes)
			(effects
				(font
					(size 1.27 1.27)
				)
				(justify mirror)
			)
		)
		(property "Value" "SSM3K324R-GP"
			(at -0.127 -8.9662 0)
			(unlocked yes)
			(layer "B.Fab")
			(hide yes)
			(effects
				(font
					(size 1.016 1.016)
					(thickness 0.1524)
				)
				(justify mirror)
			)
		)
		(property "Device Type" "SOT23DGS2D4H35"
			(at -0.127 -10.4902 0)
			(unlocked yes)
			(layer "B.Fab")
			(hide yes)
			(effects
				(font
					(size 1.016 1.016)
					(thickness 0.1524)
				)
				(justify mirror)
			)
		)
		(duplicate_pad_numbers_are_jumpers no)
		(fp_line
			(start -1.651 -1.778)
			(end 1.651 -1.778)
			(stroke
				(width 0.1524)
				(type default)
			)
			(layer "B.SilkS")
		)
		(fp_line
			(start -1.651 1.778)
			(end -1.651 -1.778)
			(stroke
				(width 0.1524)
				(type default)
			)
			(layer "B.SilkS")
		)
		(fp_line
			(start 1.651 -1.778)
			(end 1.651 1.778)
			(stroke
				(width 0.1524)
				(type default)
			)
			(layer "B.SilkS")
		)
		(fp_line
			(start 1.651 1.778)
			(end -1.651 1.778)
			(stroke
				(width 0.1524)
				(type default)
			)
			(layer "B.SilkS")
		)
		(fp_poly
			(pts
				(xy 1.778 1.8796) (xy 1.778 -1.8796) (xy -1.778 -1.8796) (xy -1.778 1.8796)
			)
			(stroke
				(width 0)
				(type default)
			)
			(fill no)
			(layer "B.CrtYd")
		)
		(fp_poly
			(pts
				(xy 1.778 1.8796) (xy 1.778 -1.8796) (xy -1.778 -1.8796) (xy -1.778 1.8796)
			)
			(stroke
				(width 0)
				(type default)
			)
			(fill no)
			(layer "B.Fab")
		)
		(pad "D" smd custom
			(at 0 -0.9525 180)
			(size 0.1905 0.1905)
			(layers "B.Cu" "B.Mask" "B.Paste")
			(net "SYS_ERROR_LED_D")
			(options
				(clearance outline)
				(anchor circle)
			)
			(primitives
				(gr_poly
					(pts
						(arc
							(start -0.1778 -0.5715)
							(mid -0.321484 -0.511984)
							(end -0.381 -0.3683)
						)
						(arc
							(start -0.381 0.3683)
							(mid -0.321484 0.511984)
							(end -0.1778 0.5715)
						)
						(arc
							(start 0.1778 0.5715)
							(mid 0.321484 0.511984)
							(end 0.381 0.3683)
						)
						(arc
							(start 0.381 -0.3683)
							(mid 0.321484 -0.511984)
							(end 0.1778 -0.5715)
						)
					)
					(width 0)
					(fill yes)
				)
			)
		)
		(pad "G" smd custom
			(at 0.98425 0.9525 180)
			(size 0.1905 0.1905)
			(layers "B.Cu" "B.Mask" "B.Paste")
			(net "SYS_ERR_0")
			(options
				(clearance outline)
				(anchor circle)
			)
			(primitives
				(gr_poly
					(pts
						(arc
							(start -0.1778 -0.5715)
							(mid -0.321484 -0.511984)
							(end -0.381 -0.3683)
						)
						(arc
							(start -0.381 0.3683)
							(mid -0.321484 0.511984)
							(end -0.1778 0.5715)
						)
						(arc
							(start 0.1778 0.5715)
							(mid 0.321484 0.511984)
							(end 0.381 0.3683)
						)
						(arc
							(start 0.381 -0.3683)
							(mid 0.321484 -0.511984)
							(end 0.1778 -0.5715)
						)
					)
					(width 0)
					(fill yes)
				)
			)
		)
		(pad "S" smd custom
			(at -0.98425 0.9525 180)
			(size 0.1905 0.1905)
			(layers "B.Cu" "B.Mask" "B.Paste")
			(net "GND")
			(options
				(clearance outline)
				(anchor circle)
			)
			(primitives
				(gr_poly
					(pts
						(arc
							(start -0.1778 -0.5715)
							(mid -0.321484 -0.511984)
							(end -0.381 -0.3683)
						)
						(arc
							(start -0.381 0.3683)
							(mid -0.321484 0.511984)
							(end -0.1778 0.5715)
						)
						(arc
							(start 0.1778 0.5715)
							(mid 0.321484 0.511984)
							(end 0.381 0.3683)
						)
						(arc
							(start 0.381 -0.3683)
							(mid 0.321484 -0.511984)
							(end 0.1778 -0.5715)
						)
					)
					(width 0)
					(fill yes)
				)
			)
		)
	)
	(footprint ""
		(layer "B.Cu")
		(at 118.27256 -74.618088 180)
		(property "Reference" "C122"
			(at 0 0 0)
			(layer "B.SilkS")
			(hide yes)
			(effects
				(font
					(size 1.27 1.27)
				)
				(justify mirror)
			)
		)
		(property "Value" "SC10U6D3V2MX-GP-U"
			(at 1.524 -1.905 180)
			(unlocked yes)
			(layer "B.Fab")
			(hide yes)
			(effects
				(font
					(size 1.016 1.016)
					(thickness 0.1524)
				)
				(justify mirror)
			)
		)
		(property "Device Type" "C402-TO0D2H28"
			(at 1.524 -3.429 180)
			(unlocked yes)
			(layer "B.Fab")
			(hide yes)
			(effects
				(font
					(size 1.016 1.016)
					(thickness 0.1524)
				)
				(justify mirror)
			)
		)
		(duplicate_pad_numbers_are_jumpers no)
		(fp_rect
			(start 0.4826 0.889)
			(end -0.4826 -0.889)
			(stroke
				(width 0)
				(type default)
			)
			(fill no)
			(layer "B.CrtYd")
		)
		(fp_rect
			(start 0.4826 0.889)
			(end -0.4826 -0.889)
			(stroke
				(width 0)
				(type default)
			)
			(fill no)
			(layer "B.Fab")
		)
		(pad "1" smd custom
			(at 0 -0.4572)
			(size 0.1524 0.1524)
			(layers "B.Cu" "B.Mask" "B.Paste")
			(net "P1V8_E")
			(options
				(clearance outline)
				(anchor circle)
			)
			(primitives
				(gr_poly
					(pts
						(arc
							(start -0.254 -0.3048)
							(mid -0.325842 -0.275042)
							(end -0.3556 -0.2032)
						)
						(arc
							(start -0.3556 0.2032)
							(mid -0.325842 0.275042)
							(end -0.254 0.3048)
						)
						(arc
							(start 0.254 0.3048)
							(mid 0.325842 0.275042)
							(end 0.3556 0.2032)
						)
						(arc
							(start 0.3556 -0.2032)
							(mid 0.325842 -0.275042)
							(end 0.254 -0.3048)
						)
					)
					(width 0)
					(fill yes)
				)
			)
		)
		(pad "2" smd custom
			(at 0 0.4572)
			(size 0.1524 0.1524)
			(layers "B.Cu" "B.Mask" "B.Paste")
			(net "GND")
			(options
				(clearance outline)
				(anchor circle)
			)
			(primitives
				(gr_poly
					(pts
						(arc
							(start -0.254 -0.3048)
							(mid -0.325842 -0.275042)
							(end -0.3556 -0.2032)
						)
						(arc
							(start -0.3556 0.2032)
							(mid -0.325842 0.275042)
							(end -0.254 0.3048)
						)
						(arc
							(start 0.254 0.3048)
							(mid 0.325842 0.275042)
							(end 0.3556 0.2032)
						)
						(arc
							(start 0.3556 -0.2032)
							(mid 0.325842 -0.275042)
							(end 0.254 -0.3048)
						)
					)
					(width 0)
					(fill yes)
				)
			)
		)
	)
	(footprint ""
		(layer "B.Cu")
		(at 166.88943 -46.754542)
		(property "Reference" "C452"
			(at 0 0 0)
			(layer "B.SilkS")
			(hide yes)
			(effects
				(font
					(size 1.27 1.27)
				)
				(justify mirror)
			)
		)
		(property "Value" "SCD1U6D3V1KX-GP"
			(at 2.8321 -1.7399 0)
			(unlocked yes)
			(layer "B.Fab")
			(hide yes)
			(effects
				(font
					(size 1.016 1.016)
					(thickness 0.1524)
				)
				(justify mirror)
			)
		)
		(property "Device Type" "C0201H13"
			(at 2.8321 -3.2639 0)
			(unlocked yes)
			(layer "B.Fab")
			(hide yes)
			(effects
				(font
					(size 1.016 1.016)
					(thickness 0.1524)
				)
				(justify mirror)
			)
		)
		(duplicate_pad_numbers_are_jumpers no)
		(fp_rect
			(start 0.2794 0.6477)
			(end -0.2794 -0.6477)
			(stroke
				(width 0)
				(type default)
			)
			(fill no)
			(layer "B.CrtYd")
		)
		(fp_rect
			(start 0.2794 0.6477)
			(end -0.2794 -0.6477)
			(stroke
				(width 0)
				(type default)
			)
			(fill no)
			(layer "B.Fab")
		)
		(pad "1" smd custom
			(at 0 -0.2794 180)
			(size 0.0762 0.0762)
			(layers "B.Cu" "B.Mask" "B.Paste")
			(net "P1V8_C")
			(options
				(clearance outline)
				(anchor circle)
			)
			(primitives
				(gr_poly
					(pts
						(arc
							(start 0.1524 0.127)
							(mid 0.137521 0.162921)
							(end 0.1016 0.1778)
						)
						(arc
							(start -0.1016 0.1778)
							(mid -0.137521 0.162921)
							(end -0.1524 0.127)
						)
						(arc
							(start -0.1524 -0.127)
							(mid -0.137521 -0.162921)
							(end -0.1016 -0.1778)
						)
						(arc
							(start 0.1016 -0.1778)
							(mid 0.137521 -0.162921)
							(end 0.1524 -0.127)
						)
					)
					(width 0)
					(fill yes)
				)
			)
		)
		(pad "2" smd custom
			(at 0 0.2794 180)
			(size 0.0762 0.0762)
			(layers "B.Cu" "B.Mask" "B.Paste")
			(net "GND")
			(options
				(clearance outline)
				(anchor circle)
			)
			(primitives
				(gr_poly
					(pts
						(arc
							(start 0.1524 0.127)
							(mid 0.137521 0.162921)
							(end 0.1016 0.1778)
						)
						(arc
							(start -0.1016 0.1778)
							(mid -0.137521 0.162921)
							(end -0.1524 0.127)
						)
						(arc
							(start -0.1524 -0.127)
							(mid -0.137521 -0.162921)
							(end -0.1016 -0.1778)
						)
						(arc
							(start 0.1016 -0.1778)
							(mid 0.137521 -0.162921)
							(end 0.1524 -0.127)
						)
					)
					(width 0)
					(fill yes)
				)
			)
		)
	)
	(footprint ""
		(layer "B.Cu")
		(at 73.025 -73.152 180)
		(property "Reference" "R287"
			(at 0 0 0)
			(layer "B.SilkS")
			(hide yes)
			(effects
				(font
					(size 1.27 1.27)
				)
				(justify mirror)
			)
		)
		(property "Value" "10KR2F-2-GP"
			(at -0.064008 -3.993896 180)
			(unlocked yes)
			(layer "B.Fab")
			(hide yes)
			(effects
				(font
					(size 1.016 1.016)
					(thickness 0.1524)
				)
				(justify mirror)
			)
		)
		(property "Device Type" "R402H16"
			(at -0.064008 -5.517896 180)
			(unlocked yes)
			(layer "B.Fab")
			(hide yes)
			(effects
				(font
					(size 1.016 1.016)
					(thickness 0.1524)
				)
				(justify mirror)
			)
		)
		(duplicate_pad_numbers_are_jumpers no)
		(fp_line
			(start 0.508 -0.9398)
			(end 0.508 0.9398)
			(stroke
				(width 0.1524)
				(type default)
			)
			(layer "B.SilkS")
		)
		(fp_line
			(start -0.508 -0.9398)
			(end 0.508 -0.9398)
			(stroke
				(width 0.1524)
				(type default)
			)
			(layer "B.SilkS")
		)
		(fp_rect
			(start 0.508 0.9398)
			(end -0.508 -0.9398)
			(stroke
				(width 0)
				(type default)
			)
			(fill no)
			(layer "B.CrtYd")
		)
		(fp_rect
			(start 0.508 0.9398)
			(end -0.508 -0.9398)
			(stroke
				(width 0)
				(type default)
			)
			(fill no)
			(layer "B.Fab")
		)
		(pad "1" smd custom
			(at 0 -0.4445)
			(size 0.1397 0.1397)
			(layers "B.Cu" "B.Mask" "B.Paste")
			(net "EXP_BYTE_N")
			(options
				(clearance outline)
				(anchor circle)
			)
			(primitives
				(gr_poly
					(pts
						(arc
							(start -0.1778 0.2794)
							(mid -0.249642 0.249642)
							(end -0.2794 0.1778)
						)
						(arc
							(start -0.2794 -0.1778)
							(mid -0.249642 -0.249642)
							(end -0.1778 -0.2794)
						)
						(arc
							(start 0.1778 -0.2794)
							(mid 0.249642 -0.249642)
							(end 0.2794 -0.1778)
						)
						(arc
							(start 0.2794 0.1778)
							(mid 0.249642 0.249642)
							(end 0.1778 0.2794)
						)
					)
					(width 0)
					(fill yes)
				)
			)
		)
		(pad "2" smd custom
			(at 0 0.4445)
			(size 0.1397 0.1397)
			(layers "B.Cu" "B.Mask" "B.Paste")
			(net "GND")
			(options
				(clearance outline)
				(anchor circle)
			)
			(primitives
				(gr_poly
					(pts
						(arc
							(start -0.1778 0.2794)
							(mid -0.249642 0.249642)
							(end -0.2794 0.1778)
						)
						(arc
							(start -0.2794 -0.1778)
							(mid -0.249642 -0.249642)
							(end -0.1778 -0.2794)
						)
						(arc
							(start 0.1778 -0.2794)
							(mid 0.249642 -0.249642)
							(end 0.2794 -0.1778)
						)
						(arc
							(start 0.2794 0.1778)
							(mid 0.249642 0.249642)
							(end 0.1778 0.2794)
						)
					)
					(width 0)
					(fill yes)
				)
			)
		)
	)
	(footprint ""
		(layer "B.Cu")
		(at 70.485 -60.833 90)
		(property "Reference" "L8"
			(at 0 0 90)
			(layer "B.SilkS")
			(hide yes)
			(effects
				(font
					(size 1.27 1.27)
				)
				(justify mirror)
			)
		)
		(property "Value" "MPZ2012S300AT-GP"
			(at 0 -4.2418 90)
			(unlocked yes)
			(layer "B.Fab")
			(hide yes)
			(effects
				(font
					(size 1.016 1.016)
					(thickness 0.1524)
				)
				(justify mirror)
			)
		)
		(property "Device Type" "L805H42"
			(at 0 -5.7912 90)
			(unlocked yes)
			(layer "B.Fab")
			(hide yes)
			(effects
				(font
					(size 1.016 1.016)
					(thickness 0.1524)
				)
				(justify mirror)
			)
		)
		(duplicate_pad_numbers_are_jumpers no)
		(fp_line
			(start 0.889 -1.7018)
			(end -0.889 -1.7018)
			(stroke
				(width 0.1524)
				(type default)
			)
			(layer "B.SilkS")
		)
		(fp_line
			(start -0.889 -1.7018)
			(end -0.889 1.7018)
			(stroke
				(width 0.1524)
				(type default)
			)
			(layer "B.SilkS")
		)
		(fp_line
			(start 0.889 1.7018)
			(end 0.889 -1.7018)
			(stroke
				(width 0.1524)
				(type default)
			)
			(layer "B.SilkS")
		)
		(fp_line
			(start -0.889 1.7018)
			(end 0.889 1.7018)
			(stroke
				(width 0.1524)
				(type default)
			)
			(layer "B.SilkS")
		)
		(fp_rect
			(start 0.9652 1.778)
			(end -0.9652 -1.778)
			(stroke
				(width 0)
				(type default)
			)
			(fill no)
			(layer "B.CrtYd")
		)
		(fp_rect
			(start 0.9652 1.778)
			(end -0.9652 -1.778)
			(stroke
				(width 0)
				(type default)
			)
			(fill no)
			(layer "B.Fab")
		)
		(pad "1" smd rect
			(at 0 -0.9652 270)
			(size 1.397 1.143)
			(layers "B.Cu" "B.Mask" "B.Paste")
			(net "P0V9")
		)
		(pad "2" smd rect
			(at 0 0.9652 270)
			(size 1.397 1.143)
			(layers "B.Cu" "B.Mask" "B.Paste")
			(net "GB_VDDA")
		)
	)
	(footprint ""
		(layer "B.Cu")
		(at 188.8236 -35.3314 90)
		(property "Reference" "TP96"
			(at 0 0 90)
			(layer "B.SilkS")
			(hide yes)
			(effects
				(font
					(size 1.27 1.27)
				)
				(justify mirror)
			)
		)
		(property "Value" "TPAD28-2-GP"
			(at 0.0127 -1.6637 90)
			(unlocked yes)
			(layer "B.Fab")
			(hide yes)
			(effects
				(font
					(size 1.016 1.016)
					(thickness 0.1524)
				)
				(justify mirror)
			)
		)
		(property "Device Type" "TPAD28"
			(at 0.0127 -3.1877 90)
			(unlocked yes)
			(layer "B.Fab")
			(hide yes)
			(effects
				(font
					(size 1.016 1.016)
					(thickness 0.1524)
				)
				(justify mirror)
			)
		)
		(duplicate_pad_numbers_are_jumpers no)
		(fp_poly
			(pts
				(arc
					(start 0 0.3556)
					(mid 0 -0.3556)
					(end 0 0.3556)
				)
			)
			(stroke
				(width 0)
				(type default)
			)
			(fill no)
			(layer "B.CrtYd")
		)
		(fp_poly
			(pts
				(arc
					(start 0 0.6096)
					(mid 0 -0.6096)
					(end 0 0.6096)
				)
			)
			(stroke
				(width 0)
				(type default)
			)
			(fill no)
			(layer "B.Fab")
		)
		(pad "1" smd circle
			(at 0 0 270)
			(size 0.7112 0.7112)
			(layers "B.Cu" "B.Mask" "B.Paste")
			(net "IOC_GPIO_35")
		)
	)
	(footprint ""
		(layer "B.Cu")
		(at 137.4648 -69.342 -90)
		(property "Reference" "C16"
			(at 0 0 90)
			(layer "B.SilkS")
			(hide yes)
			(effects
				(font
					(size 1.27 1.27)
				)
				(justify mirror)
			)
		)
		(property "Value" "SCD01U16V1KX-GP"
			(at 2.8321 -1.7399 270)
			(unlocked yes)
			(layer "B.Fab")
			(hide yes)
			(effects
				(font
					(size 1.016 1.016)
					(thickness 0.1524)
				)
				(justify mirror)
			)
		)
		(property "Device Type" "C0201H13"
			(at 2.8321 -3.2639 270)
			(unlocked yes)
			(layer "B.Fab")
			(hide yes)
			(effects
				(font
					(size 1.016 1.016)
					(thickness 0.1524)
				)
				(justify mirror)
			)
		)
		(duplicate_pad_numbers_are_jumpers no)
		(fp_rect
			(start 0.2794 0.6477)
			(end -0.2794 -0.6477)
			(stroke
				(width 0)
				(type default)
			)
			(fill no)
			(layer "B.CrtYd")
		)
		(fp_rect
			(start 0.2794 0.6477)
			(end -0.2794 -0.6477)
			(stroke
				(width 0)
				(type default)
			)
			(fill no)
			(layer "B.Fab")
		)
		(pad "1" smd custom
			(at 0 -0.2794 90)
			(size 0.0762 0.0762)
			(layers "B.Cu" "B.Mask" "B.Paste")
			(net "PHY_DPB_TO_SCC_4_DN")
			(options
				(clearance outline)
				(anchor circle)
			)
			(primitives
				(gr_poly
					(pts
						(arc
							(start 0.1524 0.127)
							(mid 0.137521 0.162921)
							(end 0.1016 0.1778)
						)
						(arc
							(start -0.1016 0.1778)
							(mid -0.137521 0.162921)
							(end -0.1524 0.127)
						)
						(arc
							(start -0.1524 -0.127)
							(mid -0.137521 -0.162921)
							(end -0.1016 -0.1778)
						)
						(arc
							(start 0.1016 -0.1778)
							(mid 0.137521 -0.162921)
							(end 0.1524 -0.127)
						)
					)
					(width 0)
					(fill yes)
				)
			)
		)
		(pad "2" smd custom
			(at 0 0.2794 90)
			(size 0.0762 0.0762)
			(layers "B.Cu" "B.Mask" "B.Paste")
			(net "PHY_DPB_TO_SCC_C_4_DN")
			(options
				(clearance outline)
				(anchor circle)
			)
			(primitives
				(gr_poly
					(pts
						(arc
							(start 0.1524 0.127)
							(mid 0.137521 0.162921)
							(end 0.1016 0.1778)
						)
						(arc
							(start -0.1016 0.1778)
							(mid -0.137521 0.162921)
							(end -0.1524 0.127)
						)
						(arc
							(start -0.1524 -0.127)
							(mid -0.137521 -0.162921)
							(end -0.1016 -0.1778)
						)
						(arc
							(start 0.1016 -0.1778)
							(mid 0.137521 -0.162921)
							(end 0.1524 -0.127)
						)
					)
					(width 0)
					(fill yes)
				)
			)
		)
	)
	(footprint ""
		(layer "B.Cu")
		(at 166.751 -64.008 90)
		(property "Reference" "C351"
			(at 0 0 90)
			(layer "B.SilkS")
			(hide yes)
			(effects
				(font
					(size 1.27 1.27)
				)
				(justify mirror)
			)
		)
		(property "Value" "SC22U6D3V3MX-9-GP-U"
			(at 0 -2.8194 90)
			(unlocked yes)
			(layer "B.Fab")
			(hide yes)
			(effects
				(font
					(size 1.016 1.016)
					(thickness 0.1524)
				)
				(justify mirror)
			)
		)
		(property "Device Type" "C603H40"
			(at 0 -4.3434 90)
			(unlocked yes)
			(layer "B.Fab")
			(hide yes)
			(effects
				(font
					(size 1.016 1.016)
					(thickness 0.1524)
				)
				(justify mirror)
			)
		)
		(duplicate_pad_numbers_are_jumpers no)
		(fp_line
			(start -0.508 0)
			(end 0.508 0)
			(stroke
				(width 0.2032)
				(type default)
			)
			(layer "B.SilkS")
		)
		(fp_rect
			(start 0.5842 1.3335)
			(end -0.5842 -1.3335)
			(stroke
				(width 0)
				(type default)
			)
			(fill no)
			(layer "B.CrtYd")
		)
		(fp_rect
			(start 0.5842 1.3335)
			(end -0.5842 -1.3335)
			(stroke
				(width 0)
				(type default)
			)
			(fill no)
			(layer "B.Fab")
		)
		(pad "1" smd custom
			(at 0 -0.762 270)
			(size 0.2159 0.2159)
			(layers "B.Cu" "B.Mask" "B.Paste")
			(net "HM40ADC_VDDA")
			(options
				(clearance outline)
				(anchor circle)
			)
			(primitives
				(gr_poly
					(pts
						(arc
							(start -0.3302 0.4318)
							(mid -0.402042 0.402042)
							(end -0.4318 0.3302)
						)
						(arc
							(start -0.4318 -0.3302)
							(mid -0.402042 -0.402042)
							(end -0.3302 -0.4318)
						)
						(arc
							(start 0.3302 -0.4318)
							(mid 0.402042 -0.402042)
							(end 0.4318 -0.3302)
						)
						(arc
							(start 0.4318 0.3302)
							(mid 0.402042 0.402042)
							(end 0.3302 0.4318)
						)
					)
					(width 0)
					(fill yes)
				)
			)
		)
		(pad "2" smd custom
			(at 0 0.762 270)
			(size 0.2159 0.2159)
			(layers "B.Cu" "B.Mask" "B.Paste")
			(net "GND")
			(options
				(clearance outline)
				(anchor circle)
			)
			(primitives
				(gr_poly
					(pts
						(arc
							(start -0.3302 0.4318)
							(mid -0.402042 0.402042)
							(end -0.4318 0.3302)
						)
						(arc
							(start -0.4318 -0.3302)
							(mid -0.402042 -0.402042)
							(end -0.3302 -0.4318)
						)
						(arc
							(start 0.3302 -0.4318)
							(mid 0.402042 -0.402042)
							(end 0.4318 -0.3302)
						)
						(arc
							(start 0.4318 0.3302)
							(mid 0.402042 0.402042)
							(end 0.3302 0.4318)
						)
					)
					(width 0)
					(fill yes)
				)
			)
		)
	)
	(footprint ""
		(layer "B.Cu")
		(at 122.4788 -64.4906 -90)
		(property "Reference" "C246"
			(at 0 0 90)
			(layer "B.SilkS")
			(hide yes)
			(effects
				(font
					(size 1.27 1.27)
				)
				(justify mirror)
			)
		)
		(property "Value" "SCD1U6D3V1KX-GP"
			(at 2.8321 -1.7399 270)
			(unlocked yes)
			(layer "B.Fab")
			(hide yes)
			(effects
				(font
					(size 1.016 1.016)
					(thickness 0.1524)
				)
				(justify mirror)
			)
		)
		(property "Device Type" "C0201H13"
			(at 2.8321 -3.2639 270)
			(unlocked yes)
			(layer "B.Fab")
			(hide yes)
			(effects
				(font
					(size 1.016 1.016)
					(thickness 0.1524)
				)
				(justify mirror)
			)
		)
		(duplicate_pad_numbers_are_jumpers no)
		(fp_rect
			(start 0.2794 0.6477)
			(end -0.2794 -0.6477)
			(stroke
				(width 0)
				(type default)
			)
			(fill no)
			(layer "B.CrtYd")
		)
		(fp_rect
			(start 0.2794 0.6477)
			(end -0.2794 -0.6477)
			(stroke
				(width 0)
				(type default)
			)
			(fill no)
			(layer "B.Fab")
		)
		(pad "1" smd custom
			(at 0 -0.2794 90)
			(size 0.0762 0.0762)
			(layers "B.Cu" "B.Mask" "B.Paste")
			(net "GB_VDDA")
			(options
				(clearance outline)
				(anchor circle)
			)
			(primitives
				(gr_poly
					(pts
						(arc
							(start 0.1524 0.127)
							(mid 0.137521 0.162921)
							(end 0.1016 0.1778)
						)
						(arc
							(start -0.1016 0.1778)
							(mid -0.137521 0.162921)
							(end -0.1524 0.127)
						)
						(arc
							(start -0.1524 -0.127)
							(mid -0.137521 -0.162921)
							(end -0.1016 -0.1778)
						)
						(arc
							(start 0.1016 -0.1778)
							(mid 0.137521 -0.162921)
							(end 0.1524 -0.127)
						)
					)
					(width 0)
					(fill yes)
				)
			)
		)
		(pad "2" smd custom
			(at 0 0.2794 90)
			(size 0.0762 0.0762)
			(layers "B.Cu" "B.Mask" "B.Paste")
			(net "GND")
			(options
				(clearance outline)
				(anchor circle)
			)
			(primitives
				(gr_poly
					(pts
						(arc
							(start 0.1524 0.127)
							(mid 0.137521 0.162921)
							(end 0.1016 0.1778)
						)
						(arc
							(start -0.1016 0.1778)
							(mid -0.137521 0.162921)
							(end -0.1524 0.127)
						)
						(arc
							(start -0.1524 -0.127)
							(mid -0.137521 -0.162921)
							(end -0.1016 -0.1778)
						)
						(arc
							(start 0.1016 -0.1778)
							(mid 0.137521 -0.162921)
							(end 0.1524 -0.127)
						)
					)
					(width 0)
					(fill yes)
				)
			)
		)
	)
	(footprint ""
		(layer "B.Cu")
		(at 111.252 -61.488066)
		(property "Reference" "C224"
			(at 0 0 0)
			(layer "B.SilkS")
			(hide yes)
			(effects
				(font
					(size 1.27 1.27)
				)
				(justify mirror)
			)
		)
		(property "Value" "SCD1U16V2KX-3GP"
			(at -1.1811 -2.7051 0)
			(unlocked yes)
			(layer "B.Fab")
			(hide yes)
			(effects
				(font
					(size 1.016 1.016)
					(thickness 0.1524)
				)
				(justify mirror)
			)
		)
		(property "Device Type" "C402H22"
			(at -1.1811 -4.2291 0)
			(unlocked yes)
			(layer "B.Fab")
			(hide yes)
			(effects
				(font
					(size 1.016 1.016)
					(thickness 0.1524)
				)
				(justify mirror)
			)
		)
		(duplicate_pad_numbers_are_jumpers no)
		(fp_rect
			(start 0.4318 0.9525)
			(end -0.4318 -0.9525)
			(stroke
				(width 0)
				(type default)
			)
			(fill no)
			(layer "B.CrtYd")
		)
		(fp_rect
			(start 0.4318 0.9525)
			(end -0.4318 -0.9525)
			(stroke
				(width 0)
				(type default)
			)
			(fill no)
			(layer "B.Fab")
		)
		(pad "1" smd custom
			(at 0 -0.4445 180)
			(size 0.1524 0.1524)
			(layers "B.Cu" "B.Mask" "B.Paste")
			(net "GB_VDDH")
			(options
				(clearance outline)
				(anchor circle)
			)
			(primitives
				(gr_poly
					(pts
						(arc
							(start 0.3048 0.2032)
							(mid 0.275042 0.275042)
							(end 0.2032 0.3048)
						)
						(arc
							(start -0.2032 0.3048)
							(mid -0.275042 0.275042)
							(end -0.3048 0.2032)
						)
						(arc
							(start -0.3048 -0.2032)
							(mid -0.275042 -0.275042)
							(end -0.2032 -0.3048)
						)
						(arc
							(start 0.2032 -0.3048)
							(mid 0.275042 -0.275042)
							(end 0.3048 -0.2032)
						)
					)
					(width 0)
					(fill yes)
				)
			)
		)
		(pad "2" smd custom
			(at 0 0.4445 180)
			(size 0.1524 0.1524)
			(layers "B.Cu" "B.Mask" "B.Paste")
			(net "GND")
			(options
				(clearance outline)
				(anchor circle)
			)
			(primitives
				(gr_poly
					(pts
						(arc
							(start 0.3048 0.2032)
							(mid 0.275042 0.275042)
							(end 0.2032 0.3048)
						)
						(arc
							(start -0.2032 0.3048)
							(mid -0.275042 0.275042)
							(end -0.3048 0.2032)
						)
						(arc
							(start -0.3048 -0.2032)
							(mid -0.275042 -0.275042)
							(end -0.2032 -0.3048)
						)
						(arc
							(start 0.2032 -0.3048)
							(mid 0.275042 -0.275042)
							(end 0.3048 -0.2032)
						)
					)
					(width 0)
					(fill yes)
				)
			)
		)
	)
	(footprint ""
		(layer "B.Cu")
		(at 183.9468 -28.1178 90)
		(property "Reference" "TP60"
			(at 0 0 90)
			(layer "B.SilkS")
			(hide yes)
			(effects
				(font
					(size 1.27 1.27)
				)
				(justify mirror)
			)
		)
		(property "Value" "TPAD28-2-GP"
			(at 0.0127 -1.6637 90)
			(unlocked yes)
			(layer "B.Fab")
			(hide yes)
			(effects
				(font
					(size 1.016 1.016)
					(thickness 0.1524)
				)
				(justify mirror)
			)
		)
		(property "Device Type" "TPAD28"
			(at 0.0127 -3.1877 90)
			(unlocked yes)
			(layer "B.Fab")
			(hide yes)
			(effects
				(font
					(size 1.016 1.016)
					(thickness 0.1524)
				)
				(justify mirror)
			)
		)
		(duplicate_pad_numbers_are_jumpers no)
		(fp_poly
			(pts
				(arc
					(start 0 0.3556)
					(mid 0 -0.3556)
					(end 0 0.3556)
				)
			)
			(stroke
				(width 0)
				(type default)
			)
			(fill no)
			(layer "B.CrtYd")
		)
		(fp_poly
			(pts
				(arc
					(start 0 0.6096)
					(mid 0 -0.6096)
					(end 0 0.6096)
				)
			)
			(stroke
				(width 0)
				(type default)
			)
			(fill no)
			(layer "B.Fab")
		)
		(pad "1" smd circle
			(at 0 0 270)
			(size 0.7112 0.7112)
			(layers "B.Cu" "B.Mask" "B.Paste")
			(net "IOC_GPIO_6")
		)
	)
	(footprint ""
		(layer "B.Cu")
		(at 201.295 -41.148)
		(property "Reference" "U15"
			(at 0 0 0)
			(layer "B.SilkS")
			(hide yes)
			(effects
				(font
					(size 1.27 1.27)
				)
				(justify mirror)
			)
		)
		(property "Value" "CAT24C64WI-GT3-GP"
			(at 3.707384 -1.5367 0)
			(unlocked yes)
			(layer "B.Fab")
			(hide yes)
			(effects
				(font
					(size 1.016 1.016)
					(thickness 0.1524)
				)
				(justify mirror)
			)
		)
		(property "Device Type" "SOIC8H69"
			(at 3.707384 -3.0607 0)
			(unlocked yes)
			(layer "B.Fab")
			(hide yes)
			(effects
				(font
					(size 1.016 1.016)
					(thickness 0.1524)
				)
				(justify mirror)
			)
		)
		(duplicate_pad_numbers_are_jumpers no)
		(fp_line
			(start -2.1336 -1.4224)
			(end 2.7432 -1.4224)
			(stroke
				(width 0.1524)
				(type default)
			)
			(layer "B.SilkS")
		)
		(fp_line
			(start -2.1336 1.4224)
			(end -2.1336 -1.4224)
			(stroke
				(width 0.1524)
				(type default)
			)
			(layer "B.SilkS")
		)
		(fp_line
			(start 2.1844 -0.0508)
			(end 2.7178 0.508)
			(stroke
				(width 0.1524)
				(type default)
			)
			(layer "B.SilkS")
		)
		(fp_line
			(start 2.6289 3.4417)
			(end 2.6289 1.4732)
			(stroke
				(width 0.381)
				(type default)
			)
			(layer "B.SilkS")
		)
		(fp_line
			(start 2.7178 -0.508)
			(end 2.1844 -0.0508)
			(stroke
				(width 0.1524)
				(type default)
			)
			(layer "B.SilkS")
		)
		(fp_line
			(start 2.7432 -1.4224)
			(end 2.7432 1.4224)
			(stroke
				(width 0.1524)
				(type default)
			)
			(layer "B.SilkS")
		)
		(fp_line
			(start 2.7432 1.4224)
			(end -2.1336 1.4224)
			(stroke
				(width 0.1524)
				(type default)
			)
			(layer "B.SilkS")
		)
		(fp_line
			(start 2.7432 1.4224)
			(end 2.6416 1.4224)
			(stroke
				(width 0.1524)
				(type default)
			)
			(layer "B.SilkS")
		)
		(fp_poly
			(pts
				(xy 2.2098 -1.4224) (xy 2.2098 1.4224) (xy -2.2098 1.4224) (xy -2.2098 -1.4224)
			)
			(stroke
				(width 0)
				(type default)
			)
			(fill yes)
			(layer "B.SilkS")
		)
		(fp_rect
			(start 2.450084 2.999994)
			(end -2.450084 -2.999994)
			(stroke
				(width 0)
				(type default)
			)
			(fill no)
			(layer "B.CrtYd")
		)
		(fp_poly
			(pts
				(xy 2.8194 3.6322) (xy 2.8194 -3.6322) (xy -2.8194 -3.6322) (xy -2.8194 1.18364) (xy -2.450084 1.18364)
				(xy -2.450084 -2.999994) (xy 2.450084 -2.999994) (xy 2.450084 2.999994) (xy -2.450084 2.999994)
				(xy -2.450084 1.18618) (xy -2.8194 1.18618) (xy -2.8194 3.6322)
			)
			(stroke
				(width 0)
				(type default)
			)
			(fill no)
			(layer "B.CrtYd")
		)
		(fp_rect
			(start 2.8194 3.6322)
			(end -2.8194 -3.6322)
			(stroke
				(width 0)
				(type default)
			)
			(fill no)
			(layer "B.Fab")
		)
		(pad "1" smd rect
			(at 1.905 2.54 180)
			(size 0.635 1.651)
			(layers "B.Cu" "B.Mask" "B.Paste")
			(net "IOC_EEPROM_A0")
		)
		(pad "2" smd rect
			(at 0.635 2.54 180)
			(size 0.635 1.651)
			(layers "B.Cu" "B.Mask" "B.Paste")
			(net "IOC_EEPROM_A1")
		)
		(pad "3" smd rect
			(at -0.635 2.54 180)
			(size 0.635 1.651)
			(layers "B.Cu" "B.Mask" "B.Paste")
			(net "IOC_EEPROM_A2")
		)
		(pad "4" smd rect
			(at -1.905 2.54 180)
			(size 0.635 1.651)
			(layers "B.Cu" "B.Mask" "B.Paste")
			(net "GND")
		)
		(pad "5" smd rect
			(at -1.905 -2.54 180)
			(size 0.635 1.651)
			(layers "B.Cu" "B.Mask" "B.Paste")
			(net "IOC_EEPROM_SDA")
		)
		(pad "6" smd rect
			(at -0.635 -2.54 180)
			(size 0.635 1.651)
			(layers "B.Cu" "B.Mask" "B.Paste")
			(net "IOC_EEPROM_SCL")
		)
		(pad "7" smd rect
			(at 0.635 -2.54 180)
			(size 0.635 1.651)
			(layers "B.Cu" "B.Mask" "B.Paste")
			(net "IOC_EEPROM_WP")
		)
		(pad "8" smd rect
			(at 1.905 -2.54 180)
			(size 0.635 1.651)
			(layers "B.Cu" "B.Mask" "B.Paste")
			(net "P1V8_C")
		)
	)
	(footprint ""
		(layer "B.Cu")
		(at 183.144668 -44.78401 -90)
		(property "Reference" "C479"
			(at 0 0 90)
			(layer "B.SilkS")
			(hide yes)
			(effects
				(font
					(size 1.27 1.27)
				)
				(justify mirror)
			)
		)
		(property "Value" "SCD1U6D3V1KX-GP"
			(at 2.8321 -1.7399 270)
			(unlocked yes)
			(layer "B.Fab")
			(hide yes)
			(effects
				(font
					(size 1.016 1.016)
					(thickness 0.1524)
				)
				(justify mirror)
			)
		)
		(property "Device Type" "C0201H13"
			(at 2.8321 -3.2639 270)
			(unlocked yes)
			(layer "B.Fab")
			(hide yes)
			(effects
				(font
					(size 1.016 1.016)
					(thickness 0.1524)
				)
				(justify mirror)
			)
		)
		(duplicate_pad_numbers_are_jumpers no)
		(fp_rect
			(start 0.2794 0.6477)
			(end -0.2794 -0.6477)
			(stroke
				(width 0)
				(type default)
			)
			(fill no)
			(layer "B.CrtYd")
		)
		(fp_rect
			(start 0.2794 0.6477)
			(end -0.2794 -0.6477)
			(stroke
				(width 0)
				(type default)
			)
			(fill no)
			(layer "B.Fab")
		)
		(pad "1" smd custom
			(at 0 -0.2794 90)
			(size 0.0762 0.0762)
			(layers "B.Cu" "B.Mask" "B.Paste")
			(net "P1V8_C")
			(options
				(clearance outline)
				(anchor circle)
			)
			(primitives
				(gr_poly
					(pts
						(arc
							(start 0.1524 0.127)
							(mid 0.137521 0.162921)
							(end 0.1016 0.1778)
						)
						(arc
							(start -0.1016 0.1778)
							(mid -0.137521 0.162921)
							(end -0.1524 0.127)
						)
						(arc
							(start -0.1524 -0.127)
							(mid -0.137521 -0.162921)
							(end -0.1016 -0.1778)
						)
						(arc
							(start 0.1016 -0.1778)
							(mid 0.137521 -0.162921)
							(end 0.1524 -0.127)
						)
					)
					(width 0)
					(fill yes)
				)
			)
		)
		(pad "2" smd custom
			(at 0 0.2794 90)
			(size 0.0762 0.0762)
			(layers "B.Cu" "B.Mask" "B.Paste")
			(net "GND")
			(options
				(clearance outline)
				(anchor circle)
			)
			(primitives
				(gr_poly
					(pts
						(arc
							(start 0.1524 0.127)
							(mid 0.137521 0.162921)
							(end 0.1016 0.1778)
						)
						(arc
							(start -0.1016 0.1778)
							(mid -0.137521 0.162921)
							(end -0.1524 0.127)
						)
						(arc
							(start -0.1524 -0.127)
							(mid -0.137521 -0.162921)
							(end -0.1016 -0.1778)
						)
						(arc
							(start 0.1016 -0.1778)
							(mid 0.137521 -0.162921)
							(end 0.1524 -0.127)
						)
					)
					(width 0)
					(fill yes)
				)
			)
		)
	)
	(footprint ""
		(layer "B.Cu")
		(at 176.890172 -35.637216)
		(property "Reference" "C414"
			(at 0 0 0)
			(layer "B.SilkS")
			(hide yes)
			(effects
				(font
					(size 1.27 1.27)
				)
				(justify mirror)
			)
		)
		(property "Value" "SC1U6D3V1MX-GP"
			(at -1.9177 2.0193 0)
			(unlocked yes)
			(layer "B.Fab")
			(hide yes)
			(effects
				(font
					(size 1.016 1.016)
					(thickness 0.1524)
				)
				(justify mirror)
			)
		)
		(property "Device Type" "C0201H14"
			(at -1.9177 0.4953 0)
			(unlocked yes)
			(layer "B.Fab")
			(hide yes)
			(effects
				(font
					(size 1.016 1.016)
					(thickness 0.1524)
				)
				(justify mirror)
			)
		)
		(duplicate_pad_numbers_are_jumpers no)
		(fp_rect
			(start 0.1524 0.3048)
			(end -0.1524 -0.3048)
			(stroke
				(width 0)
				(type default)
			)
			(fill no)
			(layer "B.CrtYd")
		)
		(fp_poly
			(pts
				(xy 0.2794 0.6477) (xy 0.2794 -0.6477) (xy -0.2794 -0.6477) (xy -0.2794 -0.1905) (xy -0.1524 -0.1905)
				(xy -0.1524 -0.3048) (xy 0.1524 -0.3048) (xy 0.1524 0.3048) (xy -0.1524 0.3048) (xy -0.1524 -0.1778)
				(xy -0.2794 -0.1778) (xy -0.2794 0.6477)
			)
			(stroke
				(width 0)
				(type default)
			)
			(fill no)
			(layer "B.CrtYd")
		)
		(fp_rect
			(start 0.2794 0.6477)
			(end -0.2794 -0.6477)
			(stroke
				(width 0)
				(type default)
			)
			(fill no)
			(layer "B.Fab")
		)
		(pad "1" smd custom
			(at 0 -0.2794 180)
			(size 0.0762 0.0762)
			(layers "B.Cu" "B.Mask" "B.Paste")
			(net "P0V975")
			(options
				(clearance outline)
				(anchor circle)
			)
			(primitives
				(gr_poly
					(pts
						(arc
							(start 0.1524 0.127)
							(mid 0.137521 0.162921)
							(end 0.1016 0.1778)
						)
						(arc
							(start -0.1016 0.1778)
							(mid -0.137521 0.162921)
							(end -0.1524 0.127)
						)
						(arc
							(start -0.1524 -0.127)
							(mid -0.137521 -0.162921)
							(end -0.1016 -0.1778)
						)
						(arc
							(start 0.1016 -0.1778)
							(mid 0.137521 -0.162921)
							(end 0.1524 -0.127)
						)
					)
					(width 0)
					(fill yes)
				)
			)
		)
		(pad "2" smd custom
			(at 0 0.2794 180)
			(size 0.0762 0.0762)
			(layers "B.Cu" "B.Mask" "B.Paste")
			(net "GND")
			(options
				(clearance outline)
				(anchor circle)
			)
			(primitives
				(gr_poly
					(pts
						(arc
							(start 0.1524 0.127)
							(mid 0.137521 0.162921)
							(end 0.1016 0.1778)
						)
						(arc
							(start -0.1016 0.1778)
							(mid -0.137521 0.162921)
							(end -0.1524 0.127)
						)
						(arc
							(start -0.1524 -0.127)
							(mid -0.137521 -0.162921)
							(end -0.1016 -0.1778)
						)
						(arc
							(start 0.1016 -0.1778)
							(mid 0.137521 -0.162921)
							(end 0.1524 -0.127)
						)
					)
					(width 0)
					(fill yes)
				)
			)
		)
	)
	(footprint ""
		(layer "B.Cu")
		(at 174.726092 -35.563048)
		(property "Reference" "C423"
			(at 0 0 0)
			(layer "B.SilkS")
			(hide yes)
			(effects
				(font
					(size 1.27 1.27)
				)
				(justify mirror)
			)
		)
		(property "Value" "SCD1U6D3V1KX-GP"
			(at 2.8321 -1.7399 0)
			(unlocked yes)
			(layer "B.Fab")
			(hide yes)
			(effects
				(font
					(size 1.016 1.016)
					(thickness 0.1524)
				)
				(justify mirror)
			)
		)
		(property "Device Type" "C0201H13"
			(at 2.8321 -3.2639 0)
			(unlocked yes)
			(layer "B.Fab")
			(hide yes)
			(effects
				(font
					(size 1.016 1.016)
					(thickness 0.1524)
				)
				(justify mirror)
			)
		)
		(duplicate_pad_numbers_are_jumpers no)
		(fp_rect
			(start 0.2794 0.6477)
			(end -0.2794 -0.6477)
			(stroke
				(width 0)
				(type default)
			)
			(fill no)
			(layer "B.CrtYd")
		)
		(fp_rect
			(start 0.2794 0.6477)
			(end -0.2794 -0.6477)
			(stroke
				(width 0)
				(type default)
			)
			(fill no)
			(layer "B.Fab")
		)
		(pad "1" smd custom
			(at 0 -0.2794 180)
			(size 0.0762 0.0762)
			(layers "B.Cu" "B.Mask" "B.Paste")
			(net "P0V975")
			(options
				(clearance outline)
				(anchor circle)
			)
			(primitives
				(gr_poly
					(pts
						(arc
							(start 0.1524 0.127)
							(mid 0.137521 0.162921)
							(end 0.1016 0.1778)
						)
						(arc
							(start -0.1016 0.1778)
							(mid -0.137521 0.162921)
							(end -0.1524 0.127)
						)
						(arc
							(start -0.1524 -0.127)
							(mid -0.137521 -0.162921)
							(end -0.1016 -0.1778)
						)
						(arc
							(start 0.1016 -0.1778)
							(mid 0.137521 -0.162921)
							(end 0.1524 -0.127)
						)
					)
					(width 0)
					(fill yes)
				)
			)
		)
		(pad "2" smd custom
			(at 0 0.2794 180)
			(size 0.0762 0.0762)
			(layers "B.Cu" "B.Mask" "B.Paste")
			(net "GND")
			(options
				(clearance outline)
				(anchor circle)
			)
			(primitives
				(gr_poly
					(pts
						(arc
							(start 0.1524 0.127)
							(mid 0.137521 0.162921)
							(end 0.1016 0.1778)
						)
						(arc
							(start -0.1016 0.1778)
							(mid -0.137521 0.162921)
							(end -0.1524 0.127)
						)
						(arc
							(start -0.1524 -0.127)
							(mid -0.137521 -0.162921)
							(end -0.1016 -0.1778)
						)
						(arc
							(start 0.1016 -0.1778)
							(mid 0.137521 -0.162921)
							(end 0.1524 -0.127)
						)
					)
					(width 0)
					(fill yes)
				)
			)
		)
	)
	(footprint ""
		(layer "B.Cu")
		(at 201.549 -27.051 -90)
		(property "Reference" "R283"
			(at 0 0 90)
			(layer "B.SilkS")
			(hide yes)
			(effects
				(font
					(size 1.27 1.27)
				)
				(justify mirror)
			)
		)
		(property "Value" "10R2F-L-GP"
			(at -0.064008 -3.993896 270)
			(unlocked yes)
			(layer "B.Fab")
			(hide yes)
			(effects
				(font
					(size 1.016 1.016)
					(thickness 0.1524)
				)
				(justify mirror)
			)
		)
		(property "Device Type" "R402H14"
			(at -0.064008 -5.517896 270)
			(unlocked yes)
			(layer "B.Fab")
			(hide yes)
			(effects
				(font
					(size 1.016 1.016)
					(thickness 0.1524)
				)
				(justify mirror)
			)
		)
		(duplicate_pad_numbers_are_jumpers no)
		(fp_line
			(start -0.508 -0.9398)
			(end 0.508 -0.9398)
			(stroke
				(width 0.1524)
				(type default)
			)
			(layer "B.SilkS")
		)
		(fp_line
			(start 0.508 -0.9398)
			(end 0.508 0.9398)
			(stroke
				(width 0.1524)
				(type default)
			)
			(layer "B.SilkS")
		)
		(fp_rect
			(start 0.508 0.9398)
			(end -0.508 -0.9398)
			(stroke
				(width 0)
				(type default)
			)
			(fill no)
			(layer "B.CrtYd")
		)
		(fp_rect
			(start 0.508 0.9398)
			(end -0.508 -0.9398)
			(stroke
				(width 0)
				(type default)
			)
			(fill no)
			(layer "B.Fab")
		)
		(pad "1" smd custom
			(at 0 -0.4445 90)
			(size 0.1397 0.1397)
			(layers "B.Cu" "B.Mask" "B.Paste")
			(net "P1V5_C")
			(options
				(clearance outline)
				(anchor circle)
			)
			(primitives
				(gr_poly
					(pts
						(arc
							(start -0.1778 0.2794)
							(mid -0.249642 0.249642)
							(end -0.2794 0.1778)
						)
						(arc
							(start -0.2794 -0.1778)
							(mid -0.249642 -0.249642)
							(end -0.1778 -0.2794)
						)
						(arc
							(start 0.1778 -0.2794)
							(mid 0.249642 -0.249642)
							(end 0.2794 -0.1778)
						)
						(arc
							(start 0.2794 0.1778)
							(mid 0.249642 0.249642)
							(end 0.1778 0.2794)
						)
					)
					(width 0)
					(fill yes)
				)
			)
		)
		(pad "2" smd custom
			(at 0 0.4445 90)
			(size 0.1397 0.1397)
			(layers "B.Cu" "B.Mask" "B.Paste")
			(net "PCE_VDDH")
			(options
				(clearance outline)
				(anchor circle)
			)
			(primitives
				(gr_poly
					(pts
						(arc
							(start -0.1778 0.2794)
							(mid -0.249642 0.249642)
							(end -0.2794 0.1778)
						)
						(arc
							(start -0.2794 -0.1778)
							(mid -0.249642 -0.249642)
							(end -0.1778 -0.2794)
						)
						(arc
							(start 0.1778 -0.2794)
							(mid 0.249642 -0.249642)
							(end 0.2794 -0.1778)
						)
						(arc
							(start 0.2794 0.1778)
							(mid 0.249642 0.249642)
							(end 0.1778 0.2794)
						)
					)
					(width 0)
					(fill yes)
				)
			)
		)
	)
	(footprint ""
		(layer "B.Cu")
		(at 124.9934 -39.4716 180)
		(property "Reference" "C52"
			(at 0 0 0)
			(layer "B.SilkS")
			(hide yes)
			(effects
				(font
					(size 1.27 1.27)
				)
				(justify mirror)
			)
		)
		(property "Value" "SCD01U16V1KX-GP"
			(at 2.8321 -1.7399 180)
			(unlocked yes)
			(layer "B.Fab")
			(hide yes)
			(effects
				(font
					(size 1.016 1.016)
					(thickness 0.1524)
				)
				(justify mirror)
			)
		)
		(property "Device Type" "C0201H13"
			(at 2.8321 -3.2639 180)
			(unlocked yes)
			(layer "B.Fab")
			(hide yes)
			(effects
				(font
					(size 1.016 1.016)
					(thickness 0.1524)
				)
				(justify mirror)
			)
		)
		(duplicate_pad_numbers_are_jumpers no)
		(fp_rect
			(start 0.2794 0.6477)
			(end -0.2794 -0.6477)
			(stroke
				(width 0)
				(type default)
			)
			(fill no)
			(layer "B.CrtYd")
		)
		(fp_rect
			(start 0.2794 0.6477)
			(end -0.2794 -0.6477)
			(stroke
				(width 0)
				(type default)
			)
			(fill no)
			(layer "B.Fab")
		)
		(pad "1" smd custom
			(at 0 -0.2794)
			(size 0.0762 0.0762)
			(layers "B.Cu" "B.Mask" "B.Paste")
			(net "PHY_DPB_TO_SCC_38_DN")
			(options
				(clearance outline)
				(anchor circle)
			)
			(primitives
				(gr_poly
					(pts
						(arc
							(start 0.1524 0.127)
							(mid 0.137521 0.162921)
							(end 0.1016 0.1778)
						)
						(arc
							(start -0.1016 0.1778)
							(mid -0.137521 0.162921)
							(end -0.1524 0.127)
						)
						(arc
							(start -0.1524 -0.127)
							(mid -0.137521 -0.162921)
							(end -0.1016 -0.1778)
						)
						(arc
							(start 0.1016 -0.1778)
							(mid 0.137521 -0.162921)
							(end 0.1524 -0.127)
						)
					)
					(width 0)
					(fill yes)
				)
			)
		)
		(pad "2" smd custom
			(at 0 0.2794)
			(size 0.0762 0.0762)
			(layers "B.Cu" "B.Mask" "B.Paste")
			(net "PHY_DPB_TO_SCC_C_38_DN")
			(options
				(clearance outline)
				(anchor circle)
			)
			(primitives
				(gr_poly
					(pts
						(arc
							(start 0.1524 0.127)
							(mid 0.137521 0.162921)
							(end 0.1016 0.1778)
						)
						(arc
							(start -0.1016 0.1778)
							(mid -0.137521 0.162921)
							(end -0.1524 0.127)
						)
						(arc
							(start -0.1524 -0.127)
							(mid -0.137521 -0.162921)
							(end -0.1016 -0.1778)
						)
						(arc
							(start 0.1016 -0.1778)
							(mid 0.137521 -0.162921)
							(end 0.1524 -0.127)
						)
					)
					(width 0)
					(fill yes)
				)
			)
		)
	)
	(footprint ""
		(layer "B.Cu")
		(at 135.622538 -84.709)
		(property "Reference" "R59"
			(at 0 0 0)
			(layer "B.SilkS")
			(hide yes)
			(effects
				(font
					(size 1.27 1.27)
				)
				(justify mirror)
			)
		)
		(property "Value" "4K7R2F-GP"
			(at -0.064008 -3.993896 0)
			(unlocked yes)
			(layer "B.Fab")
			(hide yes)
			(effects
				(font
					(size 1.016 1.016)
					(thickness 0.1524)
				)
				(justify mirror)
			)
		)
		(property "Device Type" "R402H16"
			(at -0.064008 -5.517896 0)
			(unlocked yes)
			(layer "B.Fab")
			(hide yes)
			(effects
				(font
					(size 1.016 1.016)
					(thickness 0.1524)
				)
				(justify mirror)
			)
		)
		(duplicate_pad_numbers_are_jumpers no)
		(fp_line
			(start -0.508 -0.9398)
			(end 0.508 -0.9398)
			(stroke
				(width 0.1524)
				(type default)
			)
			(layer "B.SilkS")
		)
		(fp_line
			(start 0.508 -0.9398)
			(end 0.508 0.9398)
			(stroke
				(width 0.1524)
				(type default)
			)
			(layer "B.SilkS")
		)
		(fp_rect
			(start 0.508 0.9398)
			(end -0.508 -0.9398)
			(stroke
				(width 0)
				(type default)
			)
			(fill no)
			(layer "B.CrtYd")
		)
		(fp_rect
			(start 0.508 0.9398)
			(end -0.508 -0.9398)
			(stroke
				(width 0)
				(type default)
			)
			(fill no)
			(layer "B.Fab")
		)
		(pad "1" smd custom
			(at 0 -0.4445 180)
			(size 0.1397 0.1397)
			(layers "B.Cu" "B.Mask" "B.Paste")
			(net "P1V8_E")
			(options
				(clearance outline)
				(anchor circle)
			)
			(primitives
				(gr_poly
					(pts
						(arc
							(start -0.1778 0.2794)
							(mid -0.249642 0.249642)
							(end -0.2794 0.1778)
						)
						(arc
							(start -0.2794 -0.1778)
							(mid -0.249642 -0.249642)
							(end -0.1778 -0.2794)
						)
						(arc
							(start 0.1778 -0.2794)
							(mid 0.249642 -0.249642)
							(end 0.2794 -0.1778)
						)
						(arc
							(start 0.2794 0.1778)
							(mid 0.249642 0.249642)
							(end 0.1778 0.2794)
						)
					)
					(width 0)
					(fill yes)
				)
			)
		)
		(pad "2" smd custom
			(at 0 0.4445 180)
			(size 0.1397 0.1397)
			(layers "B.Cu" "B.Mask" "B.Paste")
			(net "I2C_DRIVE_INS_SDA5_LS")
			(options
				(clearance outline)
				(anchor circle)
			)
			(primitives
				(gr_poly
					(pts
						(arc
							(start -0.1778 0.2794)
							(mid -0.249642 0.249642)
							(end -0.2794 0.1778)
						)
						(arc
							(start -0.2794 -0.1778)
							(mid -0.249642 -0.249642)
							(end -0.1778 -0.2794)
						)
						(arc
							(start 0.1778 -0.2794)
							(mid 0.249642 -0.249642)
							(end 0.2794 -0.1778)
						)
						(arc
							(start 0.2794 0.1778)
							(mid 0.249642 0.249642)
							(end 0.1778 0.2794)
						)
					)
					(width 0)
					(fill yes)
				)
			)
		)
	)
	(footprint ""
		(layer "B.Cu")
		(at 164.723318 -29.492956 -90)
		(property "Reference" "C398"
			(at 0 0 90)
			(layer "B.SilkS")
			(hide yes)
			(effects
				(font
					(size 1.27 1.27)
				)
				(justify mirror)
			)
		)
		(property "Value" "SCD1U16V2KX-3GP"
			(at -1.1811 -2.7051 270)
			(unlocked yes)
			(layer "B.Fab")
			(hide yes)
			(effects
				(font
					(size 1.016 1.016)
					(thickness 0.1524)
				)
				(justify mirror)
			)
		)
		(property "Device Type" "C402H22"
			(at -1.1811 -4.2291 270)
			(unlocked yes)
			(layer "B.Fab")
			(hide yes)
			(effects
				(font
					(size 1.016 1.016)
					(thickness 0.1524)
				)
				(justify mirror)
			)
		)
		(duplicate_pad_numbers_are_jumpers no)
		(fp_rect
			(start 0.4318 0.9525)
			(end -0.4318 -0.9525)
			(stroke
				(width 0)
				(type default)
			)
			(fill no)
			(layer "B.CrtYd")
		)
		(fp_rect
			(start 0.4318 0.9525)
			(end -0.4318 -0.9525)
			(stroke
				(width 0)
				(type default)
			)
			(fill no)
			(layer "B.Fab")
		)
		(pad "1" smd custom
			(at 0 -0.4445 90)
			(size 0.1524 0.1524)
			(layers "B.Cu" "B.Mask" "B.Paste")
			(net "SAS0_AVDD")
			(options
				(clearance outline)
				(anchor circle)
			)
			(primitives
				(gr_poly
					(pts
						(arc
							(start 0.3048 0.2032)
							(mid 0.275042 0.275042)
							(end 0.2032 0.3048)
						)
						(arc
							(start -0.2032 0.3048)
							(mid -0.275042 0.275042)
							(end -0.3048 0.2032)
						)
						(arc
							(start -0.3048 -0.2032)
							(mid -0.275042 -0.275042)
							(end -0.2032 -0.3048)
						)
						(arc
							(start 0.2032 -0.3048)
							(mid 0.275042 -0.275042)
							(end 0.3048 -0.2032)
						)
					)
					(width 0)
					(fill yes)
				)
			)
		)
		(pad "2" smd custom
			(at 0 0.4445 90)
			(size 0.1524 0.1524)
			(layers "B.Cu" "B.Mask" "B.Paste")
			(net "GND")
			(options
				(clearance outline)
				(anchor circle)
			)
			(primitives
				(gr_poly
					(pts
						(arc
							(start 0.3048 0.2032)
							(mid 0.275042 0.275042)
							(end 0.2032 0.3048)
						)
						(arc
							(start -0.2032 0.3048)
							(mid -0.275042 0.275042)
							(end -0.3048 0.2032)
						)
						(arc
							(start -0.3048 -0.2032)
							(mid -0.275042 -0.275042)
							(end -0.2032 -0.3048)
						)
						(arc
							(start 0.2032 -0.3048)
							(mid 0.275042 -0.275042)
							(end 0.3048 -0.2032)
						)
					)
					(width 0)
					(fill yes)
				)
			)
		)
	)
	(footprint ""
		(layer "B.Cu")
		(at 124.2695 -61.5061 -90)
		(property "Reference" "C592"
			(at 0 0 90)
			(layer "B.SilkS")
			(hide yes)
			(effects
				(font
					(size 1.27 1.27)
				)
				(justify mirror)
			)
		)
		(property "Value" "SCD1U6D3V1KX-GP"
			(at 2.8321 -1.7399 270)
			(unlocked yes)
			(layer "B.Fab")
			(hide yes)
			(effects
				(font
					(size 1.016 1.016)
					(thickness 0.1524)
				)
				(justify mirror)
			)
		)
		(property "Device Type" "C0201H13"
			(at 2.8321 -3.2639 270)
			(unlocked yes)
			(layer "B.Fab")
			(hide yes)
			(effects
				(font
					(size 1.016 1.016)
					(thickness 0.1524)
				)
				(justify mirror)
			)
		)
		(duplicate_pad_numbers_are_jumpers no)
		(fp_rect
			(start 0.2794 0.6477)
			(end -0.2794 -0.6477)
			(stroke
				(width 0)
				(type default)
			)
			(fill no)
			(layer "B.CrtYd")
		)
		(fp_rect
			(start 0.2794 0.6477)
			(end -0.2794 -0.6477)
			(stroke
				(width 0)
				(type default)
			)
			(fill no)
			(layer "B.Fab")
		)
		(pad "1" smd custom
			(at 0 -0.2794 90)
			(size 0.0762 0.0762)
			(layers "B.Cu" "B.Mask" "B.Paste")
			(net "GB_VDDA")
			(options
				(clearance outline)
				(anchor circle)
			)
			(primitives
				(gr_poly
					(pts
						(arc
							(start 0.1524 0.127)
							(mid 0.137521 0.162921)
							(end 0.1016 0.1778)
						)
						(arc
							(start -0.1016 0.1778)
							(mid -0.137521 0.162921)
							(end -0.1524 0.127)
						)
						(arc
							(start -0.1524 -0.127)
							(mid -0.137521 -0.162921)
							(end -0.1016 -0.1778)
						)
						(arc
							(start 0.1016 -0.1778)
							(mid 0.137521 -0.162921)
							(end 0.1524 -0.127)
						)
					)
					(width 0)
					(fill yes)
				)
			)
		)
		(pad "2" smd custom
			(at 0 0.2794 90)
			(size 0.0762 0.0762)
			(layers "B.Cu" "B.Mask" "B.Paste")
			(net "GND")
			(options
				(clearance outline)
				(anchor circle)
			)
			(primitives
				(gr_poly
					(pts
						(arc
							(start 0.1524 0.127)
							(mid 0.137521 0.162921)
							(end 0.1016 0.1778)
						)
						(arc
							(start -0.1016 0.1778)
							(mid -0.137521 0.162921)
							(end -0.1524 0.127)
						)
						(arc
							(start -0.1524 -0.127)
							(mid -0.137521 -0.162921)
							(end -0.1016 -0.1778)
						)
						(arc
							(start 0.1016 -0.1778)
							(mid 0.137521 -0.162921)
							(end 0.1524 -0.127)
						)
					)
					(width 0)
					(fill yes)
				)
			)
		)
	)
	(footprint ""
		(layer "B.Cu")
		(at 117.3988 -59.4487)
		(property "Reference" "C588"
			(at 0 0 0)
			(layer "B.SilkS")
			(hide yes)
			(effects
				(font
					(size 1.27 1.27)
				)
				(justify mirror)
			)
		)
		(property "Value" "SCD1U6D3V1KX-GP"
			(at 2.8321 -1.7399 0)
			(unlocked yes)
			(layer "B.Fab")
			(hide yes)
			(effects
				(font
					(size 1.016 1.016)
					(thickness 0.1524)
				)
				(justify mirror)
			)
		)
		(property "Device Type" "C0201H13"
			(at 2.8321 -3.2639 0)
			(unlocked yes)
			(layer "B.Fab")
			(hide yes)
			(effects
				(font
					(size 1.016 1.016)
					(thickness 0.1524)
				)
				(justify mirror)
			)
		)
		(duplicate_pad_numbers_are_jumpers no)
		(fp_rect
			(start 0.2794 0.6477)
			(end -0.2794 -0.6477)
			(stroke
				(width 0)
				(type default)
			)
			(fill no)
			(layer "B.CrtYd")
		)
		(fp_rect
			(start 0.2794 0.6477)
			(end -0.2794 -0.6477)
			(stroke
				(width 0)
				(type default)
			)
			(fill no)
			(layer "B.Fab")
		)
		(pad "1" smd custom
			(at 0 -0.2794 180)
			(size 0.0762 0.0762)
			(layers "B.Cu" "B.Mask" "B.Paste")
			(net "GB_VDDA")
			(options
				(clearance outline)
				(anchor circle)
			)
			(primitives
				(gr_poly
					(pts
						(arc
							(start 0.1524 0.127)
							(mid 0.137521 0.162921)
							(end 0.1016 0.1778)
						)
						(arc
							(start -0.1016 0.1778)
							(mid -0.137521 0.162921)
							(end -0.1524 0.127)
						)
						(arc
							(start -0.1524 -0.127)
							(mid -0.137521 -0.162921)
							(end -0.1016 -0.1778)
						)
						(arc
							(start 0.1016 -0.1778)
							(mid 0.137521 -0.162921)
							(end 0.1524 -0.127)
						)
					)
					(width 0)
					(fill yes)
				)
			)
		)
		(pad "2" smd custom
			(at 0 0.2794 180)
			(size 0.0762 0.0762)
			(layers "B.Cu" "B.Mask" "B.Paste")
			(net "GND")
			(options
				(clearance outline)
				(anchor circle)
			)
			(primitives
				(gr_poly
					(pts
						(arc
							(start 0.1524 0.127)
							(mid 0.137521 0.162921)
							(end 0.1016 0.1778)
						)
						(arc
							(start -0.1016 0.1778)
							(mid -0.137521 0.162921)
							(end -0.1524 0.127)
						)
						(arc
							(start -0.1524 -0.127)
							(mid -0.137521 -0.162921)
							(end -0.1016 -0.1778)
						)
						(arc
							(start 0.1016 -0.1778)
							(mid 0.137521 -0.162921)
							(end 0.1524 -0.127)
						)
					)
					(width 0)
					(fill yes)
				)
			)
		)
	)
	(footprint ""
		(layer "B.Cu")
		(at 174.371 -53.3908 90)
		(property "Reference" "R497"
			(at 0 0 90)
			(layer "B.SilkS")
			(hide yes)
			(effects
				(font
					(size 1.27 1.27)
				)
				(justify mirror)
			)
		)
		(property "Value" "0R2J-2-GP"
			(at -0.064008 -3.993896 90)
			(unlocked yes)
			(layer "B.Fab")
			(hide yes)
			(effects
				(font
					(size 1.016 1.016)
					(thickness 0.1524)
				)
				(justify mirror)
			)
		)
		(property "Device Type" "R402H16"
			(at -0.064008 -5.517896 90)
			(unlocked yes)
			(layer "B.Fab")
			(hide yes)
			(effects
				(font
					(size 1.016 1.016)
					(thickness 0.1524)
				)
				(justify mirror)
			)
		)
		(duplicate_pad_numbers_are_jumpers no)
		(fp_line
			(start 0.508 -0.9398)
			(end 0.508 0.9398)
			(stroke
				(width 0.1524)
				(type default)
			)
			(layer "B.SilkS")
		)
		(fp_line
			(start -0.508 -0.9398)
			(end 0.508 -0.9398)
			(stroke
				(width 0.1524)
				(type default)
			)
			(layer "B.SilkS")
		)
		(fp_rect
			(start 0.508 0.9398)
			(end -0.508 -0.9398)
			(stroke
				(width 0)
				(type default)
			)
			(fill no)
			(layer "B.CrtYd")
		)
		(fp_rect
			(start 0.508 0.9398)
			(end -0.508 -0.9398)
			(stroke
				(width 0)
				(type default)
			)
			(fill no)
			(layer "B.Fab")
		)
		(pad "1" smd custom
			(at 0 -0.4445 270)
			(size 0.1397 0.1397)
			(layers "B.Cu" "B.Mask" "B.Paste")
			(net "P0V975")
			(options
				(clearance outline)
				(anchor circle)
			)
			(primitives
				(gr_poly
					(pts
						(arc
							(start -0.1778 0.2794)
							(mid -0.249642 0.249642)
							(end -0.2794 0.1778)
						)
						(arc
							(start -0.2794 -0.1778)
							(mid -0.249642 -0.249642)
							(end -0.1778 -0.2794)
						)
						(arc
							(start 0.1778 -0.2794)
							(mid 0.249642 -0.249642)
							(end 0.2794 -0.1778)
						)
						(arc
							(start 0.2794 0.1778)
							(mid 0.249642 0.249642)
							(end 0.1778 0.2794)
						)
					)
					(width 0)
					(fill yes)
				)
			)
		)
		(pad "2" smd custom
			(at 0 0.4445 270)
			(size 0.1397 0.1397)
			(layers "B.Cu" "B.Mask" "B.Paste")
			(net "P0V975_SEN")
			(options
				(clearance outline)
				(anchor circle)
			)
			(primitives
				(gr_poly
					(pts
						(arc
							(start -0.1778 0.2794)
							(mid -0.249642 0.249642)
							(end -0.2794 0.1778)
						)
						(arc
							(start -0.2794 -0.1778)
							(mid -0.249642 -0.249642)
							(end -0.1778 -0.2794)
						)
						(arc
							(start 0.1778 -0.2794)
							(mid 0.249642 -0.249642)
							(end 0.2794 -0.1778)
						)
						(arc
							(start 0.2794 0.1778)
							(mid 0.249642 0.249642)
							(end 0.1778 0.2794)
						)
					)
					(width 0)
					(fill yes)
				)
			)
		)
	)
	(footprint ""
		(layer "B.Cu")
		(at 181.229 -30.353 -90)
		(property "Reference" "C487"
			(at 0 0 90)
			(layer "B.SilkS")
			(hide yes)
			(effects
				(font
					(size 1.27 1.27)
				)
				(justify mirror)
			)
		)
		(property "Value" "SC1U16V2KX-7-GP"
			(at -1.7526 -1.6002 270)
			(unlocked yes)
			(layer "B.Fab")
			(hide yes)
			(effects
				(font
					(size 1.016 1.016)
					(thickness 0.1524)
				)
				(justify mirror)
			)
		)
		(property "Device Type" "C402-TO0D2H24"
			(at -1.7526 -3.1242 270)
			(unlocked yes)
			(layer "B.Fab")
			(hide yes)
			(effects
				(font
					(size 1.016 1.016)
					(thickness 0.1524)
				)
				(justify mirror)
			)
		)
		(duplicate_pad_numbers_are_jumpers no)
		(fp_rect
			(start 0.4826 0.889)
			(end -0.4826 -0.889)
			(stroke
				(width 0)
				(type default)
			)
			(fill no)
			(layer "B.CrtYd")
		)
		(fp_rect
			(start 0.4826 0.889)
			(end -0.4826 -0.889)
			(stroke
				(width 0)
				(type default)
			)
			(fill no)
			(layer "B.Fab")
		)
		(pad "1" smd custom
			(at 0 -0.4572 90)
			(size 0.1524 0.1524)
			(layers "B.Cu" "B.Mask" "B.Paste")
			(net "P1V8_C")
			(options
				(clearance outline)
				(anchor circle)
			)
			(primitives
				(gr_poly
					(pts
						(arc
							(start -0.254 -0.3048)
							(mid -0.325842 -0.275042)
							(end -0.3556 -0.2032)
						)
						(arc
							(start -0.3556 0.2032)
							(mid -0.325842 0.275042)
							(end -0.254 0.3048)
						)
						(arc
							(start 0.254 0.3048)
							(mid 0.325842 0.275042)
							(end 0.3556 0.2032)
						)
						(arc
							(start 0.3556 -0.2032)
							(mid 0.325842 -0.275042)
							(end 0.254 -0.3048)
						)
					)
					(width 0)
					(fill yes)
				)
			)
		)
		(pad "2" smd custom
			(at 0 0.4572 90)
			(size 0.1524 0.1524)
			(layers "B.Cu" "B.Mask" "B.Paste")
			(net "GND")
			(options
				(clearance outline)
				(anchor circle)
			)
			(primitives
				(gr_poly
					(pts
						(arc
							(start -0.254 -0.3048)
							(mid -0.325842 -0.275042)
							(end -0.3556 -0.2032)
						)
						(arc
							(start -0.3556 0.2032)
							(mid -0.325842 0.275042)
							(end -0.254 0.3048)
						)
						(arc
							(start 0.254 0.3048)
							(mid 0.325842 0.275042)
							(end 0.3556 0.2032)
						)
						(arc
							(start 0.3556 -0.2032)
							(mid 0.325842 -0.275042)
							(end 0.254 -0.3048)
						)
					)
					(width 0)
					(fill yes)
				)
			)
		)
	)
	(footprint ""
		(layer "B.Cu")
		(at 184.155588 -32.230314 90)
		(property "Reference" "C467"
			(at 0 0 90)
			(layer "B.SilkS")
			(hide yes)
			(effects
				(font
					(size 1.27 1.27)
				)
				(justify mirror)
			)
		)
		(property "Value" "SCD1U6D3V1KX-GP"
			(at 2.8321 -1.7399 90)
			(unlocked yes)
			(layer "B.Fab")
			(hide yes)
			(effects
				(font
					(size 1.016 1.016)
					(thickness 0.1524)
				)
				(justify mirror)
			)
		)
		(property "Device Type" "C0201H13"
			(at 2.8321 -3.2639 90)
			(unlocked yes)
			(layer "B.Fab")
			(hide yes)
			(effects
				(font
					(size 1.016 1.016)
					(thickness 0.1524)
				)
				(justify mirror)
			)
		)
		(duplicate_pad_numbers_are_jumpers no)
		(fp_rect
			(start 0.2794 0.6477)
			(end -0.2794 -0.6477)
			(stroke
				(width 0)
				(type default)
			)
			(fill no)
			(layer "B.CrtYd")
		)
		(fp_rect
			(start 0.2794 0.6477)
			(end -0.2794 -0.6477)
			(stroke
				(width 0)
				(type default)
			)
			(fill no)
			(layer "B.Fab")
		)
		(pad "1" smd custom
			(at 0 -0.2794 270)
			(size 0.0762 0.0762)
			(layers "B.Cu" "B.Mask" "B.Paste")
			(net "P1V8_C")
			(options
				(clearance outline)
				(anchor circle)
			)
			(primitives
				(gr_poly
					(pts
						(arc
							(start 0.1524 0.127)
							(mid 0.137521 0.162921)
							(end 0.1016 0.1778)
						)
						(arc
							(start -0.1016 0.1778)
							(mid -0.137521 0.162921)
							(end -0.1524 0.127)
						)
						(arc
							(start -0.1524 -0.127)
							(mid -0.137521 -0.162921)
							(end -0.1016 -0.1778)
						)
						(arc
							(start 0.1016 -0.1778)
							(mid 0.137521 -0.162921)
							(end 0.1524 -0.127)
						)
					)
					(width 0)
					(fill yes)
				)
			)
		)
		(pad "2" smd custom
			(at 0 0.2794 270)
			(size 0.0762 0.0762)
			(layers "B.Cu" "B.Mask" "B.Paste")
			(net "GND")
			(options
				(clearance outline)
				(anchor circle)
			)
			(primitives
				(gr_poly
					(pts
						(arc
							(start 0.1524 0.127)
							(mid 0.137521 0.162921)
							(end 0.1016 0.1778)
						)
						(arc
							(start -0.1016 0.1778)
							(mid -0.137521 0.162921)
							(end -0.1524 0.127)
						)
						(arc
							(start -0.1524 -0.127)
							(mid -0.137521 -0.162921)
							(end -0.1016 -0.1778)
						)
						(arc
							(start 0.1016 -0.1778)
							(mid 0.137521 -0.162921)
							(end 0.1524 -0.127)
						)
					)
					(width 0)
					(fill yes)
				)
			)
		)
	)
	(footprint ""
		(layer "B.Cu")
		(at 124.2822 -68.5038 -90)
		(property "Reference" "C245"
			(at 0 0 90)
			(layer "B.SilkS")
			(hide yes)
			(effects
				(font
					(size 1.27 1.27)
				)
				(justify mirror)
			)
		)
		(property "Value" "SCD1U6D3V1KX-GP"
			(at 2.8321 -1.7399 270)
			(unlocked yes)
			(layer "B.Fab")
			(hide yes)
			(effects
				(font
					(size 1.016 1.016)
					(thickness 0.1524)
				)
				(justify mirror)
			)
		)
		(property "Device Type" "C0201H13"
			(at 2.8321 -3.2639 270)
			(unlocked yes)
			(layer "B.Fab")
			(hide yes)
			(effects
				(font
					(size 1.016 1.016)
					(thickness 0.1524)
				)
				(justify mirror)
			)
		)
		(duplicate_pad_numbers_are_jumpers no)
		(fp_rect
			(start 0.2794 0.6477)
			(end -0.2794 -0.6477)
			(stroke
				(width 0)
				(type default)
			)
			(fill no)
			(layer "B.CrtYd")
		)
		(fp_rect
			(start 0.2794 0.6477)
			(end -0.2794 -0.6477)
			(stroke
				(width 0)
				(type default)
			)
			(fill no)
			(layer "B.Fab")
		)
		(pad "1" smd custom
			(at 0 -0.2794 90)
			(size 0.0762 0.0762)
			(layers "B.Cu" "B.Mask" "B.Paste")
			(net "GB_VDDA")
			(options
				(clearance outline)
				(anchor circle)
			)
			(primitives
				(gr_poly
					(pts
						(arc
							(start 0.1524 0.127)
							(mid 0.137521 0.162921)
							(end 0.1016 0.1778)
						)
						(arc
							(start -0.1016 0.1778)
							(mid -0.137521 0.162921)
							(end -0.1524 0.127)
						)
						(arc
							(start -0.1524 -0.127)
							(mid -0.137521 -0.162921)
							(end -0.1016 -0.1778)
						)
						(arc
							(start 0.1016 -0.1778)
							(mid 0.137521 -0.162921)
							(end 0.1524 -0.127)
						)
					)
					(width 0)
					(fill yes)
				)
			)
		)
		(pad "2" smd custom
			(at 0 0.2794 90)
			(size 0.0762 0.0762)
			(layers "B.Cu" "B.Mask" "B.Paste")
			(net "GND")
			(options
				(clearance outline)
				(anchor circle)
			)
			(primitives
				(gr_poly
					(pts
						(arc
							(start 0.1524 0.127)
							(mid 0.137521 0.162921)
							(end 0.1016 0.1778)
						)
						(arc
							(start -0.1016 0.1778)
							(mid -0.137521 0.162921)
							(end -0.1524 0.127)
						)
						(arc
							(start -0.1524 -0.127)
							(mid -0.137521 -0.162921)
							(end -0.1016 -0.1778)
						)
						(arc
							(start 0.1016 -0.1778)
							(mid 0.137521 -0.162921)
							(end 0.1524 -0.127)
						)
					)
					(width 0)
					(fill yes)
				)
			)
		)
	)
	(footprint ""
		(layer "B.Cu")
		(at 127.3556 -85.344)
		(property "Reference" "TP158"
			(at 0 0 0)
			(layer "B.SilkS")
			(hide yes)
			(effects
				(font
					(size 1.27 1.27)
				)
				(justify mirror)
			)
		)
		(property "Value" "TPAD28-2-GP"
			(at 0.0127 -1.6637 0)
			(unlocked yes)
			(layer "B.Fab")
			(hide yes)
			(effects
				(font
					(size 1.016 1.016)
					(thickness 0.1524)
				)
				(justify mirror)
			)
		)
		(property "Device Type" "TPAD28"
			(at 0.0127 -3.1877 0)
			(unlocked yes)
			(layer "B.Fab")
			(hide yes)
			(effects
				(font
					(size 1.016 1.016)
					(thickness 0.1524)
				)
				(justify mirror)
			)
		)
		(duplicate_pad_numbers_are_jumpers no)
		(fp_poly
			(pts
				(arc
					(start 0.3556 0)
					(mid -0.3556 0)
					(end 0.3556 0)
				)
			)
			(stroke
				(width 0)
				(type default)
			)
			(fill no)
			(layer "B.CrtYd")
		)
		(fp_poly
			(pts
				(arc
					(start 0.6096 0)
					(mid -0.6096 0)
					(end 0.6096 0)
				)
			)
			(stroke
				(width 0)
				(type default)
			)
			(fill no)
			(layer "B.Fab")
		)
		(pad "1" smd circle
			(at 0 0 180)
			(size 0.7112 0.7112)
			(layers "B.Cu" "B.Mask" "B.Paste")
			(net "ICE_TDI")
		)
	)
	(footprint ""
		(layer "B.Cu")
		(at 164.592 -52.07)
		(property "Reference" "R197"
			(at 0 0 0)
			(layer "B.SilkS")
			(hide yes)
			(effects
				(font
					(size 1.27 1.27)
				)
				(justify mirror)
			)
		)
		(property "Value" "2K2R2F-GP"
			(at -0.064008 -3.993896 0)
			(unlocked yes)
			(layer "B.Fab")
			(hide yes)
			(effects
				(font
					(size 1.016 1.016)
					(thickness 0.1524)
				)
				(justify mirror)
			)
		)
		(property "Device Type" "R402H16"
			(at -0.064008 -5.517896 0)
			(unlocked yes)
			(layer "B.Fab")
			(hide yes)
			(effects
				(font
					(size 1.016 1.016)
					(thickness 0.1524)
				)
				(justify mirror)
			)
		)
		(duplicate_pad_numbers_are_jumpers no)
		(fp_line
			(start -0.508 -0.9398)
			(end 0.508 -0.9398)
			(stroke
				(width 0.1524)
				(type default)
			)
			(layer "B.SilkS")
		)
		(fp_line
			(start 0.508 -0.9398)
			(end 0.508 0.9398)
			(stroke
				(width 0.1524)
				(type default)
			)
			(layer "B.SilkS")
		)
		(fp_rect
			(start 0.508 0.9398)
			(end -0.508 -0.9398)
			(stroke
				(width 0)
				(type default)
			)
			(fill no)
			(layer "B.CrtYd")
		)
		(fp_rect
			(start 0.508 0.9398)
			(end -0.508 -0.9398)
			(stroke
				(width 0)
				(type default)
			)
			(fill no)
			(layer "B.Fab")
		)
		(pad "1" smd custom
			(at 0 -0.4445 180)
			(size 0.1397 0.1397)
			(layers "B.Cu" "B.Mask" "B.Paste")
			(net "P1V8_C")
			(options
				(clearance outline)
				(anchor circle)
			)
			(primitives
				(gr_poly
					(pts
						(arc
							(start -0.1778 0.2794)
							(mid -0.249642 0.249642)
							(end -0.2794 0.1778)
						)
						(arc
							(start -0.2794 -0.1778)
							(mid -0.249642 -0.249642)
							(end -0.1778 -0.2794)
						)
						(arc
							(start 0.1778 -0.2794)
							(mid 0.249642 -0.249642)
							(end 0.2794 -0.1778)
						)
						(arc
							(start 0.2794 0.1778)
							(mid 0.249642 0.249642)
							(end 0.1778 0.2794)
						)
					)
					(width 0)
					(fill yes)
				)
			)
		)
		(pad "2" smd custom
			(at 0 0.4445 180)
			(size 0.1397 0.1397)
			(layers "B.Cu" "B.Mask" "B.Paste")
			(net "SIO_DIN_1")
			(options
				(clearance outline)
				(anchor circle)
			)
			(primitives
				(gr_poly
					(pts
						(arc
							(start -0.1778 0.2794)
							(mid -0.249642 0.249642)
							(end -0.2794 0.1778)
						)
						(arc
							(start -0.2794 -0.1778)
							(mid -0.249642 -0.249642)
							(end -0.1778 -0.2794)
						)
						(arc
							(start 0.1778 -0.2794)
							(mid 0.249642 -0.249642)
							(end 0.2794 -0.1778)
						)
						(arc
							(start 0.2794 0.1778)
							(mid 0.249642 0.249642)
							(end 0.1778 0.2794)
						)
					)
					(width 0)
					(fill yes)
				)
			)
		)
	)
	(footprint ""
		(layer "B.Cu")
		(at 175.524414 -48.189642 -90)
		(property "Reference" "C488"
			(at 0 0 90)
			(layer "B.SilkS")
			(hide yes)
			(effects
				(font
					(size 1.27 1.27)
				)
				(justify mirror)
			)
		)
		(property "Value" "SCD1U6D3V1KX-GP"
			(at 2.8321 -1.7399 270)
			(unlocked yes)
			(layer "B.Fab")
			(hide yes)
			(effects
				(font
					(size 1.016 1.016)
					(thickness 0.1524)
				)
				(justify mirror)
			)
		)
		(property "Device Type" "C0201H13"
			(at 2.8321 -3.2639 270)
			(unlocked yes)
			(layer "B.Fab")
			(hide yes)
			(effects
				(font
					(size 1.016 1.016)
					(thickness 0.1524)
				)
				(justify mirror)
			)
		)
		(duplicate_pad_numbers_are_jumpers no)
		(fp_rect
			(start 0.2794 0.6477)
			(end -0.2794 -0.6477)
			(stroke
				(width 0)
				(type default)
			)
			(fill no)
			(layer "B.CrtYd")
		)
		(fp_rect
			(start 0.2794 0.6477)
			(end -0.2794 -0.6477)
			(stroke
				(width 0)
				(type default)
			)
			(fill no)
			(layer "B.Fab")
		)
		(pad "1" smd custom
			(at 0 -0.2794 90)
			(size 0.0762 0.0762)
			(layers "B.Cu" "B.Mask" "B.Paste")
			(net "P1V8_C")
			(options
				(clearance outline)
				(anchor circle)
			)
			(primitives
				(gr_poly
					(pts
						(arc
							(start 0.1524 0.127)
							(mid 0.137521 0.162921)
							(end 0.1016 0.1778)
						)
						(arc
							(start -0.1016 0.1778)
							(mid -0.137521 0.162921)
							(end -0.1524 0.127)
						)
						(arc
							(start -0.1524 -0.127)
							(mid -0.137521 -0.162921)
							(end -0.1016 -0.1778)
						)
						(arc
							(start 0.1016 -0.1778)
							(mid 0.137521 -0.162921)
							(end 0.1524 -0.127)
						)
					)
					(width 0)
					(fill yes)
				)
			)
		)
		(pad "2" smd custom
			(at 0 0.2794 90)
			(size 0.0762 0.0762)
			(layers "B.Cu" "B.Mask" "B.Paste")
			(net "GND")
			(options
				(clearance outline)
				(anchor circle)
			)
			(primitives
				(gr_poly
					(pts
						(arc
							(start 0.1524 0.127)
							(mid 0.137521 0.162921)
							(end 0.1016 0.1778)
						)
						(arc
							(start -0.1016 0.1778)
							(mid -0.137521 0.162921)
							(end -0.1524 0.127)
						)
						(arc
							(start -0.1524 -0.127)
							(mid -0.137521 -0.162921)
							(end -0.1016 -0.1778)
						)
						(arc
							(start 0.1016 -0.1778)
							(mid 0.137521 -0.162921)
							(end 0.1524 -0.127)
						)
					)
					(width 0)
					(fill yes)
				)
			)
		)
	)
	(footprint ""
		(layer "B.Cu")
		(at 106.499914 -78.49997)
		(property "Reference" "TP43"
			(at 0 0 0)
			(layer "B.SilkS")
			(hide yes)
			(effects
				(font
					(size 1.27 1.27)
				)
				(justify mirror)
			)
		)
		(property "Value" "TPAD28-2-GP"
			(at 0.0127 -1.6637 0)
			(unlocked yes)
			(layer "B.Fab")
			(hide yes)
			(effects
				(font
					(size 1.016 1.016)
					(thickness 0.1524)
				)
				(justify mirror)
			)
		)
		(property "Device Type" "TPAD28"
			(at 0.0127 -3.1877 0)
			(unlocked yes)
			(layer "B.Fab")
			(hide yes)
			(effects
				(font
					(size 1.016 1.016)
					(thickness 0.1524)
				)
				(justify mirror)
			)
		)
		(duplicate_pad_numbers_are_jumpers no)
		(fp_poly
			(pts
				(arc
					(start 0.3556 0)
					(mid -0.3556 0)
					(end 0.3556 0)
				)
			)
			(stroke
				(width 0)
				(type default)
			)
			(fill no)
			(layer "B.CrtYd")
		)
		(fp_poly
			(pts
				(arc
					(start 0.6096 0)
					(mid -0.6096 0)
					(end 0.6096 0)
				)
			)
			(stroke
				(width 0)
				(type default)
			)
			(fill no)
			(layer "B.Fab")
		)
		(pad "1" smd circle
			(at 0 0 180)
			(size 0.7112 0.7112)
			(layers "B.Cu" "B.Mask" "B.Paste")
			(net "TESTIBIAS")
		)
	)
	(footprint ""
		(layer "B.Cu")
		(at 177.8127 -38.66896 90)
		(property "Reference" "C413"
			(at 0 0 90)
			(layer "B.SilkS")
			(hide yes)
			(effects
				(font
					(size 1.27 1.27)
				)
				(justify mirror)
			)
		)
		(property "Value" "SC1U6D3V1MX-GP"
			(at -1.9177 2.0193 90)
			(unlocked yes)
			(layer "B.Fab")
			(hide yes)
			(effects
				(font
					(size 1.016 1.016)
					(thickness 0.1524)
				)
				(justify mirror)
			)
		)
		(property "Device Type" "C0201H14"
			(at -1.9177 0.4953 90)
			(unlocked yes)
			(layer "B.Fab")
			(hide yes)
			(effects
				(font
					(size 1.016 1.016)
					(thickness 0.1524)
				)
				(justify mirror)
			)
		)
		(duplicate_pad_numbers_are_jumpers no)
		(fp_rect
			(start 0.1524 0.3048)
			(end -0.1524 -0.3048)
			(stroke
				(width 0)
				(type default)
			)
			(fill no)
			(layer "B.CrtYd")
		)
		(fp_poly
			(pts
				(xy 0.2794 0.6477) (xy 0.2794 -0.6477) (xy -0.2794 -0.6477) (xy -0.2794 -0.1905) (xy -0.1524 -0.1905)
				(xy -0.1524 -0.3048) (xy 0.1524 -0.3048) (xy 0.1524 0.3048) (xy -0.1524 0.3048) (xy -0.1524 -0.1778)
				(xy -0.2794 -0.1778) (xy -0.2794 0.6477)
			)
			(stroke
				(width 0)
				(type default)
			)
			(fill no)
			(layer "B.CrtYd")
		)
		(fp_rect
			(start 0.2794 0.6477)
			(end -0.2794 -0.6477)
			(stroke
				(width 0)
				(type default)
			)
			(fill no)
			(layer "B.Fab")
		)
		(pad "1" smd custom
			(at 0 -0.2794 270)
			(size 0.0762 0.0762)
			(layers "B.Cu" "B.Mask" "B.Paste")
			(net "P0V975")
			(options
				(clearance outline)
				(anchor circle)
			)
			(primitives
				(gr_poly
					(pts
						(arc
							(start 0.1524 0.127)
							(mid 0.137521 0.162921)
							(end 0.1016 0.1778)
						)
						(arc
							(start -0.1016 0.1778)
							(mid -0.137521 0.162921)
							(end -0.1524 0.127)
						)
						(arc
							(start -0.1524 -0.127)
							(mid -0.137521 -0.162921)
							(end -0.1016 -0.1778)
						)
						(arc
							(start 0.1016 -0.1778)
							(mid 0.137521 -0.162921)
							(end 0.1524 -0.127)
						)
					)
					(width 0)
					(fill yes)
				)
			)
		)
		(pad "2" smd custom
			(at 0 0.2794 270)
			(size 0.0762 0.0762)
			(layers "B.Cu" "B.Mask" "B.Paste")
			(net "GND")
			(options
				(clearance outline)
				(anchor circle)
			)
			(primitives
				(gr_poly
					(pts
						(arc
							(start 0.1524 0.127)
							(mid 0.137521 0.162921)
							(end 0.1016 0.1778)
						)
						(arc
							(start -0.1016 0.1778)
							(mid -0.137521 0.162921)
							(end -0.1524 0.127)
						)
						(arc
							(start -0.1524 -0.127)
							(mid -0.137521 -0.162921)
							(end -0.1016 -0.1778)
						)
						(arc
							(start 0.1016 -0.1778)
							(mid 0.137521 -0.162921)
							(end 0.1524 -0.127)
						)
					)
					(width 0)
					(fill yes)
				)
			)
		)
	)
	(footprint ""
		(layer "B.Cu")
		(at 70.485 -46.482 90)
		(property "Reference" "R167"
			(at 0 0 90)
			(layer "B.SilkS")
			(hide yes)
			(effects
				(font
					(size 1.27 1.27)
				)
				(justify mirror)
			)
		)
		(property "Value" "D51R3F-2-GP"
			(at 0.0254 -2.5146 90)
			(unlocked yes)
			(layer "B.Fab")
			(hide yes)
			(effects
				(font
					(size 1.016 1.016)
					(thickness 0.1524)
				)
				(justify mirror)
			)
		)
		(property "Device Type" "R603H22"
			(at 0.0254 -4.0386 90)
			(unlocked yes)
			(layer "B.Fab")
			(hide yes)
			(effects
				(font
					(size 1.016 1.016)
					(thickness 0.1524)
				)
				(justify mirror)
			)
		)
		(duplicate_pad_numbers_are_jumpers no)
		(fp_line
			(start 0.4826 0)
			(end 0.2032 0)
			(stroke
				(width 0.2032)
				(type default)
			)
			(layer "B.SilkS")
		)
		(fp_line
			(start -0.2032 0)
			(end -0.4826 0)
			(stroke
				(width 0.2032)
				(type default)
			)
			(layer "B.SilkS")
		)
		(fp_rect
			(start 0.5842 1.3335)
			(end -0.5842 -1.3335)
			(stroke
				(width 0)
				(type default)
			)
			(fill no)
			(layer "B.CrtYd")
		)
		(fp_rect
			(start 0.5842 1.3335)
			(end -0.5842 -1.3335)
			(stroke
				(width 0)
				(type default)
			)
			(fill no)
			(layer "B.Fab")
		)
		(pad "1" smd custom
			(at 0 -0.762 270)
			(size 0.2159 0.2159)
			(layers "B.Cu" "B.Mask" "B.Paste")
			(net "P0V9")
			(options
				(clearance outline)
				(anchor circle)
			)
			(primitives
				(gr_poly
					(pts
						(arc
							(start -0.3302 0.4318)
							(mid -0.402042 0.402042)
							(end -0.4318 0.3302)
						)
						(arc
							(start -0.4318 -0.3302)
							(mid -0.402042 -0.402042)
							(end -0.3302 -0.4318)
						)
						(arc
							(start 0.3302 -0.4318)
							(mid 0.402042 -0.402042)
							(end 0.4318 -0.3302)
						)
						(arc
							(start 0.4318 0.3302)
							(mid 0.402042 0.402042)
							(end 0.3302 0.4318)
						)
					)
					(width 0)
					(fill yes)
				)
			)
		)
		(pad "2" smd custom
			(at 0 0.762 270)
			(size 0.2159 0.2159)
			(layers "B.Cu" "B.Mask" "B.Paste")
			(net "GB_VDDA")
			(options
				(clearance outline)
				(anchor circle)
			)
			(primitives
				(gr_poly
					(pts
						(arc
							(start -0.3302 0.4318)
							(mid -0.402042 0.402042)
							(end -0.4318 0.3302)
						)
						(arc
							(start -0.4318 -0.3302)
							(mid -0.402042 -0.402042)
							(end -0.3302 -0.4318)
						)
						(arc
							(start 0.3302 -0.4318)
							(mid 0.402042 -0.402042)
							(end 0.4318 -0.3302)
						)
						(arc
							(start 0.4318 0.3302)
							(mid 0.402042 0.402042)
							(end 0.3302 0.4318)
						)
					)
					(width 0)
					(fill yes)
				)
			)
		)
	)
	(footprint ""
		(layer "B.Cu")
		(at 107.517438 -65.786 180)
		(property "Reference" "C206"
			(at 0 0 0)
			(layer "B.SilkS")
			(hide yes)
			(effects
				(font
					(size 1.27 1.27)
				)
				(justify mirror)
			)
		)
		(property "Value" "SC1U6D3V1MX-GP"
			(at -1.9177 2.0193 180)
			(unlocked yes)
			(layer "B.Fab")
			(hide yes)
			(effects
				(font
					(size 1.016 1.016)
					(thickness 0.1524)
				)
				(justify mirror)
			)
		)
		(property "Device Type" "C0201H14"
			(at -1.9177 0.4953 180)
			(unlocked yes)
			(layer "B.Fab")
			(hide yes)
			(effects
				(font
					(size 1.016 1.016)
					(thickness 0.1524)
				)
				(justify mirror)
			)
		)
		(duplicate_pad_numbers_are_jumpers no)
		(fp_rect
			(start 0.1524 0.3048)
			(end -0.1524 -0.3048)
			(stroke
				(width 0)
				(type default)
			)
			(fill no)
			(layer "B.CrtYd")
		)
		(fp_poly
			(pts
				(xy 0.2794 0.6477) (xy 0.2794 -0.6477) (xy -0.2794 -0.6477) (xy -0.2794 -0.1905) (xy -0.1524 -0.1905)
				(xy -0.1524 -0.3048) (xy 0.1524 -0.3048) (xy 0.1524 0.3048) (xy -0.1524 0.3048) (xy -0.1524 -0.1778)
				(xy -0.2794 -0.1778) (xy -0.2794 0.6477)
			)
			(stroke
				(width 0)
				(type default)
			)
			(fill no)
			(layer "B.CrtYd")
		)
		(fp_rect
			(start 0.2794 0.6477)
			(end -0.2794 -0.6477)
			(stroke
				(width 0)
				(type default)
			)
			(fill no)
			(layer "B.Fab")
		)
		(pad "1" smd custom
			(at 0 -0.2794)
			(size 0.0762 0.0762)
			(layers "B.Cu" "B.Mask" "B.Paste")
			(net "XTAL_VDDA09")
			(options
				(clearance outline)
				(anchor circle)
			)
			(primitives
				(gr_poly
					(pts
						(arc
							(start 0.1524 0.127)
							(mid 0.137521 0.162921)
							(end 0.1016 0.1778)
						)
						(arc
							(start -0.1016 0.1778)
							(mid -0.137521 0.162921)
							(end -0.1524 0.127)
						)
						(arc
							(start -0.1524 -0.127)
							(mid -0.137521 -0.162921)
							(end -0.1016 -0.1778)
						)
						(arc
							(start 0.1016 -0.1778)
							(mid 0.137521 -0.162921)
							(end 0.1524 -0.127)
						)
					)
					(width 0)
					(fill yes)
				)
			)
		)
		(pad "2" smd custom
			(at 0 0.2794)
			(size 0.0762 0.0762)
			(layers "B.Cu" "B.Mask" "B.Paste")
			(net "GND")
			(options
				(clearance outline)
				(anchor circle)
			)
			(primitives
				(gr_poly
					(pts
						(arc
							(start 0.1524 0.127)
							(mid 0.137521 0.162921)
							(end 0.1016 0.1778)
						)
						(arc
							(start -0.1016 0.1778)
							(mid -0.137521 0.162921)
							(end -0.1524 0.127)
						)
						(arc
							(start -0.1524 -0.127)
							(mid -0.137521 -0.162921)
							(end -0.1016 -0.1778)
						)
						(arc
							(start 0.1016 -0.1778)
							(mid 0.137521 -0.162921)
							(end 0.1524 -0.127)
						)
					)
					(width 0)
					(fill yes)
				)
			)
		)
	)
	(footprint ""
		(layer "B.Cu")
		(at 146.2532 -123.9266 -90)
		(property "Reference" "R601"
			(at 0 0 90)
			(layer "B.SilkS")
			(hide yes)
			(effects
				(font
					(size 1.27 1.27)
				)
				(justify mirror)
			)
		)
		(property "Value" "0R2J-2-GP"
			(at -0.064008 -3.993896 270)
			(unlocked yes)
			(layer "B.Fab")
			(hide yes)
			(effects
				(font
					(size 1.016 1.016)
					(thickness 0.1524)
				)
				(justify mirror)
			)
		)
		(property "Device Type" "R402H16"
			(at -0.064008 -5.517896 270)
			(unlocked yes)
			(layer "B.Fab")
			(hide yes)
			(effects
				(font
					(size 1.016 1.016)
					(thickness 0.1524)
				)
				(justify mirror)
			)
		)
		(duplicate_pad_numbers_are_jumpers no)
		(fp_line
			(start -0.508 -0.9398)
			(end 0.508 -0.9398)
			(stroke
				(width 0.1524)
				(type default)
			)
			(layer "B.SilkS")
		)
		(fp_line
			(start 0.508 -0.9398)
			(end 0.508 0.9398)
			(stroke
				(width 0.1524)
				(type default)
			)
			(layer "B.SilkS")
		)
		(fp_rect
			(start 0.508 0.9398)
			(end -0.508 -0.9398)
			(stroke
				(width 0)
				(type default)
			)
			(fill no)
			(layer "B.CrtYd")
		)
		(fp_rect
			(start 0.508 0.9398)
			(end -0.508 -0.9398)
			(stroke
				(width 0)
				(type default)
			)
			(fill no)
			(layer "B.Fab")
		)
		(pad "1" smd custom
			(at 0 -0.4445 90)
			(size 0.1397 0.1397)
			(layers "B.Cu" "B.Mask" "B.Paste")
			(net "P1V5_C_PG")
			(options
				(clearance outline)
				(anchor circle)
			)
			(primitives
				(gr_poly
					(pts
						(arc
							(start -0.1778 0.2794)
							(mid -0.249642 0.249642)
							(end -0.2794 0.1778)
						)
						(arc
							(start -0.2794 -0.1778)
							(mid -0.249642 -0.249642)
							(end -0.1778 -0.2794)
						)
						(arc
							(start 0.1778 -0.2794)
							(mid 0.249642 -0.249642)
							(end 0.2794 -0.1778)
						)
						(arc
							(start 0.2794 0.1778)
							(mid 0.249642 0.249642)
							(end 0.1778 0.2794)
						)
					)
					(width 0)
					(fill yes)
				)
			)
		)
		(pad "2" smd custom
			(at 0 0.4445 90)
			(size 0.1397 0.1397)
			(layers "B.Cu" "B.Mask" "B.Paste")
			(net "P1V5_C_PG_R_1")
			(options
				(clearance outline)
				(anchor circle)
			)
			(primitives
				(gr_poly
					(pts
						(arc
							(start -0.1778 0.2794)
							(mid -0.249642 0.249642)
							(end -0.2794 0.1778)
						)
						(arc
							(start -0.2794 -0.1778)
							(mid -0.249642 -0.249642)
							(end -0.1778 -0.2794)
						)
						(arc
							(start 0.1778 -0.2794)
							(mid 0.249642 -0.249642)
							(end 0.2794 -0.1778)
						)
						(arc
							(start 0.2794 0.1778)
							(mid 0.249642 0.249642)
							(end 0.1778 0.2794)
						)
					)
					(width 0)
					(fill yes)
				)
			)
		)
	)
	(footprint ""
		(layer "B.Cu")
		(at 119.4054 -59.4487)
		(property "Reference" "C291"
			(at 0 0 0)
			(layer "B.SilkS")
			(hide yes)
			(effects
				(font
					(size 1.27 1.27)
				)
				(justify mirror)
			)
		)
		(property "Value" "SCD1U6D3V1KX-GP"
			(at 2.8321 -1.7399 0)
			(unlocked yes)
			(layer "B.Fab")
			(hide yes)
			(effects
				(font
					(size 1.016 1.016)
					(thickness 0.1524)
				)
				(justify mirror)
			)
		)
		(property "Device Type" "C0201H13"
			(at 2.8321 -3.2639 0)
			(unlocked yes)
			(layer "B.Fab")
			(hide yes)
			(effects
				(font
					(size 1.016 1.016)
					(thickness 0.1524)
				)
				(justify mirror)
			)
		)
		(duplicate_pad_numbers_are_jumpers no)
		(fp_rect
			(start 0.2794 0.6477)
			(end -0.2794 -0.6477)
			(stroke
				(width 0)
				(type default)
			)
			(fill no)
			(layer "B.CrtYd")
		)
		(fp_rect
			(start 0.2794 0.6477)
			(end -0.2794 -0.6477)
			(stroke
				(width 0)
				(type default)
			)
			(fill no)
			(layer "B.Fab")
		)
		(pad "1" smd custom
			(at 0 -0.2794 180)
			(size 0.0762 0.0762)
			(layers "B.Cu" "B.Mask" "B.Paste")
			(net "GB_VDDA")
			(options
				(clearance outline)
				(anchor circle)
			)
			(primitives
				(gr_poly
					(pts
						(arc
							(start 0.1524 0.127)
							(mid 0.137521 0.162921)
							(end 0.1016 0.1778)
						)
						(arc
							(start -0.1016 0.1778)
							(mid -0.137521 0.162921)
							(end -0.1524 0.127)
						)
						(arc
							(start -0.1524 -0.127)
							(mid -0.137521 -0.162921)
							(end -0.1016 -0.1778)
						)
						(arc
							(start 0.1016 -0.1778)
							(mid 0.137521 -0.162921)
							(end 0.1524 -0.127)
						)
					)
					(width 0)
					(fill yes)
				)
			)
		)
		(pad "2" smd custom
			(at 0 0.2794 180)
			(size 0.0762 0.0762)
			(layers "B.Cu" "B.Mask" "B.Paste")
			(net "GND")
			(options
				(clearance outline)
				(anchor circle)
			)
			(primitives
				(gr_poly
					(pts
						(arc
							(start 0.1524 0.127)
							(mid 0.137521 0.162921)
							(end 0.1016 0.1778)
						)
						(arc
							(start -0.1016 0.1778)
							(mid -0.137521 0.162921)
							(end -0.1524 0.127)
						)
						(arc
							(start -0.1524 -0.127)
							(mid -0.137521 -0.162921)
							(end -0.1016 -0.1778)
						)
						(arc
							(start 0.1016 -0.1778)
							(mid 0.137521 -0.162921)
							(end 0.1524 -0.127)
						)
					)
					(width 0)
					(fill yes)
				)
			)
		)
	)
	(footprint ""
		(layer "B.Cu")
		(at 176.276 -53.3908 -90)
		(property "Reference" "R498"
			(at 0 0 90)
			(layer "B.SilkS")
			(hide yes)
			(effects
				(font
					(size 1.27 1.27)
				)
				(justify mirror)
			)
		)
		(property "Value" "0R2J-2-GP"
			(at -0.064008 -3.993896 270)
			(unlocked yes)
			(layer "B.Fab")
			(hide yes)
			(effects
				(font
					(size 1.016 1.016)
					(thickness 0.1524)
				)
				(justify mirror)
			)
		)
		(property "Device Type" "R402H16"
			(at -0.064008 -5.517896 270)
			(unlocked yes)
			(layer "B.Fab")
			(hide yes)
			(effects
				(font
					(size 1.016 1.016)
					(thickness 0.1524)
				)
				(justify mirror)
			)
		)
		(duplicate_pad_numbers_are_jumpers no)
		(fp_line
			(start -0.508 -0.9398)
			(end 0.508 -0.9398)
			(stroke
				(width 0.1524)
				(type default)
			)
			(layer "B.SilkS")
		)
		(fp_line
			(start 0.508 -0.9398)
			(end 0.508 0.9398)
			(stroke
				(width 0.1524)
				(type default)
			)
			(layer "B.SilkS")
		)
		(fp_rect
			(start 0.508 0.9398)
			(end -0.508 -0.9398)
			(stroke
				(width 0)
				(type default)
			)
			(fill no)
			(layer "B.CrtYd")
		)
		(fp_rect
			(start 0.508 0.9398)
			(end -0.508 -0.9398)
			(stroke
				(width 0)
				(type default)
			)
			(fill no)
			(layer "B.Fab")
		)
		(pad "1" smd custom
			(at 0 -0.4445 90)
			(size 0.1397 0.1397)
			(layers "B.Cu" "B.Mask" "B.Paste")
			(net "GND")
			(options
				(clearance outline)
				(anchor circle)
			)
			(primitives
				(gr_poly
					(pts
						(arc
							(start -0.1778 0.2794)
							(mid -0.249642 0.249642)
							(end -0.2794 0.1778)
						)
						(arc
							(start -0.2794 -0.1778)
							(mid -0.249642 -0.249642)
							(end -0.1778 -0.2794)
						)
						(arc
							(start 0.1778 -0.2794)
							(mid 0.249642 -0.249642)
							(end 0.2794 -0.1778)
						)
						(arc
							(start 0.2794 0.1778)
							(mid 0.249642 0.249642)
							(end 0.1778 0.2794)
						)
					)
					(width 0)
					(fill yes)
				)
			)
		)
		(pad "2" smd custom
			(at 0 0.4445 90)
			(size 0.1397 0.1397)
			(layers "B.Cu" "B.Mask" "B.Paste")
			(net "GND_SENSE")
			(options
				(clearance outline)
				(anchor circle)
			)
			(primitives
				(gr_poly
					(pts
						(arc
							(start -0.1778 0.2794)
							(mid -0.249642 0.249642)
							(end -0.2794 0.1778)
						)
						(arc
							(start -0.2794 -0.1778)
							(mid -0.249642 -0.249642)
							(end -0.1778 -0.2794)
						)
						(arc
							(start 0.1778 -0.2794)
							(mid 0.249642 -0.249642)
							(end 0.2794 -0.1778)
						)
						(arc
							(start 0.2794 0.1778)
							(mid 0.249642 0.249642)
							(end 0.1778 0.2794)
						)
					)
					(width 0)
					(fill yes)
				)
			)
		)
	)
	(footprint ""
		(layer "B.Cu")
		(at 133.5278 -123.2154 -90)
		(property "Reference" "Q9"
			(at 0 0 90)
			(layer "B.SilkS")
			(hide yes)
			(effects
				(font
					(size 1.27 1.27)
				)
				(justify mirror)
			)
		)
		(property "Value" "SSM3K324R-GP"
			(at -0.127 -8.9662 270)
			(unlocked yes)
			(layer "B.Fab")
			(hide yes)
			(effects
				(font
					(size 1.016 1.016)
					(thickness 0.1524)
				)
				(justify mirror)
			)
		)
		(property "Device Type" "SOT23DGS2D4H35"
			(at -0.127 -10.4902 270)
			(unlocked yes)
			(layer "B.Fab")
			(hide yes)
			(effects
				(font
					(size 1.016 1.016)
					(thickness 0.1524)
				)
				(justify mirror)
			)
		)
		(duplicate_pad_numbers_are_jumpers no)
		(fp_line
			(start -1.651 1.778)
			(end -1.651 -1.778)
			(stroke
				(width 0.1524)
				(type default)
			)
			(layer "B.SilkS")
		)
		(fp_line
			(start 1.651 1.778)
			(end -1.651 1.778)
			(stroke
				(width 0.1524)
				(type default)
			)
			(layer "B.SilkS")
		)
		(fp_line
			(start -1.651 -1.778)
			(end 1.651 -1.778)
			(stroke
				(width 0.1524)
				(type default)
			)
			(layer "B.SilkS")
		)
		(fp_line
			(start 1.651 -1.778)
			(end 1.651 1.778)
			(stroke
				(width 0.1524)
				(type default)
			)
			(layer "B.SilkS")
		)
		(fp_poly
			(pts
				(xy 1.778 1.8796) (xy 1.778 -1.8796) (xy -1.778 -1.8796) (xy -1.778 1.8796)
			)
			(stroke
				(width 0)
				(type default)
			)
			(fill no)
			(layer "B.CrtYd")
		)
		(fp_poly
			(pts
				(xy 1.778 1.8796) (xy 1.778 -1.8796) (xy -1.778 -1.8796) (xy -1.778 1.8796)
			)
			(stroke
				(width 0)
				(type default)
			)
			(fill no)
			(layer "B.Fab")
		)
		(pad "D" smd custom
			(at 0 -0.9525 90)
			(size 0.1905 0.1905)
			(layers "B.Cu" "B.Mask" "B.Paste")
			(net "P12V_STBY_Q10_G")
			(options
				(clearance outline)
				(anchor circle)
			)
			(primitives
				(gr_poly
					(pts
						(arc
							(start -0.1778 -0.5715)
							(mid -0.321484 -0.511984)
							(end -0.381 -0.3683)
						)
						(arc
							(start -0.381 0.3683)
							(mid -0.321484 0.511984)
							(end -0.1778 0.5715)
						)
						(arc
							(start 0.1778 0.5715)
							(mid 0.321484 0.511984)
							(end 0.381 0.3683)
						)
						(arc
							(start 0.381 -0.3683)
							(mid 0.321484 -0.511984)
							(end 0.1778 -0.5715)
						)
					)
					(width 0)
					(fill yes)
				)
			)
		)
		(pad "G" smd custom
			(at 0.98425 0.9525 90)
			(size 0.1905 0.1905)
			(layers "B.Cu" "B.Mask" "B.Paste")
			(net "P1V5_C_G")
			(options
				(clearance outline)
				(anchor circle)
			)
			(primitives
				(gr_poly
					(pts
						(arc
							(start -0.1778 -0.5715)
							(mid -0.321484 -0.511984)
							(end -0.381 -0.3683)
						)
						(arc
							(start -0.381 0.3683)
							(mid -0.321484 0.511984)
							(end -0.1778 0.5715)
						)
						(arc
							(start 0.1778 0.5715)
							(mid 0.321484 0.511984)
							(end 0.381 0.3683)
						)
						(arc
							(start 0.381 -0.3683)
							(mid 0.321484 -0.511984)
							(end 0.1778 -0.5715)
						)
					)
					(width 0)
					(fill yes)
				)
			)
		)
		(pad "S" smd custom
			(at -0.98425 0.9525 90)
			(size 0.1905 0.1905)
			(layers "B.Cu" "B.Mask" "B.Paste")
			(net "GND")
			(options
				(clearance outline)
				(anchor circle)
			)
			(primitives
				(gr_poly
					(pts
						(arc
							(start -0.1778 -0.5715)
							(mid -0.321484 -0.511984)
							(end -0.381 -0.3683)
						)
						(arc
							(start -0.381 0.3683)
							(mid -0.321484 0.511984)
							(end -0.1778 0.5715)
						)
						(arc
							(start 0.1778 0.5715)
							(mid 0.321484 0.511984)
							(end 0.381 0.3683)
						)
						(arc
							(start 0.381 -0.3683)
							(mid 0.321484 -0.511984)
							(end 0.1778 -0.5715)
						)
					)
					(width 0)
					(fill yes)
				)
			)
		)
	)
	(footprint ""
		(layer "B.Cu")
		(at 126.0094 -89.8144 180)
		(property "Reference" "R41"
			(at 0 0 0)
			(layer "B.SilkS")
			(hide yes)
			(effects
				(font
					(size 1.27 1.27)
				)
				(justify mirror)
			)
		)
		(property "Value" "4K7R2F-GP"
			(at -0.064008 -3.993896 180)
			(unlocked yes)
			(layer "B.Fab")
			(hide yes)
			(effects
				(font
					(size 1.016 1.016)
					(thickness 0.1524)
				)
				(justify mirror)
			)
		)
		(property "Device Type" "R402H16"
			(at -0.064008 -5.517896 180)
			(unlocked yes)
			(layer "B.Fab")
			(hide yes)
			(effects
				(font
					(size 1.016 1.016)
					(thickness 0.1524)
				)
				(justify mirror)
			)
		)
		(duplicate_pad_numbers_are_jumpers no)
		(fp_line
			(start 0.508 -0.9398)
			(end 0.508 0.9398)
			(stroke
				(width 0.1524)
				(type default)
			)
			(layer "B.SilkS")
		)
		(fp_line
			(start -0.508 -0.9398)
			(end 0.508 -0.9398)
			(stroke
				(width 0.1524)
				(type default)
			)
			(layer "B.SilkS")
		)
		(fp_rect
			(start 0.508 0.9398)
			(end -0.508 -0.9398)
			(stroke
				(width 0)
				(type default)
			)
			(fill no)
			(layer "B.CrtYd")
		)
		(fp_rect
			(start 0.508 0.9398)
			(end -0.508 -0.9398)
			(stroke
				(width 0)
				(type default)
			)
			(fill no)
			(layer "B.Fab")
		)
		(pad "1" smd custom
			(at 0 -0.4445)
			(size 0.1397 0.1397)
			(layers "B.Cu" "B.Mask" "B.Paste")
			(net "EXP_SIO_LOAD_OUT")
			(options
				(clearance outline)
				(anchor circle)
			)
			(primitives
				(gr_poly
					(pts
						(arc
							(start -0.1778 0.2794)
							(mid -0.249642 0.249642)
							(end -0.2794 0.1778)
						)
						(arc
							(start -0.2794 -0.1778)
							(mid -0.249642 -0.249642)
							(end -0.1778 -0.2794)
						)
						(arc
							(start 0.1778 -0.2794)
							(mid 0.249642 -0.249642)
							(end 0.2794 -0.1778)
						)
						(arc
							(start 0.2794 0.1778)
							(mid 0.249642 0.249642)
							(end 0.1778 0.2794)
						)
					)
					(width 0)
					(fill yes)
				)
			)
		)
		(pad "2" smd custom
			(at 0 0.4445)
			(size 0.1397 0.1397)
			(layers "B.Cu" "B.Mask" "B.Paste")
			(net "P1V8_E")
			(options
				(clearance outline)
				(anchor circle)
			)
			(primitives
				(gr_poly
					(pts
						(arc
							(start -0.1778 0.2794)
							(mid -0.249642 0.249642)
							(end -0.2794 0.1778)
						)
						(arc
							(start -0.2794 -0.1778)
							(mid -0.249642 -0.249642)
							(end -0.1778 -0.2794)
						)
						(arc
							(start 0.1778 -0.2794)
							(mid 0.249642 -0.249642)
							(end 0.2794 -0.1778)
						)
						(arc
							(start 0.2794 0.1778)
							(mid 0.249642 0.249642)
							(end 0.1778 0.2794)
						)
					)
					(width 0)
					(fill yes)
				)
			)
		)
	)
	(footprint ""
		(layer "B.Cu")
		(at 179.438808 -38.10889 90)
		(property "Reference" "C439"
			(at 0 0 90)
			(layer "B.SilkS")
			(hide yes)
			(effects
				(font
					(size 1.27 1.27)
				)
				(justify mirror)
			)
		)
		(property "Value" "SCD1U6D3V1KX-GP"
			(at 2.8321 -1.7399 90)
			(unlocked yes)
			(layer "B.Fab")
			(hide yes)
			(effects
				(font
					(size 1.016 1.016)
					(thickness 0.1524)
				)
				(justify mirror)
			)
		)
		(property "Device Type" "C0201H13"
			(at 2.8321 -3.2639 90)
			(unlocked yes)
			(layer "B.Fab")
			(hide yes)
			(effects
				(font
					(size 1.016 1.016)
					(thickness 0.1524)
				)
				(justify mirror)
			)
		)
		(duplicate_pad_numbers_are_jumpers no)
		(fp_rect
			(start 0.2794 0.6477)
			(end -0.2794 -0.6477)
			(stroke
				(width 0)
				(type default)
			)
			(fill no)
			(layer "B.CrtYd")
		)
		(fp_rect
			(start 0.2794 0.6477)
			(end -0.2794 -0.6477)
			(stroke
				(width 0)
				(type default)
			)
			(fill no)
			(layer "B.Fab")
		)
		(pad "1" smd custom
			(at 0 -0.2794 270)
			(size 0.0762 0.0762)
			(layers "B.Cu" "B.Mask" "B.Paste")
			(net "P0V975")
			(options
				(clearance outline)
				(anchor circle)
			)
			(primitives
				(gr_poly
					(pts
						(arc
							(start 0.1524 0.127)
							(mid 0.137521 0.162921)
							(end 0.1016 0.1778)
						)
						(arc
							(start -0.1016 0.1778)
							(mid -0.137521 0.162921)
							(end -0.1524 0.127)
						)
						(arc
							(start -0.1524 -0.127)
							(mid -0.137521 -0.162921)
							(end -0.1016 -0.1778)
						)
						(arc
							(start 0.1016 -0.1778)
							(mid 0.137521 -0.162921)
							(end 0.1524 -0.127)
						)
					)
					(width 0)
					(fill yes)
				)
			)
		)
		(pad "2" smd custom
			(at 0 0.2794 270)
			(size 0.0762 0.0762)
			(layers "B.Cu" "B.Mask" "B.Paste")
			(net "GND")
			(options
				(clearance outline)
				(anchor circle)
			)
			(primitives
				(gr_poly
					(pts
						(arc
							(start 0.1524 0.127)
							(mid 0.137521 0.162921)
							(end 0.1016 0.1778)
						)
						(arc
							(start -0.1016 0.1778)
							(mid -0.137521 0.162921)
							(end -0.1524 0.127)
						)
						(arc
							(start -0.1524 -0.127)
							(mid -0.137521 -0.162921)
							(end -0.1016 -0.1778)
						)
						(arc
							(start 0.1016 -0.1778)
							(mid 0.137521 -0.162921)
							(end 0.1524 -0.127)
						)
					)
					(width 0)
					(fill yes)
				)
			)
		)
	)
	(footprint ""
		(layer "B.Cu")
		(at 159.2326 -111.0996)
		(property "Reference" "C699"
			(at 0 0 0)
			(layer "B.SilkS")
			(hide yes)
			(effects
				(font
					(size 1.27 1.27)
				)
				(justify mirror)
			)
		)
		(property "Value" "SC10U16V5KX-7-GP-U"
			(at 0.0762 -6.1214 0)
			(unlocked yes)
			(layer "B.Fab")
			(hide yes)
			(effects
				(font
					(size 1.016 1.016)
					(thickness 0.1524)
				)
				(justify mirror)
			)
		)
		(property "Device Type" "C805H58"
			(at 0.0762 -8.1534 0)
			(unlocked yes)
			(layer "B.Fab")
			(hide yes)
			(effects
				(font
					(size 1.016 1.016)
					(thickness 0.1524)
				)
				(justify mirror)
			)
		)
		(duplicate_pad_numbers_are_jumpers no)
		(fp_line
			(start -0.635 0)
			(end 0.635 0)
			(stroke
				(width 0.508)
				(type default)
			)
			(layer "B.SilkS")
		)
		(fp_rect
			(start 0.9652 1.778)
			(end -0.9652 -1.778)
			(stroke
				(width 0)
				(type default)
			)
			(fill no)
			(layer "B.CrtYd")
		)
		(fp_poly
			(pts
				(xy 0.9652 -1.778) (xy -0.9652 -1.778) (xy -0.9652 1.778) (xy 0.9652 1.778)
			)
			(stroke
				(width 0)
				(type default)
			)
			(fill no)
			(layer "B.Fab")
		)
		(pad "1" smd rect
			(at 0 -0.9652 180)
			(size 1.397 1.143)
			(layers "B.Cu" "B.Mask" "B.Paste")
			(net "P12V_STBY_VIN_U11")
		)
		(pad "2" smd rect
			(at 0 0.9652 180)
			(size 1.397 1.143)
			(layers "B.Cu" "B.Mask" "B.Paste")
			(net "GND")
		)
	)
	(footprint ""
		(layer "B.Cu")
		(at 42.910252 -108.17098 -90)
		(property "Reference" "C347"
			(at 0 0 90)
			(layer "B.SilkS")
			(hide yes)
			(effects
				(font
					(size 1.27 1.27)
				)
				(justify mirror)
			)
		)
		(property "Value" "SC4D7U25V5KX-1-GP"
			(at 0.0762 -6.1214 270)
			(unlocked yes)
			(layer "B.Fab")
			(hide yes)
			(effects
				(font
					(size 1.016 1.016)
					(thickness 0.1524)
				)
				(justify mirror)
			)
		)
		(property "Device Type" "C805H58"
			(at 0.0762 -8.1534 270)
			(unlocked yes)
			(layer "B.Fab")
			(hide yes)
			(effects
				(font
					(size 1.016 1.016)
					(thickness 0.1524)
				)
				(justify mirror)
			)
		)
		(duplicate_pad_numbers_are_jumpers no)
		(fp_line
			(start -0.635 0)
			(end 0.635 0)
			(stroke
				(width 0.508)
				(type default)
			)
			(layer "B.SilkS")
		)
		(fp_rect
			(start 0.9652 1.778)
			(end -0.9652 -1.778)
			(stroke
				(width 0)
				(type default)
			)
			(fill no)
			(layer "B.CrtYd")
		)
		(fp_poly
			(pts
				(xy 0.9652 -1.778) (xy -0.9652 -1.778) (xy -0.9652 1.778) (xy 0.9652 1.778)
			)
			(stroke
				(width 0)
				(type default)
			)
			(fill no)
			(layer "B.Fab")
		)
		(pad "1" smd rect
			(at 0 -0.9652 90)
			(size 1.397 1.143)
			(layers "B.Cu" "B.Mask" "B.Paste")
			(net "P12V_STBY_SCC")
		)
		(pad "2" smd rect
			(at 0 0.9652 90)
			(size 1.397 1.143)
			(layers "B.Cu" "B.Mask" "B.Paste")
			(net "GND")
		)
	)
	(footprint ""
		(layer "B.Cu")
		(at 170.67149 -47.587154 -90)
		(property "Reference" "C406"
			(at 0 0 90)
			(layer "B.SilkS")
			(hide yes)
			(effects
				(font
					(size 1.27 1.27)
				)
				(justify mirror)
			)
		)
		(property "Value" "SC10U6D3V5KX-4GP"
			(at 0.0762 -6.1214 270)
			(unlocked yes)
			(layer "B.Fab")
			(hide yes)
			(effects
				(font
					(size 1.016 1.016)
					(thickness 0.1524)
				)
				(justify mirror)
			)
		)
		(property "Device Type" "C805H58"
			(at 0.0762 -8.1534 270)
			(unlocked yes)
			(layer "B.Fab")
			(hide yes)
			(effects
				(font
					(size 1.016 1.016)
					(thickness 0.1524)
				)
				(justify mirror)
			)
		)
		(duplicate_pad_numbers_are_jumpers no)
		(fp_line
			(start -0.635 0)
			(end 0.635 0)
			(stroke
				(width 0.508)
				(type default)
			)
			(layer "B.SilkS")
		)
		(fp_rect
			(start 0.9652 1.778)
			(end -0.9652 -1.778)
			(stroke
				(width 0)
				(type default)
			)
			(fill no)
			(layer "B.CrtYd")
		)
		(fp_poly
			(pts
				(xy 0.9652 -1.778) (xy -0.9652 -1.778) (xy -0.9652 1.778) (xy 0.9652 1.778)
			)
			(stroke
				(width 0)
				(type default)
			)
			(fill no)
			(layer "B.Fab")
		)
		(pad "1" smd rect
			(at 0 -0.9652 90)
			(size 1.397 1.143)
			(layers "B.Cu" "B.Mask" "B.Paste")
			(net "P0V975")
		)
		(pad "2" smd rect
			(at 0 0.9652 90)
			(size 1.397 1.143)
			(layers "B.Cu" "B.Mask" "B.Paste")
			(net "GND")
		)
	)
	(footprint ""
		(layer "B.Cu")
		(at 200.787 -35.3314 180)
		(property "Reference" "R208"
			(at 0 0 0)
			(layer "B.SilkS")
			(hide yes)
			(effects
				(font
					(size 1.27 1.27)
				)
				(justify mirror)
			)
		)
		(property "Value" "4K7R2F-GP"
			(at -0.064008 -3.993896 180)
			(unlocked yes)
			(layer "B.Fab")
			(hide yes)
			(effects
				(font
					(size 1.016 1.016)
					(thickness 0.1524)
				)
				(justify mirror)
			)
		)
		(property "Device Type" "R402H16"
			(at -0.064008 -5.517896 180)
			(unlocked yes)
			(layer "B.Fab")
			(hide yes)
			(effects
				(font
					(size 1.016 1.016)
					(thickness 0.1524)
				)
				(justify mirror)
			)
		)
		(duplicate_pad_numbers_are_jumpers no)
		(fp_line
			(start 0.508 -0.9398)
			(end 0.508 0.9398)
			(stroke
				(width 0.1524)
				(type default)
			)
			(layer "B.SilkS")
		)
		(fp_line
			(start -0.508 -0.9398)
			(end 0.508 -0.9398)
			(stroke
				(width 0.1524)
				(type default)
			)
			(layer "B.SilkS")
		)
		(fp_rect
			(start 0.508 0.9398)
			(end -0.508 -0.9398)
			(stroke
				(width 0)
				(type default)
			)
			(fill no)
			(layer "B.CrtYd")
		)
		(fp_rect
			(start 0.508 0.9398)
			(end -0.508 -0.9398)
			(stroke
				(width 0)
				(type default)
			)
			(fill no)
			(layer "B.Fab")
		)
		(pad "1" smd custom
			(at 0 -0.4445)
			(size 0.1397 0.1397)
			(layers "B.Cu" "B.Mask" "B.Paste")
			(net "P1V8_C")
			(options
				(clearance outline)
				(anchor circle)
			)
			(primitives
				(gr_poly
					(pts
						(arc
							(start -0.1778 0.2794)
							(mid -0.249642 0.249642)
							(end -0.2794 0.1778)
						)
						(arc
							(start -0.2794 -0.1778)
							(mid -0.249642 -0.249642)
							(end -0.1778 -0.2794)
						)
						(arc
							(start 0.1778 -0.2794)
							(mid 0.249642 -0.249642)
							(end 0.2794 -0.1778)
						)
						(arc
							(start 0.2794 0.1778)
							(mid 0.249642 0.249642)
							(end 0.1778 0.2794)
						)
					)
					(width 0)
					(fill yes)
				)
			)
		)
		(pad "2" smd custom
			(at 0 0.4445)
			(size 0.1397 0.1397)
			(layers "B.Cu" "B.Mask" "B.Paste")
			(net "IOC_EEPROM_A1")
			(options
				(clearance outline)
				(anchor circle)
			)
			(primitives
				(gr_poly
					(pts
						(arc
							(start -0.1778 0.2794)
							(mid -0.249642 0.249642)
							(end -0.2794 0.1778)
						)
						(arc
							(start -0.2794 -0.1778)
							(mid -0.249642 -0.249642)
							(end -0.1778 -0.2794)
						)
						(arc
							(start 0.1778 -0.2794)
							(mid 0.249642 -0.249642)
							(end 0.2794 -0.1778)
						)
						(arc
							(start 0.2794 0.1778)
							(mid 0.249642 0.249642)
							(end 0.1778 0.2794)
						)
					)
					(width 0)
					(fill yes)
				)
			)
		)
	)
	(footprint ""
		(layer "B.Cu")
		(at 111.76 -70.3834 180)
		(property "Reference" "C181"
			(at 0 0 0)
			(layer "B.SilkS")
			(hide yes)
			(effects
				(font
					(size 1.27 1.27)
				)
				(justify mirror)
			)
		)
		(property "Value" "SCD1U6D3V1KX-GP"
			(at 2.8321 -1.7399 180)
			(unlocked yes)
			(layer "B.Fab")
			(hide yes)
			(effects
				(font
					(size 1.016 1.016)
					(thickness 0.1524)
				)
				(justify mirror)
			)
		)
		(property "Device Type" "C0201H13"
			(at 2.8321 -3.2639 180)
			(unlocked yes)
			(layer "B.Fab")
			(hide yes)
			(effects
				(font
					(size 1.016 1.016)
					(thickness 0.1524)
				)
				(justify mirror)
			)
		)
		(duplicate_pad_numbers_are_jumpers no)
		(fp_rect
			(start 0.2794 0.6477)
			(end -0.2794 -0.6477)
			(stroke
				(width 0)
				(type default)
			)
			(fill no)
			(layer "B.CrtYd")
		)
		(fp_rect
			(start 0.2794 0.6477)
			(end -0.2794 -0.6477)
			(stroke
				(width 0)
				(type default)
			)
			(fill no)
			(layer "B.Fab")
		)
		(pad "1" smd custom
			(at 0 -0.2794)
			(size 0.0762 0.0762)
			(layers "B.Cu" "B.Mask" "B.Paste")
			(net "P0V9")
			(options
				(clearance outline)
				(anchor circle)
			)
			(primitives
				(gr_poly
					(pts
						(arc
							(start 0.1524 0.127)
							(mid 0.137521 0.162921)
							(end 0.1016 0.1778)
						)
						(arc
							(start -0.1016 0.1778)
							(mid -0.137521 0.162921)
							(end -0.1524 0.127)
						)
						(arc
							(start -0.1524 -0.127)
							(mid -0.137521 -0.162921)
							(end -0.1016 -0.1778)
						)
						(arc
							(start 0.1016 -0.1778)
							(mid 0.137521 -0.162921)
							(end 0.1524 -0.127)
						)
					)
					(width 0)
					(fill yes)
				)
			)
		)
		(pad "2" smd custom
			(at 0 0.2794)
			(size 0.0762 0.0762)
			(layers "B.Cu" "B.Mask" "B.Paste")
			(net "GND")
			(options
				(clearance outline)
				(anchor circle)
			)
			(primitives
				(gr_poly
					(pts
						(arc
							(start 0.1524 0.127)
							(mid 0.137521 0.162921)
							(end 0.1016 0.1778)
						)
						(arc
							(start -0.1016 0.1778)
							(mid -0.137521 0.162921)
							(end -0.1524 0.127)
						)
						(arc
							(start -0.1524 -0.127)
							(mid -0.137521 -0.162921)
							(end -0.1016 -0.1778)
						)
						(arc
							(start 0.1016 -0.1778)
							(mid 0.137521 -0.162921)
							(end 0.1524 -0.127)
						)
					)
					(width 0)
					(fill yes)
				)
			)
		)
	)
	(footprint ""
		(layer "B.Cu")
		(at 76.327 -62.103 180)
		(property "Reference" "C235"
			(at 0 0 0)
			(layer "B.SilkS")
			(hide yes)
			(effects
				(font
					(size 1.27 1.27)
				)
				(justify mirror)
			)
		)
		(property "Value" "SC22U6D3V3MX-9-GP-U"
			(at 0 -2.8194 180)
			(unlocked yes)
			(layer "B.Fab")
			(hide yes)
			(effects
				(font
					(size 1.016 1.016)
					(thickness 0.1524)
				)
				(justify mirror)
			)
		)
		(property "Device Type" "C603H40"
			(at 0 -4.3434 180)
			(unlocked yes)
			(layer "B.Fab")
			(hide yes)
			(effects
				(font
					(size 1.016 1.016)
					(thickness 0.1524)
				)
				(justify mirror)
			)
		)
		(duplicate_pad_numbers_are_jumpers no)
		(fp_line
			(start -0.508 0)
			(end 0.508 0)
			(stroke
				(width 0.2032)
				(type default)
			)
			(layer "B.SilkS")
		)
		(fp_rect
			(start 0.5842 1.3335)
			(end -0.5842 -1.3335)
			(stroke
				(width 0)
				(type default)
			)
			(fill no)
			(layer "B.CrtYd")
		)
		(fp_rect
			(start 0.5842 1.3335)
			(end -0.5842 -1.3335)
			(stroke
				(width 0)
				(type default)
			)
			(fill no)
			(layer "B.Fab")
		)
		(pad "1" smd custom
			(at 0 -0.762)
			(size 0.2159 0.2159)
			(layers "B.Cu" "B.Mask" "B.Paste")
			(net "GB_VDDA")
			(options
				(clearance outline)
				(anchor circle)
			)
			(primitives
				(gr_poly
					(pts
						(arc
							(start -0.3302 0.4318)
							(mid -0.402042 0.402042)
							(end -0.4318 0.3302)
						)
						(arc
							(start -0.4318 -0.3302)
							(mid -0.402042 -0.402042)
							(end -0.3302 -0.4318)
						)
						(arc
							(start 0.3302 -0.4318)
							(mid 0.402042 -0.402042)
							(end 0.4318 -0.3302)
						)
						(arc
							(start 0.4318 0.3302)
							(mid 0.402042 0.402042)
							(end 0.3302 0.4318)
						)
					)
					(width 0)
					(fill yes)
				)
			)
		)
		(pad "2" smd custom
			(at 0 0.762)
			(size 0.2159 0.2159)
			(layers "B.Cu" "B.Mask" "B.Paste")
			(net "GND")
			(options
				(clearance outline)
				(anchor circle)
			)
			(primitives
				(gr_poly
					(pts
						(arc
							(start -0.3302 0.4318)
							(mid -0.402042 0.402042)
							(end -0.4318 0.3302)
						)
						(arc
							(start -0.4318 -0.3302)
							(mid -0.402042 -0.402042)
							(end -0.3302 -0.4318)
						)
						(arc
							(start 0.3302 -0.4318)
							(mid 0.402042 -0.402042)
							(end 0.4318 -0.3302)
						)
						(arc
							(start 0.4318 0.3302)
							(mid 0.402042 0.402042)
							(end 0.3302 0.4318)
						)
					)
					(width 0)
					(fill yes)
				)
			)
		)
	)
	(footprint ""
		(layer "B.Cu")
		(at 64.262 -105.41 -90)
		(property "Reference" "C641"
			(at 0 0 90)
			(layer "B.SilkS")
			(hide yes)
			(effects
				(font
					(size 1.27 1.27)
				)
				(justify mirror)
			)
		)
		(property "Value" "SCD1U16V2KX-3GP"
			(at -1.1811 -2.7051 270)
			(unlocked yes)
			(layer "B.Fab")
			(hide yes)
			(effects
				(font
					(size 1.016 1.016)
					(thickness 0.1524)
				)
				(justify mirror)
			)
		)
		(property "Device Type" "C402H22"
			(at -1.1811 -4.2291 270)
			(unlocked yes)
			(layer "B.Fab")
			(hide yes)
			(effects
				(font
					(size 1.016 1.016)
					(thickness 0.1524)
				)
				(justify mirror)
			)
		)
		(duplicate_pad_numbers_are_jumpers no)
		(fp_rect
			(start 0.4318 0.9525)
			(end -0.4318 -0.9525)
			(stroke
				(width 0)
				(type default)
			)
			(fill no)
			(layer "B.CrtYd")
		)
		(fp_rect
			(start 0.4318 0.9525)
			(end -0.4318 -0.9525)
			(stroke
				(width 0)
				(type default)
			)
			(fill no)
			(layer "B.Fab")
		)
		(pad "1" smd custom
			(at 0 -0.4445 90)
			(size 0.1524 0.1524)
			(layers "B.Cu" "B.Mask" "B.Paste")
			(net "P3V3_VBST_RC")
			(options
				(clearance outline)
				(anchor circle)
			)
			(primitives
				(gr_poly
					(pts
						(arc
							(start 0.3048 0.2032)
							(mid 0.275042 0.275042)
							(end 0.2032 0.3048)
						)
						(arc
							(start -0.2032 0.3048)
							(mid -0.275042 0.275042)
							(end -0.3048 0.2032)
						)
						(arc
							(start -0.3048 -0.2032)
							(mid -0.275042 -0.275042)
							(end -0.2032 -0.3048)
						)
						(arc
							(start 0.2032 -0.3048)
							(mid 0.275042 -0.275042)
							(end 0.3048 -0.2032)
						)
					)
					(width 0)
					(fill yes)
				)
			)
		)
		(pad "2" smd custom
			(at 0 0.4445 90)
			(size 0.1524 0.1524)
			(layers "B.Cu" "B.Mask" "B.Paste")
			(net "P3V3_LL")
			(options
				(clearance outline)
				(anchor circle)
			)
			(primitives
				(gr_poly
					(pts
						(arc
							(start 0.3048 0.2032)
							(mid 0.275042 0.275042)
							(end 0.2032 0.3048)
						)
						(arc
							(start -0.2032 0.3048)
							(mid -0.275042 0.275042)
							(end -0.3048 0.2032)
						)
						(arc
							(start -0.3048 -0.2032)
							(mid -0.275042 -0.275042)
							(end -0.2032 -0.3048)
						)
						(arc
							(start 0.2032 -0.3048)
							(mid 0.275042 -0.275042)
							(end 0.3048 -0.2032)
						)
					)
					(width 0)
					(fill yes)
				)
			)
		)
	)
	(footprint ""
		(layer "B.Cu")
		(at 171.5008 -93.161866 -90)
		(property "Reference" "C665"
			(at 0 0 90)
			(layer "B.SilkS")
			(hide yes)
			(effects
				(font
					(size 1.27 1.27)
				)
				(justify mirror)
			)
		)
		(property "Value" "SC22U6D3V6KX-2-GP"
			(at 0.0762 -5.1308 270)
			(unlocked yes)
			(layer "B.Fab")
			(hide yes)
			(effects
				(font
					(size 1.016 1.016)
					(thickness 0.1524)
				)
				(justify mirror)
			)
		)
		(property "Device Type" "C1206H71"
			(at 0.127 -6.6548 270)
			(unlocked yes)
			(layer "B.Fab")
			(hide yes)
			(effects
				(font
					(size 1.016 1.016)
					(thickness 0.1524)
				)
				(justify mirror)
			)
		)
		(duplicate_pad_numbers_are_jumpers no)
		(fp_line
			(start -1.016 2.2352)
			(end 1.016 2.2352)
			(stroke
				(width 0.1524)
				(type default)
			)
			(layer "B.SilkS")
		)
		(fp_line
			(start 1.016 2.2352)
			(end 1.016 0.8382)
			(stroke
				(width 0.1524)
				(type default)
			)
			(layer "B.SilkS")
		)
		(fp_line
			(start -1.016 0.8382)
			(end -1.016 2.2352)
			(stroke
				(width 0.1524)
				(type default)
			)
			(layer "B.SilkS")
		)
		(fp_line
			(start 1.016 -0.8382)
			(end 1.016 -2.2352)
			(stroke
				(width 0.1524)
				(type default)
			)
			(layer "B.SilkS")
		)
		(fp_line
			(start -1.016 -2.2352)
			(end -1.016 -0.8382)
			(stroke
				(width 0.1524)
				(type default)
			)
			(layer "B.SilkS")
		)
		(fp_line
			(start 1.016 -2.2352)
			(end -1.016 -2.2352)
			(stroke
				(width 0.1524)
				(type default)
			)
			(layer "B.SilkS")
		)
		(fp_rect
			(start 1.0922 2.3114)
			(end -1.0922 -2.3114)
			(stroke
				(width 0)
				(type default)
			)
			(fill no)
			(layer "B.CrtYd")
		)
		(fp_poly
			(pts
				(xy -1.0922 -2.3114) (xy -1.0922 2.3114) (xy 1.0922 2.3114) (xy 1.0922 -2.3114)
			)
			(stroke
				(width 0)
				(type default)
			)
			(fill no)
			(layer "B.Fab")
		)
		(pad "1" smd rect
			(at 0 -1.397 90)
			(size 1.651 1.27)
			(layers "B.Cu" "B.Mask" "B.Paste")
			(net "VT235_VDDL")
		)
		(pad "2" smd rect
			(at 0 1.397 90)
			(size 1.651 1.27)
			(layers "B.Cu" "B.Mask" "B.Paste")
			(net "GND")
		)
	)
	(footprint ""
		(layer "B.Cu")
		(at 199.771 -35.3314 180)
		(property "Reference" "R186"
			(at 0 0 0)
			(layer "B.SilkS")
			(hide yes)
			(effects
				(font
					(size 1.27 1.27)
				)
				(justify mirror)
			)
		)
		(property "Value" "4K7R2F-GP"
			(at -0.064008 -3.993896 180)
			(unlocked yes)
			(layer "B.Fab")
			(hide yes)
			(effects
				(font
					(size 1.016 1.016)
					(thickness 0.1524)
				)
				(justify mirror)
			)
		)
		(property "Device Type" "R402H16"
			(at -0.064008 -5.517896 180)
			(unlocked yes)
			(layer "B.Fab")
			(hide yes)
			(effects
				(font
					(size 1.016 1.016)
					(thickness 0.1524)
				)
				(justify mirror)
			)
		)
		(duplicate_pad_numbers_are_jumpers no)
		(fp_line
			(start 0.508 -0.9398)
			(end 0.508 0.9398)
			(stroke
				(width 0.1524)
				(type default)
			)
			(layer "B.SilkS")
		)
		(fp_line
			(start -0.508 -0.9398)
			(end 0.508 -0.9398)
			(stroke
				(width 0.1524)
				(type default)
			)
			(layer "B.SilkS")
		)
		(fp_rect
			(start 0.508 0.9398)
			(end -0.508 -0.9398)
			(stroke
				(width 0)
				(type default)
			)
			(fill no)
			(layer "B.CrtYd")
		)
		(fp_rect
			(start 0.508 0.9398)
			(end -0.508 -0.9398)
			(stroke
				(width 0)
				(type default)
			)
			(fill no)
			(layer "B.Fab")
		)
		(pad "1" smd custom
			(at 0 -0.4445)
			(size 0.1397 0.1397)
			(layers "B.Cu" "B.Mask" "B.Paste")
			(net "P1V8_C")
			(options
				(clearance outline)
				(anchor circle)
			)
			(primitives
				(gr_poly
					(pts
						(arc
							(start -0.1778 0.2794)
							(mid -0.249642 0.249642)
							(end -0.2794 0.1778)
						)
						(arc
							(start -0.2794 -0.1778)
							(mid -0.249642 -0.249642)
							(end -0.1778 -0.2794)
						)
						(arc
							(start 0.1778 -0.2794)
							(mid 0.249642 -0.249642)
							(end 0.2794 -0.1778)
						)
						(arc
							(start 0.2794 0.1778)
							(mid 0.249642 0.249642)
							(end 0.1778 0.2794)
						)
					)
					(width 0)
					(fill yes)
				)
			)
		)
		(pad "2" smd custom
			(at 0 0.4445)
			(size 0.1397 0.1397)
			(layers "B.Cu" "B.Mask" "B.Paste")
			(net "IOC_EEPROM_A2")
			(options
				(clearance outline)
				(anchor circle)
			)
			(primitives
				(gr_poly
					(pts
						(arc
							(start -0.1778 0.2794)
							(mid -0.249642 0.249642)
							(end -0.2794 0.1778)
						)
						(arc
							(start -0.2794 -0.1778)
							(mid -0.249642 -0.249642)
							(end -0.1778 -0.2794)
						)
						(arc
							(start 0.1778 -0.2794)
							(mid 0.249642 -0.249642)
							(end 0.2794 -0.1778)
						)
						(arc
							(start 0.2794 0.1778)
							(mid 0.249642 0.249642)
							(end 0.1778 0.2794)
						)
					)
					(width 0)
					(fill yes)
				)
			)
		)
	)
	(footprint ""
		(layer "B.Cu")
		(at 172.122338 -43.47845 -90)
		(property "Reference" "C442"
			(at 0 0 90)
			(layer "B.SilkS")
			(hide yes)
			(effects
				(font
					(size 1.27 1.27)
				)
				(justify mirror)
			)
		)
		(property "Value" "SCD1U6D3V1KX-GP"
			(at 2.8321 -1.7399 270)
			(unlocked yes)
			(layer "B.Fab")
			(hide yes)
			(effects
				(font
					(size 1.016 1.016)
					(thickness 0.1524)
				)
				(justify mirror)
			)
		)
		(property "Device Type" "C0201H13"
			(at 2.8321 -3.2639 270)
			(unlocked yes)
			(layer "B.Fab")
			(hide yes)
			(effects
				(font
					(size 1.016 1.016)
					(thickness 0.1524)
				)
				(justify mirror)
			)
		)
		(duplicate_pad_numbers_are_jumpers no)
		(fp_rect
			(start 0.2794 0.6477)
			(end -0.2794 -0.6477)
			(stroke
				(width 0)
				(type default)
			)
			(fill no)
			(layer "B.CrtYd")
		)
		(fp_rect
			(start 0.2794 0.6477)
			(end -0.2794 -0.6477)
			(stroke
				(width 0)
				(type default)
			)
			(fill no)
			(layer "B.Fab")
		)
		(pad "1" smd custom
			(at 0 -0.2794 90)
			(size 0.0762 0.0762)
			(layers "B.Cu" "B.Mask" "B.Paste")
			(net "P0V975")
			(options
				(clearance outline)
				(anchor circle)
			)
			(primitives
				(gr_poly
					(pts
						(arc
							(start 0.1524 0.127)
							(mid 0.137521 0.162921)
							(end 0.1016 0.1778)
						)
						(arc
							(start -0.1016 0.1778)
							(mid -0.137521 0.162921)
							(end -0.1524 0.127)
						)
						(arc
							(start -0.1524 -0.127)
							(mid -0.137521 -0.162921)
							(end -0.1016 -0.1778)
						)
						(arc
							(start 0.1016 -0.1778)
							(mid 0.137521 -0.162921)
							(end 0.1524 -0.127)
						)
					)
					(width 0)
					(fill yes)
				)
			)
		)
		(pad "2" smd custom
			(at 0 0.2794 90)
			(size 0.0762 0.0762)
			(layers "B.Cu" "B.Mask" "B.Paste")
			(net "GND")
			(options
				(clearance outline)
				(anchor circle)
			)
			(primitives
				(gr_poly
					(pts
						(arc
							(start 0.1524 0.127)
							(mid 0.137521 0.162921)
							(end 0.1016 0.1778)
						)
						(arc
							(start -0.1016 0.1778)
							(mid -0.137521 0.162921)
							(end -0.1524 0.127)
						)
						(arc
							(start -0.1524 -0.127)
							(mid -0.137521 -0.162921)
							(end -0.1016 -0.1778)
						)
						(arc
							(start 0.1016 -0.1778)
							(mid 0.137521 -0.162921)
							(end 0.1524 -0.127)
						)
					)
					(width 0)
					(fill yes)
				)
			)
		)
	)
	(footprint ""
		(layer "B.Cu")
		(at 127.970788 -54.502304 -90)
		(property "Reference" "C273"
			(at 0 0 90)
			(layer "B.SilkS")
			(hide yes)
			(effects
				(font
					(size 1.27 1.27)
				)
				(justify mirror)
			)
		)
		(property "Value" "SCD1U6D3V1KX-GP"
			(at 2.8321 -1.7399 270)
			(unlocked yes)
			(layer "B.Fab")
			(hide yes)
			(effects
				(font
					(size 1.016 1.016)
					(thickness 0.1524)
				)
				(justify mirror)
			)
		)
		(property "Device Type" "C0201H13"
			(at 2.8321 -3.2639 270)
			(unlocked yes)
			(layer "B.Fab")
			(hide yes)
			(effects
				(font
					(size 1.016 1.016)
					(thickness 0.1524)
				)
				(justify mirror)
			)
		)
		(duplicate_pad_numbers_are_jumpers no)
		(fp_rect
			(start 0.2794 0.6477)
			(end -0.2794 -0.6477)
			(stroke
				(width 0)
				(type default)
			)
			(fill no)
			(layer "B.CrtYd")
		)
		(fp_rect
			(start 0.2794 0.6477)
			(end -0.2794 -0.6477)
			(stroke
				(width 0)
				(type default)
			)
			(fill no)
			(layer "B.Fab")
		)
		(pad "1" smd custom
			(at 0 -0.2794 90)
			(size 0.0762 0.0762)
			(layers "B.Cu" "B.Mask" "B.Paste")
			(net "GB_VDDA")
			(options
				(clearance outline)
				(anchor circle)
			)
			(primitives
				(gr_poly
					(pts
						(arc
							(start 0.1524 0.127)
							(mid 0.137521 0.162921)
							(end 0.1016 0.1778)
						)
						(arc
							(start -0.1016 0.1778)
							(mid -0.137521 0.162921)
							(end -0.1524 0.127)
						)
						(arc
							(start -0.1524 -0.127)
							(mid -0.137521 -0.162921)
							(end -0.1016 -0.1778)
						)
						(arc
							(start 0.1016 -0.1778)
							(mid 0.137521 -0.162921)
							(end 0.1524 -0.127)
						)
					)
					(width 0)
					(fill yes)
				)
			)
		)
		(pad "2" smd custom
			(at 0 0.2794 90)
			(size 0.0762 0.0762)
			(layers "B.Cu" "B.Mask" "B.Paste")
			(net "GND")
			(options
				(clearance outline)
				(anchor circle)
			)
			(primitives
				(gr_poly
					(pts
						(arc
							(start 0.1524 0.127)
							(mid 0.137521 0.162921)
							(end 0.1016 0.1778)
						)
						(arc
							(start -0.1016 0.1778)
							(mid -0.137521 0.162921)
							(end -0.1524 0.127)
						)
						(arc
							(start -0.1524 -0.127)
							(mid -0.137521 -0.162921)
							(end -0.1016 -0.1778)
						)
						(arc
							(start 0.1016 -0.1778)
							(mid 0.137521 -0.162921)
							(end 0.1524 -0.127)
						)
					)
					(width 0)
					(fill yes)
				)
			)
		)
	)
	(footprint ""
		(layer "B.Cu")
		(at 141.732 -88.9)
		(property "Reference" "R67"
			(at 0 0 0)
			(layer "B.SilkS")
			(hide yes)
			(effects
				(font
					(size 1.27 1.27)
				)
				(justify mirror)
			)
		)
		(property "Value" "1KR2F-3-GP"
			(at -0.064008 -3.993896 0)
			(unlocked yes)
			(layer "B.Fab")
			(hide yes)
			(effects
				(font
					(size 1.016 1.016)
					(thickness 0.1524)
				)
				(justify mirror)
			)
		)
		(property "Device Type" "R402H16"
			(at -0.064008 -5.517896 0)
			(unlocked yes)
			(layer "B.Fab")
			(hide yes)
			(effects
				(font
					(size 1.016 1.016)
					(thickness 0.1524)
				)
				(justify mirror)
			)
		)
		(duplicate_pad_numbers_are_jumpers no)
		(fp_line
			(start -0.508 -0.9398)
			(end 0.508 -0.9398)
			(stroke
				(width 0.1524)
				(type default)
			)
			(layer "B.SilkS")
		)
		(fp_line
			(start 0.508 -0.9398)
			(end 0.508 0.9398)
			(stroke
				(width 0.1524)
				(type default)
			)
			(layer "B.SilkS")
		)
		(fp_rect
			(start 0.508 0.9398)
			(end -0.508 -0.9398)
			(stroke
				(width 0)
				(type default)
			)
			(fill no)
			(layer "B.CrtYd")
		)
		(fp_rect
			(start 0.508 0.9398)
			(end -0.508 -0.9398)
			(stroke
				(width 0)
				(type default)
			)
			(fill no)
			(layer "B.Fab")
		)
		(pad "1" smd custom
			(at 0 -0.4445 180)
			(size 0.1397 0.1397)
			(layers "B.Cu" "B.Mask" "B.Paste")
			(net "P1V8_E")
			(options
				(clearance outline)
				(anchor circle)
			)
			(primitives
				(gr_poly
					(pts
						(arc
							(start -0.1778 0.2794)
							(mid -0.249642 0.249642)
							(end -0.2794 0.1778)
						)
						(arc
							(start -0.2794 -0.1778)
							(mid -0.249642 -0.249642)
							(end -0.1778 -0.2794)
						)
						(arc
							(start 0.1778 -0.2794)
							(mid 0.249642 -0.249642)
							(end 0.2794 -0.1778)
						)
						(arc
							(start 0.2794 0.1778)
							(mid 0.249642 0.249642)
							(end 0.1778 0.2794)
						)
					)
					(width 0)
					(fill yes)
				)
			)
		)
		(pad "2" smd custom
			(at 0 0.4445 180)
			(size 0.1397 0.1397)
			(layers "B.Cu" "B.Mask" "B.Paste")
			(net "EXP_I2C_SDA9")
			(options
				(clearance outline)
				(anchor circle)
			)
			(primitives
				(gr_poly
					(pts
						(arc
							(start -0.1778 0.2794)
							(mid -0.249642 0.249642)
							(end -0.2794 0.1778)
						)
						(arc
							(start -0.2794 -0.1778)
							(mid -0.249642 -0.249642)
							(end -0.1778 -0.2794)
						)
						(arc
							(start 0.1778 -0.2794)
							(mid 0.249642 -0.249642)
							(end 0.2794 -0.1778)
						)
						(arc
							(start 0.2794 0.1778)
							(mid 0.249642 0.249642)
							(end 0.1778 0.2794)
						)
					)
					(width 0)
					(fill yes)
				)
			)
		)
	)
	(footprint ""
		(layer "B.Cu")
		(at 123.2154 -39.4716 180)
		(property "Reference" "C54"
			(at 0 0 0)
			(layer "B.SilkS")
			(hide yes)
			(effects
				(font
					(size 1.27 1.27)
				)
				(justify mirror)
			)
		)
		(property "Value" "SCD01U16V1KX-GP"
			(at 2.8321 -1.7399 180)
			(unlocked yes)
			(layer "B.Fab")
			(hide yes)
			(effects
				(font
					(size 1.016 1.016)
					(thickness 0.1524)
				)
				(justify mirror)
			)
		)
		(property "Device Type" "C0201H13"
			(at 2.8321 -3.2639 180)
			(unlocked yes)
			(layer "B.Fab")
			(hide yes)
			(effects
				(font
					(size 1.016 1.016)
					(thickness 0.1524)
				)
				(justify mirror)
			)
		)
		(duplicate_pad_numbers_are_jumpers no)
		(fp_rect
			(start 0.2794 0.6477)
			(end -0.2794 -0.6477)
			(stroke
				(width 0)
				(type default)
			)
			(fill no)
			(layer "B.CrtYd")
		)
		(fp_rect
			(start 0.2794 0.6477)
			(end -0.2794 -0.6477)
			(stroke
				(width 0)
				(type default)
			)
			(fill no)
			(layer "B.Fab")
		)
		(pad "1" smd custom
			(at 0 -0.2794)
			(size 0.0762 0.0762)
			(layers "B.Cu" "B.Mask" "B.Paste")
			(net "PHY_DPB_TO_SCC_37_DN")
			(options
				(clearance outline)
				(anchor circle)
			)
			(primitives
				(gr_poly
					(pts
						(arc
							(start 0.1524 0.127)
							(mid 0.137521 0.162921)
							(end 0.1016 0.1778)
						)
						(arc
							(start -0.1016 0.1778)
							(mid -0.137521 0.162921)
							(end -0.1524 0.127)
						)
						(arc
							(start -0.1524 -0.127)
							(mid -0.137521 -0.162921)
							(end -0.1016 -0.1778)
						)
						(arc
							(start 0.1016 -0.1778)
							(mid 0.137521 -0.162921)
							(end 0.1524 -0.127)
						)
					)
					(width 0)
					(fill yes)
				)
			)
		)
		(pad "2" smd custom
			(at 0 0.2794)
			(size 0.0762 0.0762)
			(layers "B.Cu" "B.Mask" "B.Paste")
			(net "PHY_DPB_TO_SCC_C_37_DN")
			(options
				(clearance outline)
				(anchor circle)
			)
			(primitives
				(gr_poly
					(pts
						(arc
							(start 0.1524 0.127)
							(mid 0.137521 0.162921)
							(end 0.1016 0.1778)
						)
						(arc
							(start -0.1016 0.1778)
							(mid -0.137521 0.162921)
							(end -0.1524 0.127)
						)
						(arc
							(start -0.1524 -0.127)
							(mid -0.137521 -0.162921)
							(end -0.1016 -0.1778)
						)
						(arc
							(start 0.1016 -0.1778)
							(mid 0.137521 -0.162921)
							(end 0.1524 -0.127)
						)
					)
					(width 0)
					(fill yes)
				)
			)
		)
	)
	(footprint ""
		(layer "B.Cu")
		(at 108.61929 -61.183774)
		(property "Reference" "C129"
			(at 0 0 0)
			(layer "B.SilkS")
			(hide yes)
			(effects
				(font
					(size 1.27 1.27)
				)
				(justify mirror)
			)
		)
		(property "Value" "SCD1U6D3V1KX-GP"
			(at 2.8321 -1.7399 0)
			(unlocked yes)
			(layer "B.Fab")
			(hide yes)
			(effects
				(font
					(size 1.016 1.016)
					(thickness 0.1524)
				)
				(justify mirror)
			)
		)
		(property "Device Type" "C0201H13"
			(at 2.8321 -3.2639 0)
			(unlocked yes)
			(layer "B.Fab")
			(hide yes)
			(effects
				(font
					(size 1.016 1.016)
					(thickness 0.1524)
				)
				(justify mirror)
			)
		)
		(duplicate_pad_numbers_are_jumpers no)
		(fp_rect
			(start 0.2794 0.6477)
			(end -0.2794 -0.6477)
			(stroke
				(width 0)
				(type default)
			)
			(fill no)
			(layer "B.CrtYd")
		)
		(fp_rect
			(start 0.2794 0.6477)
			(end -0.2794 -0.6477)
			(stroke
				(width 0)
				(type default)
			)
			(fill no)
			(layer "B.Fab")
		)
		(pad "1" smd custom
			(at 0 -0.2794 180)
			(size 0.0762 0.0762)
			(layers "B.Cu" "B.Mask" "B.Paste")
			(net "P1V8_E")
			(options
				(clearance outline)
				(anchor circle)
			)
			(primitives
				(gr_poly
					(pts
						(arc
							(start 0.1524 0.127)
							(mid 0.137521 0.162921)
							(end 0.1016 0.1778)
						)
						(arc
							(start -0.1016 0.1778)
							(mid -0.137521 0.162921)
							(end -0.1524 0.127)
						)
						(arc
							(start -0.1524 -0.127)
							(mid -0.137521 -0.162921)
							(end -0.1016 -0.1778)
						)
						(arc
							(start 0.1016 -0.1778)
							(mid 0.137521 -0.162921)
							(end 0.1524 -0.127)
						)
					)
					(width 0)
					(fill yes)
				)
			)
		)
		(pad "2" smd custom
			(at 0 0.2794 180)
			(size 0.0762 0.0762)
			(layers "B.Cu" "B.Mask" "B.Paste")
			(net "GND")
			(options
				(clearance outline)
				(anchor circle)
			)
			(primitives
				(gr_poly
					(pts
						(arc
							(start 0.1524 0.127)
							(mid 0.137521 0.162921)
							(end 0.1016 0.1778)
						)
						(arc
							(start -0.1016 0.1778)
							(mid -0.137521 0.162921)
							(end -0.1524 0.127)
						)
						(arc
							(start -0.1524 -0.127)
							(mid -0.137521 -0.162921)
							(end -0.1016 -0.1778)
						)
						(arc
							(start 0.1016 -0.1778)
							(mid 0.137521 -0.162921)
							(end 0.1524 -0.127)
						)
					)
					(width 0)
					(fill yes)
				)
			)
		)
	)
	(footprint ""
		(layer "B.Cu")
		(at 101.219 -44.2214 180)
		(property "Reference" "C82"
			(at 0 0 0)
			(layer "B.SilkS")
			(hide yes)
			(effects
				(font
					(size 1.27 1.27)
				)
				(justify mirror)
			)
		)
		(property "Value" "SCD01U16V1KX-GP"
			(at 2.8321 -1.7399 180)
			(unlocked yes)
			(layer "B.Fab")
			(hide yes)
			(effects
				(font
					(size 1.016 1.016)
					(thickness 0.1524)
				)
				(justify mirror)
			)
		)
		(property "Device Type" "C0201H13"
			(at 2.8321 -3.2639 180)
			(unlocked yes)
			(layer "B.Fab")
			(hide yes)
			(effects
				(font
					(size 1.016 1.016)
					(thickness 0.1524)
				)
				(justify mirror)
			)
		)
		(duplicate_pad_numbers_are_jumpers no)
		(fp_rect
			(start 0.2794 0.6477)
			(end -0.2794 -0.6477)
			(stroke
				(width 0)
				(type default)
			)
			(fill no)
			(layer "B.CrtYd")
		)
		(fp_rect
			(start 0.2794 0.6477)
			(end -0.2794 -0.6477)
			(stroke
				(width 0)
				(type default)
			)
			(fill no)
			(layer "B.Fab")
		)
		(pad "1" smd custom
			(at 0 -0.2794)
			(size 0.0762 0.0762)
			(layers "B.Cu" "B.Mask" "B.Paste")
			(net "PHY_DPB_TO_SCC_19_DN")
			(options
				(clearance outline)
				(anchor circle)
			)
			(primitives
				(gr_poly
					(pts
						(arc
							(start 0.1524 0.127)
							(mid 0.137521 0.162921)
							(end 0.1016 0.1778)
						)
						(arc
							(start -0.1016 0.1778)
							(mid -0.137521 0.162921)
							(end -0.1524 0.127)
						)
						(arc
							(start -0.1524 -0.127)
							(mid -0.137521 -0.162921)
							(end -0.1016 -0.1778)
						)
						(arc
							(start 0.1016 -0.1778)
							(mid 0.137521 -0.162921)
							(end 0.1524 -0.127)
						)
					)
					(width 0)
					(fill yes)
				)
			)
		)
		(pad "2" smd custom
			(at 0 0.2794)
			(size 0.0762 0.0762)
			(layers "B.Cu" "B.Mask" "B.Paste")
			(net "PHY_DPB_TO_SCC_C_19_DN")
			(options
				(clearance outline)
				(anchor circle)
			)
			(primitives
				(gr_poly
					(pts
						(arc
							(start 0.1524 0.127)
							(mid 0.137521 0.162921)
							(end 0.1016 0.1778)
						)
						(arc
							(start -0.1016 0.1778)
							(mid -0.137521 0.162921)
							(end -0.1524 0.127)
						)
						(arc
							(start -0.1524 -0.127)
							(mid -0.137521 -0.162921)
							(end -0.1016 -0.1778)
						)
						(arc
							(start 0.1016 -0.1778)
							(mid 0.137521 -0.162921)
							(end 0.1524 -0.127)
						)
					)
					(width 0)
					(fill yes)
				)
			)
		)
	)
	(footprint ""
		(layer "B.Cu")
		(at 118.5418 -44.2214 180)
		(property "Reference" "C59"
			(at 0 0 0)
			(layer "B.SilkS")
			(hide yes)
			(effects
				(font
					(size 1.27 1.27)
				)
				(justify mirror)
			)
		)
		(property "Value" "SCD01U16V1KX-GP"
			(at 2.8321 -1.7399 180)
			(unlocked yes)
			(layer "B.Fab")
			(hide yes)
			(effects
				(font
					(size 1.016 1.016)
					(thickness 0.1524)
				)
				(justify mirror)
			)
		)
		(property "Device Type" "C0201H13"
			(at 2.8321 -3.2639 180)
			(unlocked yes)
			(layer "B.Fab")
			(hide yes)
			(effects
				(font
					(size 1.016 1.016)
					(thickness 0.1524)
				)
				(justify mirror)
			)
		)
		(duplicate_pad_numbers_are_jumpers no)
		(fp_rect
			(start 0.2794 0.6477)
			(end -0.2794 -0.6477)
			(stroke
				(width 0)
				(type default)
			)
			(fill no)
			(layer "B.CrtYd")
		)
		(fp_rect
			(start 0.2794 0.6477)
			(end -0.2794 -0.6477)
			(stroke
				(width 0)
				(type default)
			)
			(fill no)
			(layer "B.Fab")
		)
		(pad "1" smd custom
			(at 0 -0.2794)
			(size 0.0762 0.0762)
			(layers "B.Cu" "B.Mask" "B.Paste")
			(net "PHY_DPB_TO_SCC_34_DP")
			(options
				(clearance outline)
				(anchor circle)
			)
			(primitives
				(gr_poly
					(pts
						(arc
							(start 0.1524 0.127)
							(mid 0.137521 0.162921)
							(end 0.1016 0.1778)
						)
						(arc
							(start -0.1016 0.1778)
							(mid -0.137521 0.162921)
							(end -0.1524 0.127)
						)
						(arc
							(start -0.1524 -0.127)
							(mid -0.137521 -0.162921)
							(end -0.1016 -0.1778)
						)
						(arc
							(start 0.1016 -0.1778)
							(mid 0.137521 -0.162921)
							(end 0.1524 -0.127)
						)
					)
					(width 0)
					(fill yes)
				)
			)
		)
		(pad "2" smd custom
			(at 0 0.2794)
			(size 0.0762 0.0762)
			(layers "B.Cu" "B.Mask" "B.Paste")
			(net "PHY_DPB_TO_SCC_C_34_DP")
			(options
				(clearance outline)
				(anchor circle)
			)
			(primitives
				(gr_poly
					(pts
						(arc
							(start 0.1524 0.127)
							(mid 0.137521 0.162921)
							(end 0.1016 0.1778)
						)
						(arc
							(start -0.1016 0.1778)
							(mid -0.137521 0.162921)
							(end -0.1524 0.127)
						)
						(arc
							(start -0.1524 -0.127)
							(mid -0.137521 -0.162921)
							(end -0.1016 -0.1778)
						)
						(arc
							(start 0.1016 -0.1778)
							(mid 0.137521 -0.162921)
							(end 0.1524 -0.127)
						)
					)
					(width 0)
					(fill yes)
				)
			)
		)
	)
	(footprint ""
		(layer "B.Cu")
		(at 66.932048 -15.142972 90)
		(property "Reference" "C101"
			(at 0 0 90)
			(layer "B.SilkS")
			(hide yes)
			(effects
				(font
					(size 1.27 1.27)
				)
				(justify mirror)
			)
		)
		(property "Value" "SCD1U16V2KX-3GP"
			(at -1.1811 -2.7051 90)
			(unlocked yes)
			(layer "B.Fab")
			(hide yes)
			(effects
				(font
					(size 1.016 1.016)
					(thickness 0.1524)
				)
				(justify mirror)
			)
		)
		(property "Device Type" "C402H22"
			(at -1.1811 -4.2291 90)
			(unlocked yes)
			(layer "B.Fab")
			(hide yes)
			(effects
				(font
					(size 1.016 1.016)
					(thickness 0.1524)
				)
				(justify mirror)
			)
		)
		(duplicate_pad_numbers_are_jumpers no)
		(fp_rect
			(start 0.4318 0.9525)
			(end -0.4318 -0.9525)
			(stroke
				(width 0)
				(type default)
			)
			(fill no)
			(layer "B.CrtYd")
		)
		(fp_rect
			(start 0.4318 0.9525)
			(end -0.4318 -0.9525)
			(stroke
				(width 0)
				(type default)
			)
			(fill no)
			(layer "B.Fab")
		)
		(pad "1" smd custom
			(at 0 -0.4445 270)
			(size 0.1524 0.1524)
			(layers "B.Cu" "B.Mask" "B.Paste")
			(net "P1V8_E")
			(options
				(clearance outline)
				(anchor circle)
			)
			(primitives
				(gr_poly
					(pts
						(arc
							(start 0.3048 0.2032)
							(mid 0.275042 0.275042)
							(end 0.2032 0.3048)
						)
						(arc
							(start -0.2032 0.3048)
							(mid -0.275042 0.275042)
							(end -0.3048 0.2032)
						)
						(arc
							(start -0.3048 -0.2032)
							(mid -0.275042 -0.275042)
							(end -0.2032 -0.3048)
						)
						(arc
							(start 0.2032 -0.3048)
							(mid 0.275042 -0.275042)
							(end 0.3048 -0.2032)
						)
					)
					(width 0)
					(fill yes)
				)
			)
		)
		(pad "2" smd custom
			(at 0 0.4445 270)
			(size 0.1524 0.1524)
			(layers "B.Cu" "B.Mask" "B.Paste")
			(net "GND")
			(options
				(clearance outline)
				(anchor circle)
			)
			(primitives
				(gr_poly
					(pts
						(arc
							(start 0.3048 0.2032)
							(mid 0.275042 0.275042)
							(end 0.2032 0.3048)
						)
						(arc
							(start -0.2032 0.3048)
							(mid -0.275042 0.275042)
							(end -0.3048 0.2032)
						)
						(arc
							(start -0.3048 -0.2032)
							(mid -0.275042 -0.275042)
							(end -0.2032 -0.3048)
						)
						(arc
							(start 0.2032 -0.3048)
							(mid 0.275042 -0.275042)
							(end 0.3048 -0.2032)
						)
					)
					(width 0)
					(fill yes)
				)
			)
		)
	)
	(footprint ""
		(layer "B.Cu")
		(at 164.60089 -39.19982)
		(property "Reference" "TP141"
			(at 0 0 0)
			(layer "B.SilkS")
			(hide yes)
			(effects
				(font
					(size 1.27 1.27)
				)
				(justify mirror)
			)
		)
		(property "Value" "TPAD28-2-GP"
			(at 0.0127 -1.6637 0)
			(unlocked yes)
			(layer "B.Fab")
			(hide yes)
			(effects
				(font
					(size 1.016 1.016)
					(thickness 0.1524)
				)
				(justify mirror)
			)
		)
		(property "Device Type" "TPAD28"
			(at 0.0127 -3.1877 0)
			(unlocked yes)
			(layer "B.Fab")
			(hide yes)
			(effects
				(font
					(size 1.016 1.016)
					(thickness 0.1524)
				)
				(justify mirror)
			)
		)
		(duplicate_pad_numbers_are_jumpers no)
		(fp_poly
			(pts
				(arc
					(start 0.3556 0)
					(mid -0.3556 0)
					(end 0.3556 0)
				)
			)
			(stroke
				(width 0)
				(type default)
			)
			(fill no)
			(layer "B.CrtYd")
		)
		(fp_poly
			(pts
				(arc
					(start 0.6096 0)
					(mid -0.6096 0)
					(end 0.6096 0)
				)
			)
			(stroke
				(width 0)
				(type default)
			)
			(fill no)
			(layer "B.Fab")
		)
		(pad "1" smd circle
			(at 0 0 180)
			(size 0.7112 0.7112)
			(layers "B.Cu" "B.Mask" "B.Paste")
			(net "OSC_REF_CLK")
		)
	)
	(footprint ""
		(layer "B.Cu")
		(at 124.714 -69.5071 90)
		(property "Reference" "C306"
			(at 0 0 90)
			(layer "B.SilkS")
			(hide yes)
			(effects
				(font
					(size 1.27 1.27)
				)
				(justify mirror)
			)
		)
		(property "Value" "SCD1U6D3V1KX-GP"
			(at 2.8321 -1.7399 90)
			(unlocked yes)
			(layer "B.Fab")
			(hide yes)
			(effects
				(font
					(size 1.016 1.016)
					(thickness 0.1524)
				)
				(justify mirror)
			)
		)
		(property "Device Type" "C0201H13"
			(at 2.8321 -3.2639 90)
			(unlocked yes)
			(layer "B.Fab")
			(hide yes)
			(effects
				(font
					(size 1.016 1.016)
					(thickness 0.1524)
				)
				(justify mirror)
			)
		)
		(duplicate_pad_numbers_are_jumpers no)
		(fp_rect
			(start 0.2794 0.6477)
			(end -0.2794 -0.6477)
			(stroke
				(width 0)
				(type default)
			)
			(fill no)
			(layer "B.CrtYd")
		)
		(fp_rect
			(start 0.2794 0.6477)
			(end -0.2794 -0.6477)
			(stroke
				(width 0)
				(type default)
			)
			(fill no)
			(layer "B.Fab")
		)
		(pad "1" smd custom
			(at 0 -0.2794 270)
			(size 0.0762 0.0762)
			(layers "B.Cu" "B.Mask" "B.Paste")
			(net "GB_VDDA")
			(options
				(clearance outline)
				(anchor circle)
			)
			(primitives
				(gr_poly
					(pts
						(arc
							(start 0.1524 0.127)
							(mid 0.137521 0.162921)
							(end 0.1016 0.1778)
						)
						(arc
							(start -0.1016 0.1778)
							(mid -0.137521 0.162921)
							(end -0.1524 0.127)
						)
						(arc
							(start -0.1524 -0.127)
							(mid -0.137521 -0.162921)
							(end -0.1016 -0.1778)
						)
						(arc
							(start 0.1016 -0.1778)
							(mid 0.137521 -0.162921)
							(end 0.1524 -0.127)
						)
					)
					(width 0)
					(fill yes)
				)
			)
		)
		(pad "2" smd custom
			(at 0 0.2794 270)
			(size 0.0762 0.0762)
			(layers "B.Cu" "B.Mask" "B.Paste")
			(net "GND")
			(options
				(clearance outline)
				(anchor circle)
			)
			(primitives
				(gr_poly
					(pts
						(arc
							(start 0.1524 0.127)
							(mid 0.137521 0.162921)
							(end 0.1016 0.1778)
						)
						(arc
							(start -0.1016 0.1778)
							(mid -0.137521 0.162921)
							(end -0.1524 0.127)
						)
						(arc
							(start -0.1524 -0.127)
							(mid -0.137521 -0.162921)
							(end -0.1016 -0.1778)
						)
						(arc
							(start 0.1016 -0.1778)
							(mid 0.137521 -0.162921)
							(end 0.1524 -0.127)
						)
					)
					(width 0)
					(fill yes)
				)
			)
		)
	)
	(footprint ""
		(layer "B.Cu")
		(at 166.636954 -11.428222)
		(property "Reference" "C740"
			(at 0 0 0)
			(layer "B.SilkS")
			(hide yes)
			(effects
				(font
					(size 1.27 1.27)
				)
				(justify mirror)
			)
		)
		(property "Value" "SCD1U16V2KX-3GP"
			(at -1.1811 -2.7051 0)
			(unlocked yes)
			(layer "B.Fab")
			(hide yes)
			(effects
				(font
					(size 1.016 1.016)
					(thickness 0.1524)
				)
				(justify mirror)
			)
		)
		(property "Device Type" "C402H22"
			(at -1.1811 -4.2291 0)
			(unlocked yes)
			(layer "B.Fab")
			(hide yes)
			(effects
				(font
					(size 1.016 1.016)
					(thickness 0.1524)
				)
				(justify mirror)
			)
		)
		(duplicate_pad_numbers_are_jumpers no)
		(fp_rect
			(start 0.4318 0.9525)
			(end -0.4318 -0.9525)
			(stroke
				(width 0)
				(type default)
			)
			(fill no)
			(layer "B.CrtYd")
		)
		(fp_rect
			(start 0.4318 0.9525)
			(end -0.4318 -0.9525)
			(stroke
				(width 0)
				(type default)
			)
			(fill no)
			(layer "B.Fab")
		)
		(pad "1" smd custom
			(at 0 -0.4445 180)
			(size 0.1524 0.1524)
			(layers "B.Cu" "B.Mask" "B.Paste")
			(net "U50_OE")
			(options
				(clearance outline)
				(anchor circle)
			)
			(primitives
				(gr_poly
					(pts
						(arc
							(start 0.3048 0.2032)
							(mid 0.275042 0.275042)
							(end 0.2032 0.3048)
						)
						(arc
							(start -0.2032 0.3048)
							(mid -0.275042 0.275042)
							(end -0.3048 0.2032)
						)
						(arc
							(start -0.3048 -0.2032)
							(mid -0.275042 -0.275042)
							(end -0.2032 -0.3048)
						)
						(arc
							(start 0.2032 -0.3048)
							(mid 0.275042 -0.275042)
							(end 0.3048 -0.2032)
						)
					)
					(width 0)
					(fill yes)
				)
			)
		)
		(pad "2" smd custom
			(at 0 0.4445 180)
			(size 0.1524 0.1524)
			(layers "B.Cu" "B.Mask" "B.Paste")
			(net "GND")
			(options
				(clearance outline)
				(anchor circle)
			)
			(primitives
				(gr_poly
					(pts
						(arc
							(start 0.3048 0.2032)
							(mid 0.275042 0.275042)
							(end 0.2032 0.3048)
						)
						(arc
							(start -0.2032 0.3048)
							(mid -0.275042 0.275042)
							(end -0.3048 0.2032)
						)
						(arc
							(start -0.3048 -0.2032)
							(mid -0.275042 -0.275042)
							(end -0.2032 -0.3048)
						)
						(arc
							(start 0.2032 -0.3048)
							(mid 0.275042 -0.275042)
							(end 0.3048 -0.2032)
						)
					)
					(width 0)
					(fill yes)
				)
			)
		)
	)
	(footprint ""
		(layer "B.Cu")
		(at 117.983 -44.2214 180)
		(property "Reference" "C60"
			(at 0 0 0)
			(layer "B.SilkS")
			(hide yes)
			(effects
				(font
					(size 1.27 1.27)
				)
				(justify mirror)
			)
		)
		(property "Value" "SCD01U16V1KX-GP"
			(at 2.8321 -1.7399 180)
			(unlocked yes)
			(layer "B.Fab")
			(hide yes)
			(effects
				(font
					(size 1.016 1.016)
					(thickness 0.1524)
				)
				(justify mirror)
			)
		)
		(property "Device Type" "C0201H13"
			(at 2.8321 -3.2639 180)
			(unlocked yes)
			(layer "B.Fab")
			(hide yes)
			(effects
				(font
					(size 1.016 1.016)
					(thickness 0.1524)
				)
				(justify mirror)
			)
		)
		(duplicate_pad_numbers_are_jumpers no)
		(fp_rect
			(start 0.2794 0.6477)
			(end -0.2794 -0.6477)
			(stroke
				(width 0)
				(type default)
			)
			(fill no)
			(layer "B.CrtYd")
		)
		(fp_rect
			(start 0.2794 0.6477)
			(end -0.2794 -0.6477)
			(stroke
				(width 0)
				(type default)
			)
			(fill no)
			(layer "B.Fab")
		)
		(pad "1" smd custom
			(at 0 -0.2794)
			(size 0.0762 0.0762)
			(layers "B.Cu" "B.Mask" "B.Paste")
			(net "PHY_DPB_TO_SCC_34_DN")
			(options
				(clearance outline)
				(anchor circle)
			)
			(primitives
				(gr_poly
					(pts
						(arc
							(start 0.1524 0.127)
							(mid 0.137521 0.162921)
							(end 0.1016 0.1778)
						)
						(arc
							(start -0.1016 0.1778)
							(mid -0.137521 0.162921)
							(end -0.1524 0.127)
						)
						(arc
							(start -0.1524 -0.127)
							(mid -0.137521 -0.162921)
							(end -0.1016 -0.1778)
						)
						(arc
							(start 0.1016 -0.1778)
							(mid 0.137521 -0.162921)
							(end 0.1524 -0.127)
						)
					)
					(width 0)
					(fill yes)
				)
			)
		)
		(pad "2" smd custom
			(at 0 0.2794)
			(size 0.0762 0.0762)
			(layers "B.Cu" "B.Mask" "B.Paste")
			(net "PHY_DPB_TO_SCC_C_34_DN")
			(options
				(clearance outline)
				(anchor circle)
			)
			(primitives
				(gr_poly
					(pts
						(arc
							(start 0.1524 0.127)
							(mid 0.137521 0.162921)
							(end 0.1016 0.1778)
						)
						(arc
							(start -0.1016 0.1778)
							(mid -0.137521 0.162921)
							(end -0.1524 0.127)
						)
						(arc
							(start -0.1524 -0.127)
							(mid -0.137521 -0.162921)
							(end -0.1016 -0.1778)
						)
						(arc
							(start 0.1016 -0.1778)
							(mid 0.137521 -0.162921)
							(end 0.1524 -0.127)
						)
					)
					(width 0)
					(fill yes)
				)
			)
		)
	)
	(footprint ""
		(layer "B.Cu")
		(at 130.2258 -80.899 180)
		(property "Reference" "C146"
			(at 0 0 0)
			(layer "B.SilkS")
			(hide yes)
			(effects
				(font
					(size 1.27 1.27)
				)
				(justify mirror)
			)
		)
		(property "Value" "SCD1U6D3V1KX-GP"
			(at 2.8321 -1.7399 180)
			(unlocked yes)
			(layer "B.Fab")
			(hide yes)
			(effects
				(font
					(size 1.016 1.016)
					(thickness 0.1524)
				)
				(justify mirror)
			)
		)
		(property "Device Type" "C0201H13"
			(at 2.8321 -3.2639 180)
			(unlocked yes)
			(layer "B.Fab")
			(hide yes)
			(effects
				(font
					(size 1.016 1.016)
					(thickness 0.1524)
				)
				(justify mirror)
			)
		)
		(duplicate_pad_numbers_are_jumpers no)
		(fp_rect
			(start 0.2794 0.6477)
			(end -0.2794 -0.6477)
			(stroke
				(width 0)
				(type default)
			)
			(fill no)
			(layer "B.CrtYd")
		)
		(fp_rect
			(start 0.2794 0.6477)
			(end -0.2794 -0.6477)
			(stroke
				(width 0)
				(type default)
			)
			(fill no)
			(layer "B.Fab")
		)
		(pad "1" smd custom
			(at 0 -0.2794)
			(size 0.0762 0.0762)
			(layers "B.Cu" "B.Mask" "B.Paste")
			(net "P1V8_E")
			(options
				(clearance outline)
				(anchor circle)
			)
			(primitives
				(gr_poly
					(pts
						(arc
							(start 0.1524 0.127)
							(mid 0.137521 0.162921)
							(end 0.1016 0.1778)
						)
						(arc
							(start -0.1016 0.1778)
							(mid -0.137521 0.162921)
							(end -0.1524 0.127)
						)
						(arc
							(start -0.1524 -0.127)
							(mid -0.137521 -0.162921)
							(end -0.1016 -0.1778)
						)
						(arc
							(start 0.1016 -0.1778)
							(mid 0.137521 -0.162921)
							(end 0.1524 -0.127)
						)
					)
					(width 0)
					(fill yes)
				)
			)
		)
		(pad "2" smd custom
			(at 0 0.2794)
			(size 0.0762 0.0762)
			(layers "B.Cu" "B.Mask" "B.Paste")
			(net "GND")
			(options
				(clearance outline)
				(anchor circle)
			)
			(primitives
				(gr_poly
					(pts
						(arc
							(start 0.1524 0.127)
							(mid 0.137521 0.162921)
							(end 0.1016 0.1778)
						)
						(arc
							(start -0.1016 0.1778)
							(mid -0.137521 0.162921)
							(end -0.1524 0.127)
						)
						(arc
							(start -0.1524 -0.127)
							(mid -0.137521 -0.162921)
							(end -0.1016 -0.1778)
						)
						(arc
							(start 0.1016 -0.1778)
							(mid 0.137521 -0.162921)
							(end 0.1524 -0.127)
						)
					)
					(width 0)
					(fill yes)
				)
			)
		)
	)
	(footprint ""
		(layer "B.Cu")
		(at 178.420014 -20.579842 90)
		(property "Reference" "C323"
			(at 0 0 90)
			(layer "B.SilkS")
			(hide yes)
			(effects
				(font
					(size 1.27 1.27)
				)
				(justify mirror)
			)
		)
		(property "Value" "SCD22U10V1KX-GP"
			(at 2.8321 -1.7399 90)
			(unlocked yes)
			(layer "B.Fab")
			(hide yes)
			(effects
				(font
					(size 1.016 1.016)
					(thickness 0.1524)
				)
				(justify mirror)
			)
		)
		(property "Device Type" "C0201H13"
			(at 2.8321 -3.2639 90)
			(unlocked yes)
			(layer "B.Fab")
			(hide yes)
			(effects
				(font
					(size 1.016 1.016)
					(thickness 0.1524)
				)
				(justify mirror)
			)
		)
		(duplicate_pad_numbers_are_jumpers no)
		(fp_rect
			(start 0.2794 0.6477)
			(end -0.2794 -0.6477)
			(stroke
				(width 0)
				(type default)
			)
			(fill no)
			(layer "B.CrtYd")
		)
		(fp_rect
			(start 0.2794 0.6477)
			(end -0.2794 -0.6477)
			(stroke
				(width 0)
				(type default)
			)
			(fill no)
			(layer "B.Fab")
		)
		(pad "1" smd custom
			(at 0 -0.2794 270)
			(size 0.0762 0.0762)
			(layers "B.Cu" "B.Mask" "B.Paste")
			(net "PCIE_SCC_TO_COMP_C_6_DP")
			(options
				(clearance outline)
				(anchor circle)
			)
			(primitives
				(gr_poly
					(pts
						(arc
							(start 0.1524 0.127)
							(mid 0.137521 0.162921)
							(end 0.1016 0.1778)
						)
						(arc
							(start -0.1016 0.1778)
							(mid -0.137521 0.162921)
							(end -0.1524 0.127)
						)
						(arc
							(start -0.1524 -0.127)
							(mid -0.137521 -0.162921)
							(end -0.1016 -0.1778)
						)
						(arc
							(start 0.1016 -0.1778)
							(mid 0.137521 -0.162921)
							(end 0.1524 -0.127)
						)
					)
					(width 0)
					(fill yes)
				)
			)
		)
		(pad "2" smd custom
			(at 0 0.2794 270)
			(size 0.0762 0.0762)
			(layers "B.Cu" "B.Mask" "B.Paste")
			(net "PCIE_SCC_TO_COMP_6_DP")
			(options
				(clearance outline)
				(anchor circle)
			)
			(primitives
				(gr_poly
					(pts
						(arc
							(start 0.1524 0.127)
							(mid 0.137521 0.162921)
							(end 0.1016 0.1778)
						)
						(arc
							(start -0.1016 0.1778)
							(mid -0.137521 0.162921)
							(end -0.1524 0.127)
						)
						(arc
							(start -0.1524 -0.127)
							(mid -0.137521 -0.162921)
							(end -0.1016 -0.1778)
						)
						(arc
							(start 0.1016 -0.1778)
							(mid 0.137521 -0.162921)
							(end 0.1524 -0.127)
						)
					)
					(width 0)
					(fill yes)
				)
			)
		)
	)
	(footprint ""
		(layer "B.Cu")
		(at 62.1792 -56.7182 -90)
		(property "Reference" "C708"
			(at 0 0 90)
			(layer "B.SilkS")
			(hide yes)
			(effects
				(font
					(size 1.27 1.27)
				)
				(justify mirror)
			)
		)
		(property "Value" "SC10U6D3V5KX-4GP"
			(at 0.0762 -6.1214 270)
			(unlocked yes)
			(layer "B.Fab")
			(hide yes)
			(effects
				(font
					(size 1.016 1.016)
					(thickness 0.1524)
				)
				(justify mirror)
			)
		)
		(property "Device Type" "C805H58"
			(at 0.0762 -8.1534 270)
			(unlocked yes)
			(layer "B.Fab")
			(hide yes)
			(effects
				(font
					(size 1.016 1.016)
					(thickness 0.1524)
				)
				(justify mirror)
			)
		)
		(duplicate_pad_numbers_are_jumpers no)
		(fp_line
			(start -0.635 0)
			(end 0.635 0)
			(stroke
				(width 0.508)
				(type default)
			)
			(layer "B.SilkS")
		)
		(fp_rect
			(start 0.9652 1.778)
			(end -0.9652 -1.778)
			(stroke
				(width 0)
				(type default)
			)
			(fill no)
			(layer "B.CrtYd")
		)
		(fp_poly
			(pts
				(xy 0.9652 -1.778) (xy -0.9652 -1.778) (xy -0.9652 1.778) (xy 0.9652 1.778)
			)
			(stroke
				(width 0)
				(type default)
			)
			(fill no)
			(layer "B.Fab")
		)
		(pad "1" smd rect
			(at 0 -0.9652 90)
			(size 1.397 1.143)
			(layers "B.Cu" "B.Mask" "B.Paste")
			(net "P0V9")
		)
		(pad "2" smd rect
			(at 0 0.9652 90)
			(size 1.397 1.143)
			(layers "B.Cu" "B.Mask" "B.Paste")
			(net "GND")
		)
	)
	(footprint ""
		(layer "B.Cu")
		(at 198.882 -28.321 180)
		(property "Reference" "C378"
			(at 0 0 0)
			(layer "B.SilkS")
			(hide yes)
			(effects
				(font
					(size 1.27 1.27)
				)
				(justify mirror)
			)
		)
		(property "Value" "SC10U6D3V5KX-4GP"
			(at 0.0762 -6.1214 180)
			(unlocked yes)
			(layer "B.Fab")
			(hide yes)
			(effects
				(font
					(size 1.016 1.016)
					(thickness 0.1524)
				)
				(justify mirror)
			)
		)
		(property "Device Type" "C805H58"
			(at 0.0762 -8.1534 180)
			(unlocked yes)
			(layer "B.Fab")
			(hide yes)
			(effects
				(font
					(size 1.016 1.016)
					(thickness 0.1524)
				)
				(justify mirror)
			)
		)
		(duplicate_pad_numbers_are_jumpers no)
		(fp_line
			(start -0.635 0)
			(end 0.635 0)
			(stroke
				(width 0.508)
				(type default)
			)
			(layer "B.SilkS")
		)
		(fp_rect
			(start 0.9652 1.778)
			(end -0.9652 -1.778)
			(stroke
				(width 0)
				(type default)
			)
			(fill no)
			(layer "B.CrtYd")
		)
		(fp_poly
			(pts
				(xy 0.9652 -1.778) (xy -0.9652 -1.778) (xy -0.9652 1.778) (xy 0.9652 1.778)
			)
			(stroke
				(width 0)
				(type default)
			)
			(fill no)
			(layer "B.Fab")
		)
		(pad "1" smd rect
			(at 0 -0.9652)
			(size 1.397 1.143)
			(layers "B.Cu" "B.Mask" "B.Paste")
			(net "PCE_VDDH")
		)
		(pad "2" smd rect
			(at 0 0.9652)
			(size 1.397 1.143)
			(layers "B.Cu" "B.Mask" "B.Paste")
			(net "GND")
		)
	)
	(footprint ""
		(layer "B.Cu")
		(at 189.4078 -27.6098 90)
		(property "Reference" "TP62"
			(at 0 0 90)
			(layer "B.SilkS")
			(hide yes)
			(effects
				(font
					(size 1.27 1.27)
				)
				(justify mirror)
			)
		)
		(property "Value" "TPAD28-2-GP"
			(at 0.0127 -1.6637 90)
			(unlocked yes)
			(layer "B.Fab")
			(hide yes)
			(effects
				(font
					(size 1.016 1.016)
					(thickness 0.1524)
				)
				(justify mirror)
			)
		)
		(property "Device Type" "TPAD28"
			(at 0.0127 -3.1877 90)
			(unlocked yes)
			(layer "B.Fab")
			(hide yes)
			(effects
				(font
					(size 1.016 1.016)
					(thickness 0.1524)
				)
				(justify mirror)
			)
		)
		(duplicate_pad_numbers_are_jumpers no)
		(fp_poly
			(pts
				(arc
					(start 0 0.3556)
					(mid 0 -0.3556)
					(end 0 0.3556)
				)
			)
			(stroke
				(width 0)
				(type default)
			)
			(fill no)
			(layer "B.CrtYd")
		)
		(fp_poly
			(pts
				(arc
					(start 0 0.6096)
					(mid 0 -0.6096)
					(end 0 0.6096)
				)
			)
			(stroke
				(width 0)
				(type default)
			)
			(fill no)
			(layer "B.Fab")
		)
		(pad "1" smd circle
			(at 0 0 270)
			(size 0.7112 0.7112)
			(layers "B.Cu" "B.Mask" "B.Paste")
			(net "IOC_GPIO_9")
		)
	)
	(footprint ""
		(layer "B.Cu")
		(at 107.4928 -57.4802)
		(property "Reference" "C253"
			(at 0 0 0)
			(layer "B.SilkS")
			(hide yes)
			(effects
				(font
					(size 1.27 1.27)
				)
				(justify mirror)
			)
		)
		(property "Value" "SCD1U6D3V1KX-GP"
			(at 2.8321 -1.7399 0)
			(unlocked yes)
			(layer "B.Fab")
			(hide yes)
			(effects
				(font
					(size 1.016 1.016)
					(thickness 0.1524)
				)
				(justify mirror)
			)
		)
		(property "Device Type" "C0201H13"
			(at 2.8321 -3.2639 0)
			(unlocked yes)
			(layer "B.Fab")
			(hide yes)
			(effects
				(font
					(size 1.016 1.016)
					(thickness 0.1524)
				)
				(justify mirror)
			)
		)
		(duplicate_pad_numbers_are_jumpers no)
		(fp_rect
			(start 0.2794 0.6477)
			(end -0.2794 -0.6477)
			(stroke
				(width 0)
				(type default)
			)
			(fill no)
			(layer "B.CrtYd")
		)
		(fp_rect
			(start 0.2794 0.6477)
			(end -0.2794 -0.6477)
			(stroke
				(width 0)
				(type default)
			)
			(fill no)
			(layer "B.Fab")
		)
		(pad "1" smd custom
			(at 0 -0.2794 180)
			(size 0.0762 0.0762)
			(layers "B.Cu" "B.Mask" "B.Paste")
			(net "GB_VDDA")
			(options
				(clearance outline)
				(anchor circle)
			)
			(primitives
				(gr_poly
					(pts
						(arc
							(start 0.1524 0.127)
							(mid 0.137521 0.162921)
							(end 0.1016 0.1778)
						)
						(arc
							(start -0.1016 0.1778)
							(mid -0.137521 0.162921)
							(end -0.1524 0.127)
						)
						(arc
							(start -0.1524 -0.127)
							(mid -0.137521 -0.162921)
							(end -0.1016 -0.1778)
						)
						(arc
							(start 0.1016 -0.1778)
							(mid 0.137521 -0.162921)
							(end 0.1524 -0.127)
						)
					)
					(width 0)
					(fill yes)
				)
			)
		)
		(pad "2" smd custom
			(at 0 0.2794 180)
			(size 0.0762 0.0762)
			(layers "B.Cu" "B.Mask" "B.Paste")
			(net "GND")
			(options
				(clearance outline)
				(anchor circle)
			)
			(primitives
				(gr_poly
					(pts
						(arc
							(start 0.1524 0.127)
							(mid 0.137521 0.162921)
							(end 0.1016 0.1778)
						)
						(arc
							(start -0.1016 0.1778)
							(mid -0.137521 0.162921)
							(end -0.1524 0.127)
						)
						(arc
							(start -0.1524 -0.127)
							(mid -0.137521 -0.162921)
							(end -0.1016 -0.1778)
						)
						(arc
							(start 0.1016 -0.1778)
							(mid 0.137521 -0.162921)
							(end 0.1524 -0.127)
						)
					)
					(width 0)
					(fill yes)
				)
			)
		)
	)
	(footprint ""
		(layer "B.Cu")
		(at 139.4968 -89.6874)
		(property "Reference" "R52"
			(at 0 0 0)
			(layer "B.SilkS")
			(hide yes)
			(effects
				(font
					(size 1.27 1.27)
				)
				(justify mirror)
			)
		)
		(property "Value" "4K7R2F-GP"
			(at -0.064008 -3.993896 0)
			(unlocked yes)
			(layer "B.Fab")
			(hide yes)
			(effects
				(font
					(size 1.016 1.016)
					(thickness 0.1524)
				)
				(justify mirror)
			)
		)
		(property "Device Type" "R402H16"
			(at -0.064008 -5.517896 0)
			(unlocked yes)
			(layer "B.Fab")
			(hide yes)
			(effects
				(font
					(size 1.016 1.016)
					(thickness 0.1524)
				)
				(justify mirror)
			)
		)
		(duplicate_pad_numbers_are_jumpers no)
		(fp_line
			(start -0.508 -0.9398)
			(end 0.508 -0.9398)
			(stroke
				(width 0.1524)
				(type default)
			)
			(layer "B.SilkS")
		)
		(fp_line
			(start 0.508 -0.9398)
			(end 0.508 0.9398)
			(stroke
				(width 0.1524)
				(type default)
			)
			(layer "B.SilkS")
		)
		(fp_rect
			(start 0.508 0.9398)
			(end -0.508 -0.9398)
			(stroke
				(width 0)
				(type default)
			)
			(fill no)
			(layer "B.CrtYd")
		)
		(fp_rect
			(start 0.508 0.9398)
			(end -0.508 -0.9398)
			(stroke
				(width 0)
				(type default)
			)
			(fill no)
			(layer "B.Fab")
		)
		(pad "1" smd custom
			(at 0 -0.4445 180)
			(size 0.1397 0.1397)
			(layers "B.Cu" "B.Mask" "B.Paste")
			(net "P1V8_E")
			(options
				(clearance outline)
				(anchor circle)
			)
			(primitives
				(gr_poly
					(pts
						(arc
							(start -0.1778 0.2794)
							(mid -0.249642 0.249642)
							(end -0.2794 0.1778)
						)
						(arc
							(start -0.2794 -0.1778)
							(mid -0.249642 -0.249642)
							(end -0.1778 -0.2794)
						)
						(arc
							(start 0.1778 -0.2794)
							(mid 0.249642 -0.249642)
							(end 0.2794 -0.1778)
						)
						(arc
							(start 0.2794 0.1778)
							(mid 0.249642 0.249642)
							(end 0.1778 0.2794)
						)
					)
					(width 0)
					(fill yes)
				)
			)
		)
		(pad "2" smd custom
			(at 0 0.4445 180)
			(size 0.1397 0.1397)
			(layers "B.Cu" "B.Mask" "B.Paste")
			(net "I2C_SCC_SCL2_LS")
			(options
				(clearance outline)
				(anchor circle)
			)
			(primitives
				(gr_poly
					(pts
						(arc
							(start -0.1778 0.2794)
							(mid -0.249642 0.249642)
							(end -0.2794 0.1778)
						)
						(arc
							(start -0.2794 -0.1778)
							(mid -0.249642 -0.249642)
							(end -0.1778 -0.2794)
						)
						(arc
							(start 0.1778 -0.2794)
							(mid 0.249642 -0.249642)
							(end 0.2794 -0.1778)
						)
						(arc
							(start 0.2794 0.1778)
							(mid 0.249642 0.249642)
							(end 0.1778 0.2794)
						)
					)
					(width 0)
					(fill yes)
				)
			)
		)
	)
	(footprint ""
		(layer "B.Cu")
		(at 120.7516 -59.4487)
		(property "Reference" "C276"
			(at 0 0 0)
			(layer "B.SilkS")
			(hide yes)
			(effects
				(font
					(size 1.27 1.27)
				)
				(justify mirror)
			)
		)
		(property "Value" "SCD1U6D3V1KX-GP"
			(at 2.8321 -1.7399 0)
			(unlocked yes)
			(layer "B.Fab")
			(hide yes)
			(effects
				(font
					(size 1.016 1.016)
					(thickness 0.1524)
				)
				(justify mirror)
			)
		)
		(property "Device Type" "C0201H13"
			(at 2.8321 -3.2639 0)
			(unlocked yes)
			(layer "B.Fab")
			(hide yes)
			(effects
				(font
					(size 1.016 1.016)
					(thickness 0.1524)
				)
				(justify mirror)
			)
		)
		(duplicate_pad_numbers_are_jumpers no)
		(fp_rect
			(start 0.2794 0.6477)
			(end -0.2794 -0.6477)
			(stroke
				(width 0)
				(type default)
			)
			(fill no)
			(layer "B.CrtYd")
		)
		(fp_rect
			(start 0.2794 0.6477)
			(end -0.2794 -0.6477)
			(stroke
				(width 0)
				(type default)
			)
			(fill no)
			(layer "B.Fab")
		)
		(pad "1" smd custom
			(at 0 -0.2794 180)
			(size 0.0762 0.0762)
			(layers "B.Cu" "B.Mask" "B.Paste")
			(net "GB_VDDA")
			(options
				(clearance outline)
				(anchor circle)
			)
			(primitives
				(gr_poly
					(pts
						(arc
							(start 0.1524 0.127)
							(mid 0.137521 0.162921)
							(end 0.1016 0.1778)
						)
						(arc
							(start -0.1016 0.1778)
							(mid -0.137521 0.162921)
							(end -0.1524 0.127)
						)
						(arc
							(start -0.1524 -0.127)
							(mid -0.137521 -0.162921)
							(end -0.1016 -0.1778)
						)
						(arc
							(start 0.1016 -0.1778)
							(mid 0.137521 -0.162921)
							(end 0.1524 -0.127)
						)
					)
					(width 0)
					(fill yes)
				)
			)
		)
		(pad "2" smd custom
			(at 0 0.2794 180)
			(size 0.0762 0.0762)
			(layers "B.Cu" "B.Mask" "B.Paste")
			(net "GND")
			(options
				(clearance outline)
				(anchor circle)
			)
			(primitives
				(gr_poly
					(pts
						(arc
							(start 0.1524 0.127)
							(mid 0.137521 0.162921)
							(end 0.1016 0.1778)
						)
						(arc
							(start -0.1016 0.1778)
							(mid -0.137521 0.162921)
							(end -0.1524 0.127)
						)
						(arc
							(start -0.1524 -0.127)
							(mid -0.137521 -0.162921)
							(end -0.1016 -0.1778)
						)
						(arc
							(start 0.1016 -0.1778)
							(mid 0.137521 -0.162921)
							(end 0.1524 -0.127)
						)
					)
					(width 0)
					(fill yes)
				)
			)
		)
	)
	(footprint ""
		(layer "B.Cu")
		(at 92.168472 -71.192898)
		(property "Reference" "C196"
			(at 0 0 0)
			(layer "B.SilkS")
			(hide yes)
			(effects
				(font
					(size 1.27 1.27)
				)
				(justify mirror)
			)
		)
		(property "Value" "SC22U6D3V3MX-9-GP-U"
			(at 0 -2.8194 0)
			(unlocked yes)
			(layer "B.Fab")
			(hide yes)
			(effects
				(font
					(size 1.016 1.016)
					(thickness 0.1524)
				)
				(justify mirror)
			)
		)
		(property "Device Type" "C603H40"
			(at 0 -4.3434 0)
			(unlocked yes)
			(layer "B.Fab")
			(hide yes)
			(effects
				(font
					(size 1.016 1.016)
					(thickness 0.1524)
				)
				(justify mirror)
			)
		)
		(duplicate_pad_numbers_are_jumpers no)
		(fp_line
			(start -0.508 0)
			(end 0.508 0)
			(stroke
				(width 0.2032)
				(type default)
			)
			(layer "B.SilkS")
		)
		(fp_rect
			(start 0.5842 1.3335)
			(end -0.5842 -1.3335)
			(stroke
				(width 0)
				(type default)
			)
			(fill no)
			(layer "B.CrtYd")
		)
		(fp_rect
			(start 0.5842 1.3335)
			(end -0.5842 -1.3335)
			(stroke
				(width 0)
				(type default)
			)
			(fill no)
			(layer "B.Fab")
		)
		(pad "1" smd custom
			(at 0 -0.762 180)
			(size 0.2159 0.2159)
			(layers "B.Cu" "B.Mask" "B.Paste")
			(net "SYSPLL_VDDA18")
			(options
				(clearance outline)
				(anchor circle)
			)
			(primitives
				(gr_poly
					(pts
						(arc
							(start -0.3302 0.4318)
							(mid -0.402042 0.402042)
							(end -0.4318 0.3302)
						)
						(arc
							(start -0.4318 -0.3302)
							(mid -0.402042 -0.402042)
							(end -0.3302 -0.4318)
						)
						(arc
							(start 0.3302 -0.4318)
							(mid 0.402042 -0.402042)
							(end 0.4318 -0.3302)
						)
						(arc
							(start 0.4318 0.3302)
							(mid 0.402042 0.402042)
							(end 0.3302 0.4318)
						)
					)
					(width 0)
					(fill yes)
				)
			)
		)
		(pad "2" smd custom
			(at 0 0.762 180)
			(size 0.2159 0.2159)
			(layers "B.Cu" "B.Mask" "B.Paste")
			(net "GND")
			(options
				(clearance outline)
				(anchor circle)
			)
			(primitives
				(gr_poly
					(pts
						(arc
							(start -0.3302 0.4318)
							(mid -0.402042 0.402042)
							(end -0.4318 0.3302)
						)
						(arc
							(start -0.4318 -0.3302)
							(mid -0.402042 -0.402042)
							(end -0.3302 -0.4318)
						)
						(arc
							(start 0.3302 -0.4318)
							(mid 0.402042 -0.402042)
							(end 0.4318 -0.3302)
						)
						(arc
							(start 0.4318 0.3302)
							(mid 0.402042 0.402042)
							(end 0.3302 0.4318)
						)
					)
					(width 0)
					(fill yes)
				)
			)
		)
	)
	(footprint ""
		(layer "B.Cu")
		(at 199.4789 -23.749 180)
		(property "Reference" "R239"
			(at 0 0 0)
			(layer "B.SilkS")
			(hide yes)
			(effects
				(font
					(size 1.27 1.27)
				)
				(justify mirror)
			)
		)
		(property "Value" "150R2F-1-GP"
			(at -0.064008 -3.993896 180)
			(unlocked yes)
			(layer "B.Fab")
			(hide yes)
			(effects
				(font
					(size 1.016 1.016)
					(thickness 0.1524)
				)
				(justify mirror)
			)
		)
		(property "Device Type" "R402H16"
			(at -0.064008 -5.517896 180)
			(unlocked yes)
			(layer "B.Fab")
			(hide yes)
			(effects
				(font
					(size 1.016 1.016)
					(thickness 0.1524)
				)
				(justify mirror)
			)
		)
		(duplicate_pad_numbers_are_jumpers no)
		(fp_line
			(start 0.508 -0.9398)
			(end 0.508 0.9398)
			(stroke
				(width 0.1524)
				(type default)
			)
			(layer "B.SilkS")
		)
		(fp_line
			(start -0.508 -0.9398)
			(end 0.508 -0.9398)
			(stroke
				(width 0.1524)
				(type default)
			)
			(layer "B.SilkS")
		)
		(fp_rect
			(start 0.508 0.9398)
			(end -0.508 -0.9398)
			(stroke
				(width 0)
				(type default)
			)
			(fill no)
			(layer "B.CrtYd")
		)
		(fp_rect
			(start 0.508 0.9398)
			(end -0.508 -0.9398)
			(stroke
				(width 0)
				(type default)
			)
			(fill no)
			(layer "B.Fab")
		)
		(pad "1" smd custom
			(at 0 -0.4445)
			(size 0.1397 0.1397)
			(layers "B.Cu" "B.Mask" "B.Paste")
			(net "P3V3")
			(options
				(clearance outline)
				(anchor circle)
			)
			(primitives
				(gr_poly
					(pts
						(arc
							(start -0.1778 0.2794)
							(mid -0.249642 0.249642)
							(end -0.2794 0.1778)
						)
						(arc
							(start -0.2794 -0.1778)
							(mid -0.249642 -0.249642)
							(end -0.1778 -0.2794)
						)
						(arc
							(start 0.1778 -0.2794)
							(mid 0.249642 -0.249642)
							(end 0.2794 -0.1778)
						)
						(arc
							(start 0.2794 0.1778)
							(mid 0.249642 0.249642)
							(end 0.1778 0.2794)
						)
					)
					(width 0)
					(fill yes)
				)
			)
		)
		(pad "2" smd custom
			(at 0 0.4445)
			(size 0.1397 0.1397)
			(layers "B.Cu" "B.Mask" "B.Paste")
			(net "SYS_ERROR_LED_R")
			(options
				(clearance outline)
				(anchor circle)
			)
			(primitives
				(gr_poly
					(pts
						(arc
							(start -0.1778 0.2794)
							(mid -0.249642 0.249642)
							(end -0.2794 0.1778)
						)
						(arc
							(start -0.2794 -0.1778)
							(mid -0.249642 -0.249642)
							(end -0.1778 -0.2794)
						)
						(arc
							(start 0.1778 -0.2794)
							(mid 0.249642 -0.249642)
							(end 0.2794 -0.1778)
						)
						(arc
							(start 0.2794 0.1778)
							(mid 0.249642 0.249642)
							(end 0.1778 0.2794)
						)
					)
					(width 0)
					(fill yes)
				)
			)
		)
	)
	(footprint ""
		(layer "B.Cu")
		(at 157.2768 -111.0996)
		(property "Reference" "C700"
			(at 0 0 0)
			(layer "B.SilkS")
			(hide yes)
			(effects
				(font
					(size 1.27 1.27)
				)
				(justify mirror)
			)
		)
		(property "Value" "SC10U16V5KX-7-GP-U"
			(at 0.0762 -6.1214 0)
			(unlocked yes)
			(layer "B.Fab")
			(hide yes)
			(effects
				(font
					(size 1.016 1.016)
					(thickness 0.1524)
				)
				(justify mirror)
			)
		)
		(property "Device Type" "C805H58"
			(at 0.0762 -8.1534 0)
			(unlocked yes)
			(layer "B.Fab")
			(hide yes)
			(effects
				(font
					(size 1.016 1.016)
					(thickness 0.1524)
				)
				(justify mirror)
			)
		)
		(duplicate_pad_numbers_are_jumpers no)
		(fp_line
			(start -0.635 0)
			(end 0.635 0)
			(stroke
				(width 0.508)
				(type default)
			)
			(layer "B.SilkS")
		)
		(fp_rect
			(start 0.9652 1.778)
			(end -0.9652 -1.778)
			(stroke
				(width 0)
				(type default)
			)
			(fill no)
			(layer "B.CrtYd")
		)
		(fp_poly
			(pts
				(xy 0.9652 -1.778) (xy -0.9652 -1.778) (xy -0.9652 1.778) (xy 0.9652 1.778)
			)
			(stroke
				(width 0)
				(type default)
			)
			(fill no)
			(layer "B.Fab")
		)
		(pad "1" smd rect
			(at 0 -0.9652 180)
			(size 1.397 1.143)
			(layers "B.Cu" "B.Mask" "B.Paste")
			(net "P12V_STBY_VIN_U11")
		)
		(pad "2" smd rect
			(at 0 0.9652 180)
			(size 1.397 1.143)
			(layers "B.Cu" "B.Mask" "B.Paste")
			(net "GND")
		)
	)
	(footprint ""
		(layer "B.Cu")
		(at 193.26098 -20.8026 90)
		(property "Reference" "R242"
			(at 0 0 90)
			(layer "B.SilkS")
			(hide yes)
			(effects
				(font
					(size 1.27 1.27)
				)
				(justify mirror)
			)
		)
		(property "Value" "4K7R2F-GP"
			(at -0.064008 -3.993896 90)
			(unlocked yes)
			(layer "B.Fab")
			(hide yes)
			(effects
				(font
					(size 1.016 1.016)
					(thickness 0.1524)
				)
				(justify mirror)
			)
		)
		(property "Device Type" "R402H16"
			(at -0.064008 -5.517896 90)
			(unlocked yes)
			(layer "B.Fab")
			(hide yes)
			(effects
				(font
					(size 1.016 1.016)
					(thickness 0.1524)
				)
				(justify mirror)
			)
		)
		(duplicate_pad_numbers_are_jumpers no)
		(fp_line
			(start 0.508 -0.9398)
			(end 0.508 0.9398)
			(stroke
				(width 0.1524)
				(type default)
			)
			(layer "B.SilkS")
		)
		(fp_line
			(start -0.508 -0.9398)
			(end 0.508 -0.9398)
			(stroke
				(width 0.1524)
				(type default)
			)
			(layer "B.SilkS")
		)
		(fp_rect
			(start 0.508 0.9398)
			(end -0.508 -0.9398)
			(stroke
				(width 0)
				(type default)
			)
			(fill no)
			(layer "B.CrtYd")
		)
		(fp_rect
			(start 0.508 0.9398)
			(end -0.508 -0.9398)
			(stroke
				(width 0)
				(type default)
			)
			(fill no)
			(layer "B.Fab")
		)
		(pad "1" smd custom
			(at 0 -0.4445 270)
			(size 0.1397 0.1397)
			(layers "B.Cu" "B.Mask" "B.Paste")
			(net "P1V8_C")
			(options
				(clearance outline)
				(anchor circle)
			)
			(primitives
				(gr_poly
					(pts
						(arc
							(start -0.1778 0.2794)
							(mid -0.249642 0.249642)
							(end -0.2794 0.1778)
						)
						(arc
							(start -0.2794 -0.1778)
							(mid -0.249642 -0.249642)
							(end -0.1778 -0.2794)
						)
						(arc
							(start 0.1778 -0.2794)
							(mid 0.249642 -0.249642)
							(end 0.2794 -0.1778)
						)
						(arc
							(start 0.2794 0.1778)
							(mid 0.249642 0.249642)
							(end 0.1778 0.2794)
						)
					)
					(width 0)
					(fill yes)
				)
			)
		)
		(pad "2" smd custom
			(at 0 0.4445 270)
			(size 0.1397 0.1397)
			(layers "B.Cu" "B.Mask" "B.Paste")
			(net "SYS_RST")
			(options
				(clearance outline)
				(anchor circle)
			)
			(primitives
				(gr_poly
					(pts
						(arc
							(start -0.1778 0.2794)
							(mid -0.249642 0.249642)
							(end -0.2794 0.1778)
						)
						(arc
							(start -0.2794 -0.1778)
							(mid -0.249642 -0.249642)
							(end -0.1778 -0.2794)
						)
						(arc
							(start 0.1778 -0.2794)
							(mid 0.249642 -0.249642)
							(end 0.2794 -0.1778)
						)
						(arc
							(start 0.2794 0.1778)
							(mid 0.249642 0.249642)
							(end 0.1778 0.2794)
						)
					)
					(width 0)
					(fill yes)
				)
			)
		)
	)
	(footprint ""
		(layer "B.Cu")
		(at 114.3 -70.3834 180)
		(property "Reference" "C171"
			(at 0 0 0)
			(layer "B.SilkS")
			(hide yes)
			(effects
				(font
					(size 1.27 1.27)
				)
				(justify mirror)
			)
		)
		(property "Value" "SCD1U6D3V1KX-GP"
			(at 2.8321 -1.7399 180)
			(unlocked yes)
			(layer "B.Fab")
			(hide yes)
			(effects
				(font
					(size 1.016 1.016)
					(thickness 0.1524)
				)
				(justify mirror)
			)
		)
		(property "Device Type" "C0201H13"
			(at 2.8321 -3.2639 180)
			(unlocked yes)
			(layer "B.Fab")
			(hide yes)
			(effects
				(font
					(size 1.016 1.016)
					(thickness 0.1524)
				)
				(justify mirror)
			)
		)
		(duplicate_pad_numbers_are_jumpers no)
		(fp_rect
			(start 0.2794 0.6477)
			(end -0.2794 -0.6477)
			(stroke
				(width 0)
				(type default)
			)
			(fill no)
			(layer "B.CrtYd")
		)
		(fp_rect
			(start 0.2794 0.6477)
			(end -0.2794 -0.6477)
			(stroke
				(width 0)
				(type default)
			)
			(fill no)
			(layer "B.Fab")
		)
		(pad "1" smd custom
			(at 0 -0.2794)
			(size 0.0762 0.0762)
			(layers "B.Cu" "B.Mask" "B.Paste")
			(net "P0V9")
			(options
				(clearance outline)
				(anchor circle)
			)
			(primitives
				(gr_poly
					(pts
						(arc
							(start 0.1524 0.127)
							(mid 0.137521 0.162921)
							(end 0.1016 0.1778)
						)
						(arc
							(start -0.1016 0.1778)
							(mid -0.137521 0.162921)
							(end -0.1524 0.127)
						)
						(arc
							(start -0.1524 -0.127)
							(mid -0.137521 -0.162921)
							(end -0.1016 -0.1778)
						)
						(arc
							(start 0.1016 -0.1778)
							(mid 0.137521 -0.162921)
							(end 0.1524 -0.127)
						)
					)
					(width 0)
					(fill yes)
				)
			)
		)
		(pad "2" smd custom
			(at 0 0.2794)
			(size 0.0762 0.0762)
			(layers "B.Cu" "B.Mask" "B.Paste")
			(net "GND")
			(options
				(clearance outline)
				(anchor circle)
			)
			(primitives
				(gr_poly
					(pts
						(arc
							(start 0.1524 0.127)
							(mid 0.137521 0.162921)
							(end 0.1016 0.1778)
						)
						(arc
							(start -0.1016 0.1778)
							(mid -0.137521 0.162921)
							(end -0.1524 0.127)
						)
						(arc
							(start -0.1524 -0.127)
							(mid -0.137521 -0.162921)
							(end -0.1016 -0.1778)
						)
						(arc
							(start 0.1016 -0.1778)
							(mid 0.137521 -0.162921)
							(end 0.1524 -0.127)
						)
					)
					(width 0)
					(fill yes)
				)
			)
		)
	)
	(footprint ""
		(layer "B.Cu")
		(at 124.2822 -63.5 -90)
		(property "Reference" "C258"
			(at 0 0 90)
			(layer "B.SilkS")
			(hide yes)
			(effects
				(font
					(size 1.27 1.27)
				)
				(justify mirror)
			)
		)
		(property "Value" "SCD1U6D3V1KX-GP"
			(at 2.8321 -1.7399 270)
			(unlocked yes)
			(layer "B.Fab")
			(hide yes)
			(effects
				(font
					(size 1.016 1.016)
					(thickness 0.1524)
				)
				(justify mirror)
			)
		)
		(property "Device Type" "C0201H13"
			(at 2.8321 -3.2639 270)
			(unlocked yes)
			(layer "B.Fab")
			(hide yes)
			(effects
				(font
					(size 1.016 1.016)
					(thickness 0.1524)
				)
				(justify mirror)
			)
		)
		(duplicate_pad_numbers_are_jumpers no)
		(fp_rect
			(start 0.2794 0.6477)
			(end -0.2794 -0.6477)
			(stroke
				(width 0)
				(type default)
			)
			(fill no)
			(layer "B.CrtYd")
		)
		(fp_rect
			(start 0.2794 0.6477)
			(end -0.2794 -0.6477)
			(stroke
				(width 0)
				(type default)
			)
			(fill no)
			(layer "B.Fab")
		)
		(pad "1" smd custom
			(at 0 -0.2794 90)
			(size 0.0762 0.0762)
			(layers "B.Cu" "B.Mask" "B.Paste")
			(net "GB_VDDA")
			(options
				(clearance outline)
				(anchor circle)
			)
			(primitives
				(gr_poly
					(pts
						(arc
							(start 0.1524 0.127)
							(mid 0.137521 0.162921)
							(end 0.1016 0.1778)
						)
						(arc
							(start -0.1016 0.1778)
							(mid -0.137521 0.162921)
							(end -0.1524 0.127)
						)
						(arc
							(start -0.1524 -0.127)
							(mid -0.137521 -0.162921)
							(end -0.1016 -0.1778)
						)
						(arc
							(start 0.1016 -0.1778)
							(mid 0.137521 -0.162921)
							(end 0.1524 -0.127)
						)
					)
					(width 0)
					(fill yes)
				)
			)
		)
		(pad "2" smd custom
			(at 0 0.2794 90)
			(size 0.0762 0.0762)
			(layers "B.Cu" "B.Mask" "B.Paste")
			(net "GND")
			(options
				(clearance outline)
				(anchor circle)
			)
			(primitives
				(gr_poly
					(pts
						(arc
							(start 0.1524 0.127)
							(mid 0.137521 0.162921)
							(end 0.1016 0.1778)
						)
						(arc
							(start -0.1016 0.1778)
							(mid -0.137521 0.162921)
							(end -0.1524 0.127)
						)
						(arc
							(start -0.1524 -0.127)
							(mid -0.137521 -0.162921)
							(end -0.1016 -0.1778)
						)
						(arc
							(start 0.1016 -0.1778)
							(mid 0.137521 -0.162921)
							(end 0.1524 -0.127)
						)
					)
					(width 0)
					(fill yes)
				)
			)
		)
	)
	(footprint ""
		(layer "B.Cu")
		(at 200.179178 -31.849822)
		(property "Reference" "C363"
			(at 0 0 0)
			(layer "B.SilkS")
			(hide yes)
			(effects
				(font
					(size 1.27 1.27)
				)
				(justify mirror)
			)
		)
		(property "Value" "SC22U6D3V3MX-9-GP-U"
			(at 0 -2.8194 0)
			(unlocked yes)
			(layer "B.Fab")
			(hide yes)
			(effects
				(font
					(size 1.016 1.016)
					(thickness 0.1524)
				)
				(justify mirror)
			)
		)
		(property "Device Type" "C603H40"
			(at 0 -4.3434 0)
			(unlocked yes)
			(layer "B.Fab")
			(hide yes)
			(effects
				(font
					(size 1.016 1.016)
					(thickness 0.1524)
				)
				(justify mirror)
			)
		)
		(duplicate_pad_numbers_are_jumpers no)
		(fp_line
			(start -0.508 0)
			(end 0.508 0)
			(stroke
				(width 0.2032)
				(type default)
			)
			(layer "B.SilkS")
		)
		(fp_rect
			(start 0.5842 1.3335)
			(end -0.5842 -1.3335)
			(stroke
				(width 0)
				(type default)
			)
			(fill no)
			(layer "B.CrtYd")
		)
		(fp_rect
			(start 0.5842 1.3335)
			(end -0.5842 -1.3335)
			(stroke
				(width 0)
				(type default)
			)
			(fill no)
			(layer "B.Fab")
		)
		(pad "1" smd custom
			(at 0 -0.762 180)
			(size 0.2159 0.2159)
			(layers "B.Cu" "B.Mask" "B.Paste")
			(net "PLL_VDD")
			(options
				(clearance outline)
				(anchor circle)
			)
			(primitives
				(gr_poly
					(pts
						(arc
							(start -0.3302 0.4318)
							(mid -0.402042 0.402042)
							(end -0.4318 0.3302)
						)
						(arc
							(start -0.4318 -0.3302)
							(mid -0.402042 -0.402042)
							(end -0.3302 -0.4318)
						)
						(arc
							(start 0.3302 -0.4318)
							(mid 0.402042 -0.402042)
							(end 0.4318 -0.3302)
						)
						(arc
							(start 0.4318 0.3302)
							(mid 0.402042 0.402042)
							(end 0.3302 0.4318)
						)
					)
					(width 0)
					(fill yes)
				)
			)
		)
		(pad "2" smd custom
			(at 0 0.762 180)
			(size 0.2159 0.2159)
			(layers "B.Cu" "B.Mask" "B.Paste")
			(net "GND")
			(options
				(clearance outline)
				(anchor circle)
			)
			(primitives
				(gr_poly
					(pts
						(arc
							(start -0.3302 0.4318)
							(mid -0.402042 0.402042)
							(end -0.4318 0.3302)
						)
						(arc
							(start -0.4318 -0.3302)
							(mid -0.402042 -0.402042)
							(end -0.3302 -0.4318)
						)
						(arc
							(start 0.3302 -0.4318)
							(mid 0.402042 -0.402042)
							(end 0.4318 -0.3302)
						)
						(arc
							(start 0.4318 0.3302)
							(mid 0.402042 0.402042)
							(end 0.3302 0.4318)
						)
					)
					(width 0)
					(fill yes)
				)
			)
		)
	)
	(footprint ""
		(layer "B.Cu")
		(at 175.124872 -63.09487 180)
		(property "Reference" "R546"
			(at 0 0 0)
			(layer "B.SilkS")
			(hide yes)
			(effects
				(font
					(size 1.27 1.27)
				)
				(justify mirror)
			)
		)
		(property "Value" "4K7R2F-GP"
			(at -0.064008 -3.993896 180)
			(unlocked yes)
			(layer "B.Fab")
			(hide yes)
			(effects
				(font
					(size 1.016 1.016)
					(thickness 0.1524)
				)
				(justify mirror)
			)
		)
		(property "Device Type" "R402H16"
			(at -0.064008 -5.517896 180)
			(unlocked yes)
			(layer "B.Fab")
			(hide yes)
			(effects
				(font
					(size 1.016 1.016)
					(thickness 0.1524)
				)
				(justify mirror)
			)
		)
		(duplicate_pad_numbers_are_jumpers no)
		(fp_line
			(start 0.508 -0.9398)
			(end 0.508 0.9398)
			(stroke
				(width 0.1524)
				(type default)
			)
			(layer "B.SilkS")
		)
		(fp_line
			(start -0.508 -0.9398)
			(end 0.508 -0.9398)
			(stroke
				(width 0.1524)
				(type default)
			)
			(layer "B.SilkS")
		)
		(fp_rect
			(start 0.508 0.9398)
			(end -0.508 -0.9398)
			(stroke
				(width 0)
				(type default)
			)
			(fill no)
			(layer "B.CrtYd")
		)
		(fp_rect
			(start 0.508 0.9398)
			(end -0.508 -0.9398)
			(stroke
				(width 0)
				(type default)
			)
			(fill no)
			(layer "B.Fab")
		)
		(pad "1" smd custom
			(at 0 -0.4445)
			(size 0.1397 0.1397)
			(layers "B.Cu" "B.Mask" "B.Paste")
			(net "P1V8_C")
			(options
				(clearance outline)
				(anchor circle)
			)
			(primitives
				(gr_poly
					(pts
						(arc
							(start -0.1778 0.2794)
							(mid -0.249642 0.249642)
							(end -0.2794 0.1778)
						)
						(arc
							(start -0.2794 -0.1778)
							(mid -0.249642 -0.249642)
							(end -0.1778 -0.2794)
						)
						(arc
							(start 0.1778 -0.2794)
							(mid 0.249642 -0.249642)
							(end 0.2794 -0.1778)
						)
						(arc
							(start 0.2794 0.1778)
							(mid 0.249642 0.249642)
							(end 0.1778 0.2794)
						)
					)
					(width 0)
					(fill yes)
				)
			)
		)
		(pad "2" smd custom
			(at 0 0.4445)
			(size 0.1397 0.1397)
			(layers "B.Cu" "B.Mask" "B.Paste")
			(net "IOC_RESET_N")
			(options
				(clearance outline)
				(anchor circle)
			)
			(primitives
				(gr_poly
					(pts
						(arc
							(start -0.1778 0.2794)
							(mid -0.249642 0.249642)
							(end -0.2794 0.1778)
						)
						(arc
							(start -0.2794 -0.1778)
							(mid -0.249642 -0.249642)
							(end -0.1778 -0.2794)
						)
						(arc
							(start 0.1778 -0.2794)
							(mid 0.249642 -0.249642)
							(end 0.2794 -0.1778)
						)
						(arc
							(start 0.2794 0.1778)
							(mid 0.249642 0.249642)
							(end 0.1778 0.2794)
						)
					)
					(width 0)
					(fill yes)
				)
			)
		)
	)
	(footprint ""
		(layer "B.Cu")
		(at 159.512 -52.07)
		(property "Reference" "R192"
			(at 0 0 0)
			(layer "B.SilkS")
			(hide yes)
			(effects
				(font
					(size 1.27 1.27)
				)
				(justify mirror)
			)
		)
		(property "Value" "2K2R2F-GP"
			(at -0.064008 -3.993896 0)
			(unlocked yes)
			(layer "B.Fab")
			(hide yes)
			(effects
				(font
					(size 1.016 1.016)
					(thickness 0.1524)
				)
				(justify mirror)
			)
		)
		(property "Device Type" "R402H16"
			(at -0.064008 -5.517896 0)
			(unlocked yes)
			(layer "B.Fab")
			(hide yes)
			(effects
				(font
					(size 1.016 1.016)
					(thickness 0.1524)
				)
				(justify mirror)
			)
		)
		(duplicate_pad_numbers_are_jumpers no)
		(fp_line
			(start -0.508 -0.9398)
			(end 0.508 -0.9398)
			(stroke
				(width 0.1524)
				(type default)
			)
			(layer "B.SilkS")
		)
		(fp_line
			(start 0.508 -0.9398)
			(end 0.508 0.9398)
			(stroke
				(width 0.1524)
				(type default)
			)
			(layer "B.SilkS")
		)
		(fp_rect
			(start 0.508 0.9398)
			(end -0.508 -0.9398)
			(stroke
				(width 0)
				(type default)
			)
			(fill no)
			(layer "B.CrtYd")
		)
		(fp_rect
			(start 0.508 0.9398)
			(end -0.508 -0.9398)
			(stroke
				(width 0)
				(type default)
			)
			(fill no)
			(layer "B.Fab")
		)
		(pad "1" smd custom
			(at 0 -0.4445 180)
			(size 0.1397 0.1397)
			(layers "B.Cu" "B.Mask" "B.Paste")
			(net "P1V8_C")
			(options
				(clearance outline)
				(anchor circle)
			)
			(primitives
				(gr_poly
					(pts
						(arc
							(start -0.1778 0.2794)
							(mid -0.249642 0.249642)
							(end -0.2794 0.1778)
						)
						(arc
							(start -0.2794 -0.1778)
							(mid -0.249642 -0.249642)
							(end -0.1778 -0.2794)
						)
						(arc
							(start 0.1778 -0.2794)
							(mid 0.249642 -0.249642)
							(end 0.2794 -0.1778)
						)
						(arc
							(start 0.2794 0.1778)
							(mid 0.249642 0.249642)
							(end 0.1778 0.2794)
						)
					)
					(width 0)
					(fill yes)
				)
			)
		)
		(pad "2" smd custom
			(at 0 0.4445 180)
			(size 0.1397 0.1397)
			(layers "B.Cu" "B.Mask" "B.Paste")
			(net "SIO_CLK_0")
			(options
				(clearance outline)
				(anchor circle)
			)
			(primitives
				(gr_poly
					(pts
						(arc
							(start -0.1778 0.2794)
							(mid -0.249642 0.249642)
							(end -0.2794 0.1778)
						)
						(arc
							(start -0.2794 -0.1778)
							(mid -0.249642 -0.249642)
							(end -0.1778 -0.2794)
						)
						(arc
							(start 0.1778 -0.2794)
							(mid 0.249642 -0.249642)
							(end 0.2794 -0.1778)
						)
						(arc
							(start 0.2794 0.1778)
							(mid 0.249642 0.249642)
							(end 0.1778 0.2794)
						)
					)
					(width 0)
					(fill yes)
				)
			)
		)
	)
	(footprint ""
		(layer "B.Cu")
		(at 201.676 -28.575 90)
		(property "Reference" "L25"
			(at 0 0 90)
			(layer "B.SilkS")
			(hide yes)
			(effects
				(font
					(size 1.27 1.27)
				)
				(justify mirror)
			)
		)
		(property "Value" "MPZ2012S601AT-GP"
			(at 0 -4.2418 90)
			(unlocked yes)
			(layer "B.Fab")
			(hide yes)
			(effects
				(font
					(size 1.016 1.016)
					(thickness 0.1524)
				)
				(justify mirror)
			)
		)
		(property "Device Type" "L805H42"
			(at 0 -5.7912 90)
			(unlocked yes)
			(layer "B.Fab")
			(hide yes)
			(effects
				(font
					(size 1.016 1.016)
					(thickness 0.1524)
				)
				(justify mirror)
			)
		)
		(duplicate_pad_numbers_are_jumpers no)
		(fp_line
			(start 0.889 -1.7018)
			(end -0.889 -1.7018)
			(stroke
				(width 0.1524)
				(type default)
			)
			(layer "B.SilkS")
		)
		(fp_line
			(start -0.889 -1.7018)
			(end -0.889 1.7018)
			(stroke
				(width 0.1524)
				(type default)
			)
			(layer "B.SilkS")
		)
		(fp_line
			(start 0.889 1.7018)
			(end 0.889 -1.7018)
			(stroke
				(width 0.1524)
				(type default)
			)
			(layer "B.SilkS")
		)
		(fp_line
			(start -0.889 1.7018)
			(end 0.889 1.7018)
			(stroke
				(width 0.1524)
				(type default)
			)
			(layer "B.SilkS")
		)
		(fp_rect
			(start 0.9652 1.778)
			(end -0.9652 -1.778)
			(stroke
				(width 0)
				(type default)
			)
			(fill no)
			(layer "B.CrtYd")
		)
		(fp_rect
			(start 0.9652 1.778)
			(end -0.9652 -1.778)
			(stroke
				(width 0)
				(type default)
			)
			(fill no)
			(layer "B.Fab")
		)
		(pad "1" smd rect
			(at 0 -0.9652 270)
			(size 1.397 1.143)
			(layers "B.Cu" "B.Mask" "B.Paste")
			(net "PCE_VDDH")
		)
		(pad "2" smd rect
			(at 0 0.9652 270)
			(size 1.397 1.143)
			(layers "B.Cu" "B.Mask" "B.Paste")
			(net "P1V5_C")
		)
	)
	(footprint ""
		(layer "B.Cu")
		(at 121.2596 -89.5604 180)
		(property "Reference" "R302"
			(at 0 0 0)
			(layer "B.SilkS")
			(hide yes)
			(effects
				(font
					(size 1.27 1.27)
				)
				(justify mirror)
			)
		)
		(property "Value" "4K75R2F-1-GP"
			(at -0.064008 -3.993896 180)
			(unlocked yes)
			(layer "B.Fab")
			(hide yes)
			(effects
				(font
					(size 1.016 1.016)
					(thickness 0.1524)
				)
				(justify mirror)
			)
		)
		(property "Device Type" "R402H16"
			(at -0.064008 -5.517896 180)
			(unlocked yes)
			(layer "B.Fab")
			(hide yes)
			(effects
				(font
					(size 1.016 1.016)
					(thickness 0.1524)
				)
				(justify mirror)
			)
		)
		(duplicate_pad_numbers_are_jumpers no)
		(fp_line
			(start 0.508 -0.9398)
			(end 0.508 0.9398)
			(stroke
				(width 0.1524)
				(type default)
			)
			(layer "B.SilkS")
		)
		(fp_line
			(start -0.508 -0.9398)
			(end 0.508 -0.9398)
			(stroke
				(width 0.1524)
				(type default)
			)
			(layer "B.SilkS")
		)
		(fp_rect
			(start 0.508 0.9398)
			(end -0.508 -0.9398)
			(stroke
				(width 0)
				(type default)
			)
			(fill no)
			(layer "B.CrtYd")
		)
		(fp_rect
			(start 0.508 0.9398)
			(end -0.508 -0.9398)
			(stroke
				(width 0)
				(type default)
			)
			(fill no)
			(layer "B.Fab")
		)
		(pad "1" smd custom
			(at 0 -0.4445)
			(size 0.1397 0.1397)
			(layers "B.Cu" "B.Mask" "B.Paste")
			(net "P1V8_E")
			(options
				(clearance outline)
				(anchor circle)
			)
			(primitives
				(gr_poly
					(pts
						(arc
							(start -0.1778 0.2794)
							(mid -0.249642 0.249642)
							(end -0.2794 0.1778)
						)
						(arc
							(start -0.2794 -0.1778)
							(mid -0.249642 -0.249642)
							(end -0.1778 -0.2794)
						)
						(arc
							(start 0.1778 -0.2794)
							(mid 0.249642 -0.249642)
							(end 0.2794 -0.1778)
						)
						(arc
							(start 0.2794 0.1778)
							(mid 0.249642 0.249642)
							(end 0.1778 0.2794)
						)
					)
					(width 0)
					(fill yes)
				)
			)
		)
		(pad "2" smd custom
			(at 0 0.4445)
			(size 0.1397 0.1397)
			(layers "B.Cu" "B.Mask" "B.Paste")
			(net "ICE_TCK")
			(options
				(clearance outline)
				(anchor circle)
			)
			(primitives
				(gr_poly
					(pts
						(arc
							(start -0.1778 0.2794)
							(mid -0.249642 0.249642)
							(end -0.2794 0.1778)
						)
						(arc
							(start -0.2794 -0.1778)
							(mid -0.249642 -0.249642)
							(end -0.1778 -0.2794)
						)
						(arc
							(start 0.1778 -0.2794)
							(mid 0.249642 -0.249642)
							(end 0.2794 -0.1778)
						)
						(arc
							(start 0.2794 0.1778)
							(mid 0.249642 0.249642)
							(end 0.1778 0.2794)
						)
					)
					(width 0)
					(fill yes)
				)
			)
		)
	)
	(footprint ""
		(layer "B.Cu")
		(at 181.443884 -70.245732 90)
		(property "Reference" "R231"
			(at 0 0 90)
			(layer "B.SilkS")
			(hide yes)
			(effects
				(font
					(size 1.27 1.27)
				)
				(justify mirror)
			)
		)
		(property "Value" "10KR2F-2-GP"
			(at -0.064008 -3.993896 90)
			(unlocked yes)
			(layer "B.Fab")
			(hide yes)
			(effects
				(font
					(size 1.016 1.016)
					(thickness 0.1524)
				)
				(justify mirror)
			)
		)
		(property "Device Type" "R402H16"
			(at -0.064008 -5.517896 90)
			(unlocked yes)
			(layer "B.Fab")
			(hide yes)
			(effects
				(font
					(size 1.016 1.016)
					(thickness 0.1524)
				)
				(justify mirror)
			)
		)
		(duplicate_pad_numbers_are_jumpers no)
		(fp_line
			(start 0.508 -0.9398)
			(end 0.508 0.9398)
			(stroke
				(width 0.1524)
				(type default)
			)
			(layer "B.SilkS")
		)
		(fp_line
			(start -0.508 -0.9398)
			(end 0.508 -0.9398)
			(stroke
				(width 0.1524)
				(type default)
			)
			(layer "B.SilkS")
		)
		(fp_rect
			(start 0.508 0.9398)
			(end -0.508 -0.9398)
			(stroke
				(width 0)
				(type default)
			)
			(fill no)
			(layer "B.CrtYd")
		)
		(fp_rect
			(start 0.508 0.9398)
			(end -0.508 -0.9398)
			(stroke
				(width 0)
				(type default)
			)
			(fill no)
			(layer "B.Fab")
		)
		(pad "1" smd custom
			(at 0 -0.4445 270)
			(size 0.1397 0.1397)
			(layers "B.Cu" "B.Mask" "B.Paste")
			(net "P1V8_C")
			(options
				(clearance outline)
				(anchor circle)
			)
			(primitives
				(gr_poly
					(pts
						(arc
							(start -0.1778 0.2794)
							(mid -0.249642 0.249642)
							(end -0.2794 0.1778)
						)
						(arc
							(start -0.2794 -0.1778)
							(mid -0.249642 -0.249642)
							(end -0.1778 -0.2794)
						)
						(arc
							(start 0.1778 -0.2794)
							(mid 0.249642 -0.249642)
							(end 0.2794 -0.1778)
						)
						(arc
							(start 0.2794 0.1778)
							(mid 0.249642 0.249642)
							(end 0.1778 0.2794)
						)
					)
					(width 0)
					(fill yes)
				)
			)
		)
		(pad "2" smd custom
			(at 0 0.4445 270)
			(size 0.1397 0.1397)
			(layers "B.Cu" "B.Mask" "B.Paste")
			(net "IOC_WP_N")
			(options
				(clearance outline)
				(anchor circle)
			)
			(primitives
				(gr_poly
					(pts
						(arc
							(start -0.1778 0.2794)
							(mid -0.249642 0.249642)
							(end -0.2794 0.1778)
						)
						(arc
							(start -0.2794 -0.1778)
							(mid -0.249642 -0.249642)
							(end -0.1778 -0.2794)
						)
						(arc
							(start 0.1778 -0.2794)
							(mid 0.249642 -0.249642)
							(end 0.2794 -0.1778)
						)
						(arc
							(start 0.2794 0.1778)
							(mid 0.249642 0.249642)
							(end 0.1778 0.2794)
						)
					)
					(width 0)
					(fill yes)
				)
			)
		)
	)
	(footprint ""
		(layer "B.Cu")
		(at 89.465912 -71.040498)
		(property "Reference" "L2"
			(at 0 0 0)
			(layer "B.SilkS")
			(hide yes)
			(effects
				(font
					(size 1.27 1.27)
				)
				(justify mirror)
			)
		)
		(property "Value" "MPZ2012S601AT-GP"
			(at 0 -4.2418 0)
			(unlocked yes)
			(layer "B.Fab")
			(hide yes)
			(effects
				(font
					(size 1.016 1.016)
					(thickness 0.1524)
				)
				(justify mirror)
			)
		)
		(property "Device Type" "L805H42"
			(at 0 -5.7912 0)
			(unlocked yes)
			(layer "B.Fab")
			(hide yes)
			(effects
				(font
					(size 1.016 1.016)
					(thickness 0.1524)
				)
				(justify mirror)
			)
		)
		(duplicate_pad_numbers_are_jumpers no)
		(fp_line
			(start -0.889 -1.7018)
			(end -0.889 1.7018)
			(stroke
				(width 0.1524)
				(type default)
			)
			(layer "B.SilkS")
		)
		(fp_line
			(start -0.889 1.7018)
			(end 0.889 1.7018)
			(stroke
				(width 0.1524)
				(type default)
			)
			(layer "B.SilkS")
		)
		(fp_line
			(start 0.889 -1.7018)
			(end -0.889 -1.7018)
			(stroke
				(width 0.1524)
				(type default)
			)
			(layer "B.SilkS")
		)
		(fp_line
			(start 0.889 1.7018)
			(end 0.889 -1.7018)
			(stroke
				(width 0.1524)
				(type default)
			)
			(layer "B.SilkS")
		)
		(fp_rect
			(start 0.9652 1.778)
			(end -0.9652 -1.778)
			(stroke
				(width 0)
				(type default)
			)
			(fill no)
			(layer "B.CrtYd")
		)
		(fp_rect
			(start 0.9652 1.778)
			(end -0.9652 -1.778)
			(stroke
				(width 0)
				(type default)
			)
			(fill no)
			(layer "B.Fab")
		)
		(pad "1" smd rect
			(at 0 -0.9652 180)
			(size 1.397 1.143)
			(layers "B.Cu" "B.Mask" "B.Paste")
			(net "SYSPLL_VDDA18")
		)
		(pad "2" smd rect
			(at 0 0.9652 180)
			(size 1.397 1.143)
			(layers "B.Cu" "B.Mask" "B.Paste")
			(net "P1V8_E")
		)
	)
	(footprint ""
		(layer "B.Cu")
		(at 131.38277 -44.379388 180)
		(property "Reference" "C29"
			(at 0 0 0)
			(layer "B.SilkS")
			(hide yes)
			(effects
				(font
					(size 1.27 1.27)
				)
				(justify mirror)
			)
		)
		(property "Value" "SCD01U16V1KX-GP"
			(at 2.8321 -1.7399 180)
			(unlocked yes)
			(layer "B.Fab")
			(hide yes)
			(effects
				(font
					(size 1.016 1.016)
					(thickness 0.1524)
				)
				(justify mirror)
			)
		)
		(property "Device Type" "C0201H13"
			(at 2.8321 -3.2639 180)
			(unlocked yes)
			(layer "B.Fab")
			(hide yes)
			(effects
				(font
					(size 1.016 1.016)
					(thickness 0.1524)
				)
				(justify mirror)
			)
		)
		(duplicate_pad_numbers_are_jumpers no)
		(fp_rect
			(start 0.2794 0.6477)
			(end -0.2794 -0.6477)
			(stroke
				(width 0)
				(type default)
			)
			(fill no)
			(layer "B.CrtYd")
		)
		(fp_rect
			(start 0.2794 0.6477)
			(end -0.2794 -0.6477)
			(stroke
				(width 0)
				(type default)
			)
			(fill no)
			(layer "B.Fab")
		)
		(pad "1" smd custom
			(at 0 -0.2794)
			(size 0.0762 0.0762)
			(layers "B.Cu" "B.Mask" "B.Paste")
			(net "PHY_DPB_TO_SCC_29_DP")
			(options
				(clearance outline)
				(anchor circle)
			)
			(primitives
				(gr_poly
					(pts
						(arc
							(start 0.1524 0.127)
							(mid 0.137521 0.162921)
							(end 0.1016 0.1778)
						)
						(arc
							(start -0.1016 0.1778)
							(mid -0.137521 0.162921)
							(end -0.1524 0.127)
						)
						(arc
							(start -0.1524 -0.127)
							(mid -0.137521 -0.162921)
							(end -0.1016 -0.1778)
						)
						(arc
							(start 0.1016 -0.1778)
							(mid 0.137521 -0.162921)
							(end 0.1524 -0.127)
						)
					)
					(width 0)
					(fill yes)
				)
			)
		)
		(pad "2" smd custom
			(at 0 0.2794)
			(size 0.0762 0.0762)
			(layers "B.Cu" "B.Mask" "B.Paste")
			(net "PHY_DPB_TO_SCC_C_29_DP")
			(options
				(clearance outline)
				(anchor circle)
			)
			(primitives
				(gr_poly
					(pts
						(arc
							(start 0.1524 0.127)
							(mid 0.137521 0.162921)
							(end 0.1016 0.1778)
						)
						(arc
							(start -0.1016 0.1778)
							(mid -0.137521 0.162921)
							(end -0.1524 0.127)
						)
						(arc
							(start -0.1524 -0.127)
							(mid -0.137521 -0.162921)
							(end -0.1016 -0.1778)
						)
						(arc
							(start 0.1016 -0.1778)
							(mid 0.137521 -0.162921)
							(end 0.1524 -0.127)
						)
					)
					(width 0)
					(fill yes)
				)
			)
		)
	)
	(footprint ""
		(layer "B.Cu")
		(at 174.59325 -46.102016 180)
		(property "Reference" "C408"
			(at 0 0 0)
			(layer "B.SilkS")
			(hide yes)
			(effects
				(font
					(size 1.27 1.27)
				)
				(justify mirror)
			)
		)
		(property "Value" "SC10U6D3V5KX-4GP"
			(at 0.0762 -6.1214 180)
			(unlocked yes)
			(layer "B.Fab")
			(hide yes)
			(effects
				(font
					(size 1.016 1.016)
					(thickness 0.1524)
				)
				(justify mirror)
			)
		)
		(property "Device Type" "C805H58"
			(at 0.0762 -8.1534 180)
			(unlocked yes)
			(layer "B.Fab")
			(hide yes)
			(effects
				(font
					(size 1.016 1.016)
					(thickness 0.1524)
				)
				(justify mirror)
			)
		)
		(duplicate_pad_numbers_are_jumpers no)
		(fp_line
			(start -0.635 0)
			(end 0.635 0)
			(stroke
				(width 0.508)
				(type default)
			)
			(layer "B.SilkS")
		)
		(fp_rect
			(start 0.9652 1.778)
			(end -0.9652 -1.778)
			(stroke
				(width 0)
				(type default)
			)
			(fill no)
			(layer "B.CrtYd")
		)
		(fp_poly
			(pts
				(xy 0.9652 -1.778) (xy -0.9652 -1.778) (xy -0.9652 1.778) (xy 0.9652 1.778)
			)
			(stroke
				(width 0)
				(type default)
			)
			(fill no)
			(layer "B.Fab")
		)
		(pad "1" smd rect
			(at 0 -0.9652)
			(size 1.397 1.143)
			(layers "B.Cu" "B.Mask" "B.Paste")
			(net "P0V975")
		)
		(pad "2" smd rect
			(at 0 0.9652)
			(size 1.397 1.143)
			(layers "B.Cu" "B.Mask" "B.Paste")
			(net "GND")
		)
	)
	(footprint ""
		(layer "B.Cu")
		(at 183.261 -51.4604 -90)
		(property "Reference" "TP113"
			(at 0 0 90)
			(layer "B.SilkS")
			(hide yes)
			(effects
				(font
					(size 1.27 1.27)
				)
				(justify mirror)
			)
		)
		(property "Value" "TPAD28-2-GP"
			(at 0.0127 -1.6637 270)
			(unlocked yes)
			(layer "B.Fab")
			(hide yes)
			(effects
				(font
					(size 1.016 1.016)
					(thickness 0.1524)
				)
				(justify mirror)
			)
		)
		(property "Device Type" "TPAD28"
			(at 0.0127 -3.1877 270)
			(unlocked yes)
			(layer "B.Fab")
			(hide yes)
			(effects
				(font
					(size 1.016 1.016)
					(thickness 0.1524)
				)
				(justify mirror)
			)
		)
		(duplicate_pad_numbers_are_jumpers no)
		(fp_poly
			(pts
				(arc
					(start 0 -0.3556)
					(mid 0 0.3556)
					(end 0 -0.3556)
				)
			)
			(stroke
				(width 0)
				(type default)
			)
			(fill no)
			(layer "B.CrtYd")
		)
		(fp_poly
			(pts
				(arc
					(start 0 -0.6096)
					(mid 0 0.6096)
					(end 0 -0.6096)
				)
			)
			(stroke
				(width 0)
				(type default)
			)
			(fill no)
			(layer "B.Fab")
		)
		(pad "1" smd circle
			(at 0 0 90)
			(size 0.7112 0.7112)
			(layers "B.Cu" "B.Mask" "B.Paste")
			(net "XM_WP")
		)
	)
	(footprint ""
		(layer "B.Cu")
		(at 189.032388 -30.613858 90)
		(property "Reference" "TP69"
			(at 0 0 90)
			(layer "B.SilkS")
			(hide yes)
			(effects
				(font
					(size 1.27 1.27)
				)
				(justify mirror)
			)
		)
		(property "Value" "TPAD28-2-GP"
			(at 0.0127 -1.6637 90)
			(unlocked yes)
			(layer "B.Fab")
			(hide yes)
			(effects
				(font
					(size 1.016 1.016)
					(thickness 0.1524)
				)
				(justify mirror)
			)
		)
		(property "Device Type" "TPAD28"
			(at 0.0127 -3.1877 90)
			(unlocked yes)
			(layer "B.Fab")
			(hide yes)
			(effects
				(font
					(size 1.016 1.016)
					(thickness 0.1524)
				)
				(justify mirror)
			)
		)
		(duplicate_pad_numbers_are_jumpers no)
		(fp_poly
			(pts
				(arc
					(start 0 0.3556)
					(mid 0 -0.3556)
					(end 0 0.3556)
				)
			)
			(stroke
				(width 0)
				(type default)
			)
			(fill no)
			(layer "B.CrtYd")
		)
		(fp_poly
			(pts
				(arc
					(start 0 0.6096)
					(mid 0 -0.6096)
					(end 0 0.6096)
				)
			)
			(stroke
				(width 0)
				(type default)
			)
			(fill no)
			(layer "B.Fab")
		)
		(pad "1" smd circle
			(at 0 0 270)
			(size 0.7112 0.7112)
			(layers "B.Cu" "B.Mask" "B.Paste")
			(net "IOC_GPIO_16")
		)
	)
	(footprint ""
		(layer "B.Cu")
		(at 169.905172 -36.02355 90)
		(property "Reference" "C403"
			(at 0 0 90)
			(layer "B.SilkS")
			(hide yes)
			(effects
				(font
					(size 1.27 1.27)
				)
				(justify mirror)
			)
		)
		(property "Value" "SCD1U16V2KX-3GP"
			(at -1.1811 -2.7051 90)
			(unlocked yes)
			(layer "B.Fab")
			(hide yes)
			(effects
				(font
					(size 1.016 1.016)
					(thickness 0.1524)
				)
				(justify mirror)
			)
		)
		(property "Device Type" "C402H22"
			(at -1.1811 -4.2291 90)
			(unlocked yes)
			(layer "B.Fab")
			(hide yes)
			(effects
				(font
					(size 1.016 1.016)
					(thickness 0.1524)
				)
				(justify mirror)
			)
		)
		(duplicate_pad_numbers_are_jumpers no)
		(fp_rect
			(start 0.4318 0.9525)
			(end -0.4318 -0.9525)
			(stroke
				(width 0)
				(type default)
			)
			(fill no)
			(layer "B.CrtYd")
		)
		(fp_rect
			(start 0.4318 0.9525)
			(end -0.4318 -0.9525)
			(stroke
				(width 0)
				(type default)
			)
			(fill no)
			(layer "B.Fab")
		)
		(pad "1" smd custom
			(at 0 -0.4445 270)
			(size 0.1524 0.1524)
			(layers "B.Cu" "B.Mask" "B.Paste")
			(net "SAS0_AVDD")
			(options
				(clearance outline)
				(anchor circle)
			)
			(primitives
				(gr_poly
					(pts
						(arc
							(start 0.3048 0.2032)
							(mid 0.275042 0.275042)
							(end 0.2032 0.3048)
						)
						(arc
							(start -0.2032 0.3048)
							(mid -0.275042 0.275042)
							(end -0.3048 0.2032)
						)
						(arc
							(start -0.3048 -0.2032)
							(mid -0.275042 -0.275042)
							(end -0.2032 -0.3048)
						)
						(arc
							(start 0.2032 -0.3048)
							(mid 0.275042 -0.275042)
							(end 0.3048 -0.2032)
						)
					)
					(width 0)
					(fill yes)
				)
			)
		)
		(pad "2" smd custom
			(at 0 0.4445 270)
			(size 0.1524 0.1524)
			(layers "B.Cu" "B.Mask" "B.Paste")
			(net "GND")
			(options
				(clearance outline)
				(anchor circle)
			)
			(primitives
				(gr_poly
					(pts
						(arc
							(start 0.3048 0.2032)
							(mid 0.275042 0.275042)
							(end 0.2032 0.3048)
						)
						(arc
							(start -0.2032 0.3048)
							(mid -0.275042 0.275042)
							(end -0.3048 0.2032)
						)
						(arc
							(start -0.3048 -0.2032)
							(mid -0.275042 -0.275042)
							(end -0.2032 -0.3048)
						)
						(arc
							(start 0.2032 -0.3048)
							(mid 0.275042 -0.275042)
							(end 0.3048 -0.2032)
						)
					)
					(width 0)
					(fill yes)
				)
			)
		)
	)
	(footprint ""
		(layer "B.Cu")
		(at 193.3956 -24.31542 -90)
		(property "Reference" "Q3"
			(at 0 0 90)
			(layer "B.SilkS")
			(hide yes)
			(effects
				(font
					(size 1.27 1.27)
				)
				(justify mirror)
			)
		)
		(property "Value" "SSM3K324R-GP"
			(at -0.127 -8.9662 270)
			(unlocked yes)
			(layer "B.Fab")
			(hide yes)
			(effects
				(font
					(size 1.016 1.016)
					(thickness 0.1524)
				)
				(justify mirror)
			)
		)
		(property "Device Type" "SOT23DGS2D4H35"
			(at -0.127 -10.4902 270)
			(unlocked yes)
			(layer "B.Fab")
			(hide yes)
			(effects
				(font
					(size 1.016 1.016)
					(thickness 0.1524)
				)
				(justify mirror)
			)
		)
		(duplicate_pad_numbers_are_jumpers no)
		(fp_line
			(start -1.651 1.778)
			(end -1.651 -1.778)
			(stroke
				(width 0.1524)
				(type default)
			)
			(layer "B.SilkS")
		)
		(fp_line
			(start 1.651 1.778)
			(end -1.651 1.778)
			(stroke
				(width 0.1524)
				(type default)
			)
			(layer "B.SilkS")
		)
		(fp_line
			(start -1.651 -1.778)
			(end 1.651 -1.778)
			(stroke
				(width 0.1524)
				(type default)
			)
			(layer "B.SilkS")
		)
		(fp_line
			(start 1.651 -1.778)
			(end 1.651 1.778)
			(stroke
				(width 0.1524)
				(type default)
			)
			(layer "B.SilkS")
		)
		(fp_poly
			(pts
				(xy 1.778 1.8796) (xy 1.778 -1.8796) (xy -1.778 -1.8796) (xy -1.778 1.8796)
			)
			(stroke
				(width 0)
				(type default)
			)
			(fill no)
			(layer "B.CrtYd")
		)
		(fp_poly
			(pts
				(xy 1.778 1.8796) (xy 1.778 -1.8796) (xy -1.778 -1.8796) (xy -1.778 1.8796)
			)
			(stroke
				(width 0)
				(type default)
			)
			(fill no)
			(layer "B.Fab")
		)
		(pad "D" smd custom
			(at 0 -0.9525 90)
			(size 0.1905 0.1905)
			(layers "B.Cu" "B.Mask" "B.Paste")
			(net "SYS_HB_LED_D")
			(options
				(clearance outline)
				(anchor circle)
			)
			(primitives
				(gr_poly
					(pts
						(arc
							(start -0.1778 -0.5715)
							(mid -0.321484 -0.511984)
							(end -0.381 -0.3683)
						)
						(arc
							(start -0.381 0.3683)
							(mid -0.321484 0.511984)
							(end -0.1778 0.5715)
						)
						(arc
							(start 0.1778 0.5715)
							(mid 0.321484 0.511984)
							(end 0.381 0.3683)
						)
						(arc
							(start 0.381 -0.3683)
							(mid 0.321484 -0.511984)
							(end 0.1778 -0.5715)
						)
					)
					(width 0)
					(fill yes)
				)
			)
		)
		(pad "G" smd custom
			(at 0.98425 0.9525 90)
			(size 0.1905 0.1905)
			(layers "B.Cu" "B.Mask" "B.Paste")
			(net "SYS_HB_LED")
			(options
				(clearance outline)
				(anchor circle)
			)
			(primitives
				(gr_poly
					(pts
						(arc
							(start -0.1778 -0.5715)
							(mid -0.321484 -0.511984)
							(end -0.381 -0.3683)
						)
						(arc
							(start -0.381 0.3683)
							(mid -0.321484 0.511984)
							(end -0.1778 0.5715)
						)
						(arc
							(start 0.1778 0.5715)
							(mid 0.321484 0.511984)
							(end 0.381 0.3683)
						)
						(arc
							(start 0.381 -0.3683)
							(mid 0.321484 -0.511984)
							(end 0.1778 -0.5715)
						)
					)
					(width 0)
					(fill yes)
				)
			)
		)
		(pad "S" smd custom
			(at -0.98425 0.9525 90)
			(size 0.1905 0.1905)
			(layers "B.Cu" "B.Mask" "B.Paste")
			(net "GND")
			(options
				(clearance outline)
				(anchor circle)
			)
			(primitives
				(gr_poly
					(pts
						(arc
							(start -0.1778 -0.5715)
							(mid -0.321484 -0.511984)
							(end -0.381 -0.3683)
						)
						(arc
							(start -0.381 0.3683)
							(mid -0.321484 0.511984)
							(end -0.1778 0.5715)
						)
						(arc
							(start 0.1778 0.5715)
							(mid 0.321484 0.511984)
							(end 0.381 0.3683)
						)
						(arc
							(start 0.381 -0.3683)
							(mid 0.321484 -0.511984)
							(end 0.1778 -0.5715)
						)
					)
					(width 0)
					(fill yes)
				)
			)
		)
	)
	(footprint ""
		(layer "B.Cu")
		(at 181.995318 -47.630842)
		(property "Reference" "C500"
			(at 0 0 0)
			(layer "B.SilkS")
			(hide yes)
			(effects
				(font
					(size 1.27 1.27)
				)
				(justify mirror)
			)
		)
		(property "Value" "SC1KP50V2KX-1GP"
			(at -1.1811 -2.7051 0)
			(unlocked yes)
			(layer "B.Fab")
			(hide yes)
			(effects
				(font
					(size 1.016 1.016)
					(thickness 0.1524)
				)
				(justify mirror)
			)
		)
		(property "Device Type" "C402H22"
			(at -1.1811 -4.2291 0)
			(unlocked yes)
			(layer "B.Fab")
			(hide yes)
			(effects
				(font
					(size 1.016 1.016)
					(thickness 0.1524)
				)
				(justify mirror)
			)
		)
		(duplicate_pad_numbers_are_jumpers no)
		(fp_rect
			(start 0.4318 0.9525)
			(end -0.4318 -0.9525)
			(stroke
				(width 0)
				(type default)
			)
			(fill no)
			(layer "B.CrtYd")
		)
		(fp_rect
			(start 0.4318 0.9525)
			(end -0.4318 -0.9525)
			(stroke
				(width 0)
				(type default)
			)
			(fill no)
			(layer "B.Fab")
		)
		(pad "1" smd custom
			(at 0 -0.4445 180)
			(size 0.1524 0.1524)
			(layers "B.Cu" "B.Mask" "B.Paste")
			(net "P1V8_C")
			(options
				(clearance outline)
				(anchor circle)
			)
			(primitives
				(gr_poly
					(pts
						(arc
							(start 0.3048 0.2032)
							(mid 0.275042 0.275042)
							(end 0.2032 0.3048)
						)
						(arc
							(start -0.2032 0.3048)
							(mid -0.275042 0.275042)
							(end -0.3048 0.2032)
						)
						(arc
							(start -0.3048 -0.2032)
							(mid -0.275042 -0.275042)
							(end -0.2032 -0.3048)
						)
						(arc
							(start 0.2032 -0.3048)
							(mid 0.275042 -0.275042)
							(end 0.3048 -0.2032)
						)
					)
					(width 0)
					(fill yes)
				)
			)
		)
		(pad "2" smd custom
			(at 0 0.4445 180)
			(size 0.1524 0.1524)
			(layers "B.Cu" "B.Mask" "B.Paste")
			(net "GND")
			(options
				(clearance outline)
				(anchor circle)
			)
			(primitives
				(gr_poly
					(pts
						(arc
							(start 0.3048 0.2032)
							(mid 0.275042 0.275042)
							(end 0.2032 0.3048)
						)
						(arc
							(start -0.2032 0.3048)
							(mid -0.275042 0.275042)
							(end -0.3048 0.2032)
						)
						(arc
							(start -0.3048 -0.2032)
							(mid -0.275042 -0.275042)
							(end -0.2032 -0.3048)
						)
						(arc
							(start 0.2032 -0.3048)
							(mid 0.275042 -0.275042)
							(end 0.3048 -0.2032)
						)
					)
					(width 0)
					(fill yes)
				)
			)
		)
	)
	(footprint ""
		(layer "B.Cu")
		(at 129.397252 -59.371992 90)
		(property "Reference" "C264"
			(at 0 0 90)
			(layer "B.SilkS")
			(hide yes)
			(effects
				(font
					(size 1.27 1.27)
				)
				(justify mirror)
			)
		)
		(property "Value" "SC1U6D3V1MX-GP"
			(at -1.9177 2.0193 90)
			(unlocked yes)
			(layer "B.Fab")
			(hide yes)
			(effects
				(font
					(size 1.016 1.016)
					(thickness 0.1524)
				)
				(justify mirror)
			)
		)
		(property "Device Type" "C0201H14"
			(at -1.9177 0.4953 90)
			(unlocked yes)
			(layer "B.Fab")
			(hide yes)
			(effects
				(font
					(size 1.016 1.016)
					(thickness 0.1524)
				)
				(justify mirror)
			)
		)
		(duplicate_pad_numbers_are_jumpers no)
		(fp_rect
			(start 0.1524 0.3048)
			(end -0.1524 -0.3048)
			(stroke
				(width 0)
				(type default)
			)
			(fill no)
			(layer "B.CrtYd")
		)
		(fp_poly
			(pts
				(xy 0.2794 0.6477) (xy 0.2794 -0.6477) (xy -0.2794 -0.6477) (xy -0.2794 -0.1905) (xy -0.1524 -0.1905)
				(xy -0.1524 -0.3048) (xy 0.1524 -0.3048) (xy 0.1524 0.3048) (xy -0.1524 0.3048) (xy -0.1524 -0.1778)
				(xy -0.2794 -0.1778) (xy -0.2794 0.6477)
			)
			(stroke
				(width 0)
				(type default)
			)
			(fill no)
			(layer "B.CrtYd")
		)
		(fp_rect
			(start 0.2794 0.6477)
			(end -0.2794 -0.6477)
			(stroke
				(width 0)
				(type default)
			)
			(fill no)
			(layer "B.Fab")
		)
		(pad "1" smd custom
			(at 0 -0.2794 270)
			(size 0.0762 0.0762)
			(layers "B.Cu" "B.Mask" "B.Paste")
			(net "GB_VDDA")
			(options
				(clearance outline)
				(anchor circle)
			)
			(primitives
				(gr_poly
					(pts
						(arc
							(start 0.1524 0.127)
							(mid 0.137521 0.162921)
							(end 0.1016 0.1778)
						)
						(arc
							(start -0.1016 0.1778)
							(mid -0.137521 0.162921)
							(end -0.1524 0.127)
						)
						(arc
							(start -0.1524 -0.127)
							(mid -0.137521 -0.162921)
							(end -0.1016 -0.1778)
						)
						(arc
							(start 0.1016 -0.1778)
							(mid 0.137521 -0.162921)
							(end 0.1524 -0.127)
						)
					)
					(width 0)
					(fill yes)
				)
			)
		)
		(pad "2" smd custom
			(at 0 0.2794 270)
			(size 0.0762 0.0762)
			(layers "B.Cu" "B.Mask" "B.Paste")
			(net "GND")
			(options
				(clearance outline)
				(anchor circle)
			)
			(primitives
				(gr_poly
					(pts
						(arc
							(start 0.1524 0.127)
							(mid 0.137521 0.162921)
							(end 0.1016 0.1778)
						)
						(arc
							(start -0.1016 0.1778)
							(mid -0.137521 0.162921)
							(end -0.1524 0.127)
						)
						(arc
							(start -0.1524 -0.127)
							(mid -0.137521 -0.162921)
							(end -0.1016 -0.1778)
						)
						(arc
							(start 0.1016 -0.1778)
							(mid 0.137521 -0.162921)
							(end 0.1524 -0.127)
						)
					)
					(width 0)
					(fill yes)
				)
			)
		)
	)
	(footprint ""
		(layer "B.Cu")
		(at 165.537388 -50.441352)
		(property "Reference" "TP118"
			(at 0 0 0)
			(layer "B.SilkS")
			(hide yes)
			(effects
				(font
					(size 1.27 1.27)
				)
				(justify mirror)
			)
		)
		(property "Value" "TPAD28-2-GP"
			(at 0.0127 -1.6637 0)
			(unlocked yes)
			(layer "B.Fab")
			(hide yes)
			(effects
				(font
					(size 1.016 1.016)
					(thickness 0.1524)
				)
				(justify mirror)
			)
		)
		(property "Device Type" "TPAD28"
			(at 0.0127 -3.1877 0)
			(unlocked yes)
			(layer "B.Fab")
			(hide yes)
			(effects
				(font
					(size 1.016 1.016)
					(thickness 0.1524)
				)
				(justify mirror)
			)
		)
		(duplicate_pad_numbers_are_jumpers no)
		(fp_poly
			(pts
				(arc
					(start 0.3556 0)
					(mid -0.3556 0)
					(end 0.3556 0)
				)
			)
			(stroke
				(width 0)
				(type default)
			)
			(fill no)
			(layer "B.CrtYd")
		)
		(fp_poly
			(pts
				(arc
					(start 0.6096 0)
					(mid -0.6096 0)
					(end 0.6096 0)
				)
			)
			(stroke
				(width 0)
				(type default)
			)
			(fill no)
			(layer "B.Fab")
		)
		(pad "1" smd circle
			(at 0 0 180)
			(size 0.7112 0.7112)
			(layers "B.Cu" "B.Mask" "B.Paste")
			(net "ICE_SEL")
		)
	)
	(footprint ""
		(layer "B.Cu")
		(at 123.522232 -80.554068 180)
		(property "Reference" "C147"
			(at 0 0 0)
			(layer "B.SilkS")
			(hide yes)
			(effects
				(font
					(size 1.27 1.27)
				)
				(justify mirror)
			)
		)
		(property "Value" "SCD1U6D3V1KX-GP"
			(at 2.8321 -1.7399 180)
			(unlocked yes)
			(layer "B.Fab")
			(hide yes)
			(effects
				(font
					(size 1.016 1.016)
					(thickness 0.1524)
				)
				(justify mirror)
			)
		)
		(property "Device Type" "C0201H13"
			(at 2.8321 -3.2639 180)
			(unlocked yes)
			(layer "B.Fab")
			(hide yes)
			(effects
				(font
					(size 1.016 1.016)
					(thickness 0.1524)
				)
				(justify mirror)
			)
		)
		(duplicate_pad_numbers_are_jumpers no)
		(fp_rect
			(start 0.2794 0.6477)
			(end -0.2794 -0.6477)
			(stroke
				(width 0)
				(type default)
			)
			(fill no)
			(layer "B.CrtYd")
		)
		(fp_rect
			(start 0.2794 0.6477)
			(end -0.2794 -0.6477)
			(stroke
				(width 0)
				(type default)
			)
			(fill no)
			(layer "B.Fab")
		)
		(pad "1" smd custom
			(at 0 -0.2794)
			(size 0.0762 0.0762)
			(layers "B.Cu" "B.Mask" "B.Paste")
			(net "P1V8_E")
			(options
				(clearance outline)
				(anchor circle)
			)
			(primitives
				(gr_poly
					(pts
						(arc
							(start 0.1524 0.127)
							(mid 0.137521 0.162921)
							(end 0.1016 0.1778)
						)
						(arc
							(start -0.1016 0.1778)
							(mid -0.137521 0.162921)
							(end -0.1524 0.127)
						)
						(arc
							(start -0.1524 -0.127)
							(mid -0.137521 -0.162921)
							(end -0.1016 -0.1778)
						)
						(arc
							(start 0.1016 -0.1778)
							(mid 0.137521 -0.162921)
							(end 0.1524 -0.127)
						)
					)
					(width 0)
					(fill yes)
				)
			)
		)
		(pad "2" smd custom
			(at 0 0.2794)
			(size 0.0762 0.0762)
			(layers "B.Cu" "B.Mask" "B.Paste")
			(net "GND")
			(options
				(clearance outline)
				(anchor circle)
			)
			(primitives
				(gr_poly
					(pts
						(arc
							(start 0.1524 0.127)
							(mid 0.137521 0.162921)
							(end 0.1016 0.1778)
						)
						(arc
							(start -0.1016 0.1778)
							(mid -0.137521 0.162921)
							(end -0.1524 0.127)
						)
						(arc
							(start -0.1524 -0.127)
							(mid -0.137521 -0.162921)
							(end -0.1016 -0.1778)
						)
						(arc
							(start 0.1016 -0.1778)
							(mid 0.137521 -0.162921)
							(end 0.1524 -0.127)
						)
					)
					(width 0)
					(fill yes)
				)
			)
		)
	)
	(footprint ""
		(layer "B.Cu")
		(at 197.231 -28.321 180)
		(property "Reference" "C377"
			(at 0 0 0)
			(layer "B.SilkS")
			(hide yes)
			(effects
				(font
					(size 1.27 1.27)
				)
				(justify mirror)
			)
		)
		(property "Value" "SC22U6D3V3MX-9-GP-U"
			(at 0 -2.8194 180)
			(unlocked yes)
			(layer "B.Fab")
			(hide yes)
			(effects
				(font
					(size 1.016 1.016)
					(thickness 0.1524)
				)
				(justify mirror)
			)
		)
		(property "Device Type" "C603H40"
			(at 0 -4.3434 180)
			(unlocked yes)
			(layer "B.Fab")
			(hide yes)
			(effects
				(font
					(size 1.016 1.016)
					(thickness 0.1524)
				)
				(justify mirror)
			)
		)
		(duplicate_pad_numbers_are_jumpers no)
		(fp_line
			(start -0.508 0)
			(end 0.508 0)
			(stroke
				(width 0.2032)
				(type default)
			)
			(layer "B.SilkS")
		)
		(fp_rect
			(start 0.5842 1.3335)
			(end -0.5842 -1.3335)
			(stroke
				(width 0)
				(type default)
			)
			(fill no)
			(layer "B.CrtYd")
		)
		(fp_rect
			(start 0.5842 1.3335)
			(end -0.5842 -1.3335)
			(stroke
				(width 0)
				(type default)
			)
			(fill no)
			(layer "B.Fab")
		)
		(pad "1" smd custom
			(at 0 -0.762)
			(size 0.2159 0.2159)
			(layers "B.Cu" "B.Mask" "B.Paste")
			(net "PCE_VDDH")
			(options
				(clearance outline)
				(anchor circle)
			)
			(primitives
				(gr_poly
					(pts
						(arc
							(start -0.3302 0.4318)
							(mid -0.402042 0.402042)
							(end -0.4318 0.3302)
						)
						(arc
							(start -0.4318 -0.3302)
							(mid -0.402042 -0.402042)
							(end -0.3302 -0.4318)
						)
						(arc
							(start 0.3302 -0.4318)
							(mid 0.402042 -0.402042)
							(end 0.4318 -0.3302)
						)
						(arc
							(start 0.4318 0.3302)
							(mid 0.402042 0.402042)
							(end 0.3302 0.4318)
						)
					)
					(width 0)
					(fill yes)
				)
			)
		)
		(pad "2" smd custom
			(at 0 0.762)
			(size 0.2159 0.2159)
			(layers "B.Cu" "B.Mask" "B.Paste")
			(net "GND")
			(options
				(clearance outline)
				(anchor circle)
			)
			(primitives
				(gr_poly
					(pts
						(arc
							(start -0.3302 0.4318)
							(mid -0.402042 0.402042)
							(end -0.4318 0.3302)
						)
						(arc
							(start -0.4318 -0.3302)
							(mid -0.402042 -0.402042)
							(end -0.3302 -0.4318)
						)
						(arc
							(start 0.3302 -0.4318)
							(mid 0.402042 -0.402042)
							(end 0.4318 -0.3302)
						)
						(arc
							(start 0.4318 0.3302)
							(mid 0.402042 0.402042)
							(end 0.3302 0.4318)
						)
					)
					(width 0)
					(fill yes)
				)
			)
		)
	)
	(footprint ""
		(layer "B.Cu")
		(at 174.244 -32.6898 90)
		(property "Reference" "C382"
			(at 0 0 90)
			(layer "B.SilkS")
			(hide yes)
			(effects
				(font
					(size 1.27 1.27)
				)
				(justify mirror)
			)
		)
		(property "Value" "SCD1U16V2KX-3GP"
			(at -1.1811 -2.7051 90)
			(unlocked yes)
			(layer "B.Fab")
			(hide yes)
			(effects
				(font
					(size 1.016 1.016)
					(thickness 0.1524)
				)
				(justify mirror)
			)
		)
		(property "Device Type" "C402H22"
			(at -1.1811 -4.2291 90)
			(unlocked yes)
			(layer "B.Fab")
			(hide yes)
			(effects
				(font
					(size 1.016 1.016)
					(thickness 0.1524)
				)
				(justify mirror)
			)
		)
		(duplicate_pad_numbers_are_jumpers no)
		(fp_rect
			(start 0.4318 0.9525)
			(end -0.4318 -0.9525)
			(stroke
				(width 0)
				(type default)
			)
			(fill no)
			(layer "B.CrtYd")
		)
		(fp_rect
			(start 0.4318 0.9525)
			(end -0.4318 -0.9525)
			(stroke
				(width 0)
				(type default)
			)
			(fill no)
			(layer "B.Fab")
		)
		(pad "1" smd custom
			(at 0 -0.4445 270)
			(size 0.1524 0.1524)
			(layers "B.Cu" "B.Mask" "B.Paste")
			(net "PCE_VDDH")
			(options
				(clearance outline)
				(anchor circle)
			)
			(primitives
				(gr_poly
					(pts
						(arc
							(start 0.3048 0.2032)
							(mid 0.275042 0.275042)
							(end 0.2032 0.3048)
						)
						(arc
							(start -0.2032 0.3048)
							(mid -0.275042 0.275042)
							(end -0.3048 0.2032)
						)
						(arc
							(start -0.3048 -0.2032)
							(mid -0.275042 -0.275042)
							(end -0.2032 -0.3048)
						)
						(arc
							(start 0.2032 -0.3048)
							(mid 0.275042 -0.275042)
							(end 0.3048 -0.2032)
						)
					)
					(width 0)
					(fill yes)
				)
			)
		)
		(pad "2" smd custom
			(at 0 0.4445 270)
			(size 0.1524 0.1524)
			(layers "B.Cu" "B.Mask" "B.Paste")
			(net "GND")
			(options
				(clearance outline)
				(anchor circle)
			)
			(primitives
				(gr_poly
					(pts
						(arc
							(start 0.3048 0.2032)
							(mid 0.275042 0.275042)
							(end 0.2032 0.3048)
						)
						(arc
							(start -0.2032 0.3048)
							(mid -0.275042 0.275042)
							(end -0.3048 0.2032)
						)
						(arc
							(start -0.3048 -0.2032)
							(mid -0.275042 -0.275042)
							(end -0.2032 -0.3048)
						)
						(arc
							(start 0.2032 -0.3048)
							(mid 0.275042 -0.275042)
							(end 0.3048 -0.2032)
						)
					)
					(width 0)
					(fill yes)
				)
			)
		)
	)
	(footprint ""
		(layer "B.Cu")
		(at 76.327 -51.308 180)
		(property "Reference" "C242"
			(at 0 0 0)
			(layer "B.SilkS")
			(hide yes)
			(effects
				(font
					(size 1.27 1.27)
				)
				(justify mirror)
			)
		)
		(property "Value" "SC22U6D3V3MX-9-GP-U"
			(at 0 -2.8194 180)
			(unlocked yes)
			(layer "B.Fab")
			(hide yes)
			(effects
				(font
					(size 1.016 1.016)
					(thickness 0.1524)
				)
				(justify mirror)
			)
		)
		(property "Device Type" "C603H40"
			(at 0 -4.3434 180)
			(unlocked yes)
			(layer "B.Fab")
			(hide yes)
			(effects
				(font
					(size 1.016 1.016)
					(thickness 0.1524)
				)
				(justify mirror)
			)
		)
		(duplicate_pad_numbers_are_jumpers no)
		(fp_line
			(start -0.508 0)
			(end 0.508 0)
			(stroke
				(width 0.2032)
				(type default)
			)
			(layer "B.SilkS")
		)
		(fp_rect
			(start 0.5842 1.3335)
			(end -0.5842 -1.3335)
			(stroke
				(width 0)
				(type default)
			)
			(fill no)
			(layer "B.CrtYd")
		)
		(fp_rect
			(start 0.5842 1.3335)
			(end -0.5842 -1.3335)
			(stroke
				(width 0)
				(type default)
			)
			(fill no)
			(layer "B.Fab")
		)
		(pad "1" smd custom
			(at 0 -0.762)
			(size 0.2159 0.2159)
			(layers "B.Cu" "B.Mask" "B.Paste")
			(net "GB_VDDA")
			(options
				(clearance outline)
				(anchor circle)
			)
			(primitives
				(gr_poly
					(pts
						(arc
							(start -0.3302 0.4318)
							(mid -0.402042 0.402042)
							(end -0.4318 0.3302)
						)
						(arc
							(start -0.4318 -0.3302)
							(mid -0.402042 -0.402042)
							(end -0.3302 -0.4318)
						)
						(arc
							(start 0.3302 -0.4318)
							(mid 0.402042 -0.402042)
							(end 0.4318 -0.3302)
						)
						(arc
							(start 0.4318 0.3302)
							(mid 0.402042 0.402042)
							(end 0.3302 0.4318)
						)
					)
					(width 0)
					(fill yes)
				)
			)
		)
		(pad "2" smd custom
			(at 0 0.762)
			(size 0.2159 0.2159)
			(layers "B.Cu" "B.Mask" "B.Paste")
			(net "GND")
			(options
				(clearance outline)
				(anchor circle)
			)
			(primitives
				(gr_poly
					(pts
						(arc
							(start -0.3302 0.4318)
							(mid -0.402042 0.402042)
							(end -0.4318 0.3302)
						)
						(arc
							(start -0.4318 -0.3302)
							(mid -0.402042 -0.402042)
							(end -0.3302 -0.4318)
						)
						(arc
							(start 0.3302 -0.4318)
							(mid 0.402042 -0.402042)
							(end 0.4318 -0.3302)
						)
						(arc
							(start 0.4318 0.3302)
							(mid 0.402042 0.402042)
							(end 0.3302 0.4318)
						)
					)
					(width 0)
					(fill yes)
				)
			)
		)
	)
	(footprint ""
		(layer "B.Cu")
		(at 172.399706 -63.597536 180)
		(property "Reference" "U16"
			(at 0 0 0)
			(layer "B.SilkS")
			(hide yes)
			(effects
				(font
					(size 1.27 1.27)
				)
				(justify mirror)
			)
		)
		(property "Value" "TPS3808G01DBVT-GP"
			(at 0.0254 -11.9634 180)
			(unlocked yes)
			(layer "B.Fab")
			(hide yes)
			(effects
				(font
					(size 1.016 1.016)
					(thickness 0.1524)
				)
				(justify mirror)
			)
		)
		(property "Device Type" "SOT-6H58"
			(at 0.0254 -13.5636 180)
			(unlocked yes)
			(layer "B.Fab")
			(hide yes)
			(effects
				(font
					(size 1.016 1.016)
					(thickness 0.1524)
				)
				(justify mirror)
			)
		)
		(duplicate_pad_numbers_are_jumpers no)
		(fp_line
			(start 1.9685 0.5842)
			(end 1.9685 2.3622)
			(stroke
				(width 0.508)
				(type default)
			)
			(layer "B.SilkS")
		)
		(fp_line
			(start 1.9685 0.5842)
			(end -1.7145 0.5842)
			(stroke
				(width 0.1524)
				(type default)
			)
			(layer "B.SilkS")
		)
		(fp_line
			(start 1.9685 -0.4064)
			(end 1.5621 0)
			(stroke
				(width 0.1524)
				(type default)
			)
			(layer "B.SilkS")
		)
		(fp_line
			(start 1.9685 -0.5842)
			(end 1.9685 0.5842)
			(stroke
				(width 0.1524)
				(type default)
			)
			(layer "B.SilkS")
		)
		(fp_line
			(start 1.5621 0)
			(end 1.9685 0.4064)
			(stroke
				(width 0.1524)
				(type default)
			)
			(layer "B.SilkS")
		)
		(fp_line
			(start -1.7145 0.5842)
			(end -1.7145 -0.5842)
			(stroke
				(width 0.1524)
				(type default)
			)
			(layer "B.SilkS")
		)
		(fp_line
			(start -1.7145 -0.5842)
			(end 1.9685 -0.5842)
			(stroke
				(width 0.1524)
				(type default)
			)
			(layer "B.SilkS")
		)
		(fp_poly
			(pts
				(xy 1.27 -0.635) (xy -1.27 -0.635) (xy -1.27 0.635) (xy 1.27 0.635)
			)
			(stroke
				(width 0)
				(type default)
			)
			(fill yes)
			(layer "B.SilkS")
		)
		(fp_rect
			(start 1.9685 2.3622)
			(end -1.9685 -2.3622)
			(stroke
				(width 0)
				(type default)
			)
			(fill no)
			(layer "B.CrtYd")
		)
		(fp_poly
			(pts
				(xy 1.9685 -2.3622) (xy -1.9685 -2.3622) (xy -1.9685 2.3622) (xy 1.9685 2.3622)
			)
			(stroke
				(width 0)
				(type default)
			)
			(fill no)
			(layer "B.Fab")
		)
		(pad "1" smd rect
			(at 0.9525 1.3462)
			(size 0.5842 1.016)
			(layers "B.Cu" "B.Mask" "B.Paste")
			(net "IOC_RESET_N")
		)
		(pad "2" smd rect
			(at 0 1.3462)
			(size 0.5842 1.016)
			(layers "B.Cu" "B.Mask" "B.Paste")
			(net "GND")
		)
		(pad "3" smd rect
			(at -0.9525 1.3462)
			(size 0.5842 1.016)
			(layers "B.Cu" "B.Mask" "B.Paste")
			(net "IOC_VREF_SET_LS")
		)
		(pad "4" smd rect
			(at -0.9525 -1.3462)
			(size 0.5842 1.016)
			(layers "B.Cu" "B.Mask" "B.Paste")
			(net "Net_619")
		)
		(pad "5" smd rect
			(at 0 -1.3462)
			(size 0.5842 1.016)
			(layers "B.Cu" "B.Mask" "B.Paste")
			(net "SCC_FULL_PGOOD_SENSE")
		)
		(pad "6" smd rect
			(at 0.9525 -1.3462)
			(size 0.5842 1.016)
			(layers "B.Cu" "B.Mask" "B.Paste")
			(net "P3V3")
		)
	)
	(footprint ""
		(layer "B.Cu")
		(at 120.777 -61.488066)
		(property "Reference" "C219"
			(at 0 0 0)
			(layer "B.SilkS")
			(hide yes)
			(effects
				(font
					(size 1.27 1.27)
				)
				(justify mirror)
			)
		)
		(property "Value" "SCD1U16V2KX-3GP"
			(at -1.1811 -2.7051 0)
			(unlocked yes)
			(layer "B.Fab")
			(hide yes)
			(effects
				(font
					(size 1.016 1.016)
					(thickness 0.1524)
				)
				(justify mirror)
			)
		)
		(property "Device Type" "C402H22"
			(at -1.1811 -4.2291 0)
			(unlocked yes)
			(layer "B.Fab")
			(hide yes)
			(effects
				(font
					(size 1.016 1.016)
					(thickness 0.1524)
				)
				(justify mirror)
			)
		)
		(duplicate_pad_numbers_are_jumpers no)
		(fp_rect
			(start 0.4318 0.9525)
			(end -0.4318 -0.9525)
			(stroke
				(width 0)
				(type default)
			)
			(fill no)
			(layer "B.CrtYd")
		)
		(fp_rect
			(start 0.4318 0.9525)
			(end -0.4318 -0.9525)
			(stroke
				(width 0)
				(type default)
			)
			(fill no)
			(layer "B.Fab")
		)
		(pad "1" smd custom
			(at 0 -0.4445 180)
			(size 0.1524 0.1524)
			(layers "B.Cu" "B.Mask" "B.Paste")
			(net "GB_VDDH")
			(options
				(clearance outline)
				(anchor circle)
			)
			(primitives
				(gr_poly
					(pts
						(arc
							(start 0.3048 0.2032)
							(mid 0.275042 0.275042)
							(end 0.2032 0.3048)
						)
						(arc
							(start -0.2032 0.3048)
							(mid -0.275042 0.275042)
							(end -0.3048 0.2032)
						)
						(arc
							(start -0.3048 -0.2032)
							(mid -0.275042 -0.275042)
							(end -0.2032 -0.3048)
						)
						(arc
							(start 0.2032 -0.3048)
							(mid 0.275042 -0.275042)
							(end 0.3048 -0.2032)
						)
					)
					(width 0)
					(fill yes)
				)
			)
		)
		(pad "2" smd custom
			(at 0 0.4445 180)
			(size 0.1524 0.1524)
			(layers "B.Cu" "B.Mask" "B.Paste")
			(net "GND")
			(options
				(clearance outline)
				(anchor circle)
			)
			(primitives
				(gr_poly
					(pts
						(arc
							(start 0.3048 0.2032)
							(mid 0.275042 0.275042)
							(end 0.2032 0.3048)
						)
						(arc
							(start -0.2032 0.3048)
							(mid -0.275042 0.275042)
							(end -0.3048 0.2032)
						)
						(arc
							(start -0.3048 -0.2032)
							(mid -0.275042 -0.275042)
							(end -0.2032 -0.3048)
						)
						(arc
							(start 0.2032 -0.3048)
							(mid 0.275042 -0.275042)
							(end 0.3048 -0.2032)
						)
					)
					(width 0)
					(fill yes)
				)
			)
		)
	)
	(footprint ""
		(layer "B.Cu")
		(at 115.7986 -86.995)
		(property "Reference" "R393"
			(at 0 0 0)
			(layer "B.SilkS")
			(hide yes)
			(effects
				(font
					(size 1.27 1.27)
				)
				(justify mirror)
			)
		)
		(property "Value" "4K7R2F-GP"
			(at -0.064008 -3.993896 0)
			(unlocked yes)
			(layer "B.Fab")
			(hide yes)
			(effects
				(font
					(size 1.016 1.016)
					(thickness 0.1524)
				)
				(justify mirror)
			)
		)
		(property "Device Type" "R402H16"
			(at -0.064008 -5.517896 0)
			(unlocked yes)
			(layer "B.Fab")
			(hide yes)
			(effects
				(font
					(size 1.016 1.016)
					(thickness 0.1524)
				)
				(justify mirror)
			)
		)
		(duplicate_pad_numbers_are_jumpers no)
		(fp_line
			(start -0.508 -0.9398)
			(end 0.508 -0.9398)
			(stroke
				(width 0.1524)
				(type default)
			)
			(layer "B.SilkS")
		)
		(fp_line
			(start 0.508 -0.9398)
			(end 0.508 0.9398)
			(stroke
				(width 0.1524)
				(type default)
			)
			(layer "B.SilkS")
		)
		(fp_rect
			(start 0.508 0.9398)
			(end -0.508 -0.9398)
			(stroke
				(width 0)
				(type default)
			)
			(fill no)
			(layer "B.CrtYd")
		)
		(fp_rect
			(start 0.508 0.9398)
			(end -0.508 -0.9398)
			(stroke
				(width 0)
				(type default)
			)
			(fill no)
			(layer "B.Fab")
		)
		(pad "1" smd custom
			(at 0 -0.4445 180)
			(size 0.1397 0.1397)
			(layers "B.Cu" "B.Mask" "B.Paste")
			(net "P1V8_E")
			(options
				(clearance outline)
				(anchor circle)
			)
			(primitives
				(gr_poly
					(pts
						(arc
							(start -0.1778 0.2794)
							(mid -0.249642 0.249642)
							(end -0.2794 0.1778)
						)
						(arc
							(start -0.2794 -0.1778)
							(mid -0.249642 -0.249642)
							(end -0.1778 -0.2794)
						)
						(arc
							(start 0.1778 -0.2794)
							(mid 0.249642 -0.249642)
							(end 0.2794 -0.1778)
						)
						(arc
							(start 0.2794 0.1778)
							(mid 0.249642 0.249642)
							(end 0.1778 0.2794)
						)
					)
					(width 0)
					(fill yes)
				)
			)
		)
		(pad "2" smd custom
			(at 0 0.4445 180)
			(size 0.1397 0.1397)
			(layers "B.Cu" "B.Mask" "B.Paste")
			(net "EXP_XM_ADDR_17")
			(options
				(clearance outline)
				(anchor circle)
			)
			(primitives
				(gr_poly
					(pts
						(arc
							(start -0.1778 0.2794)
							(mid -0.249642 0.249642)
							(end -0.2794 0.1778)
						)
						(arc
							(start -0.2794 -0.1778)
							(mid -0.249642 -0.249642)
							(end -0.1778 -0.2794)
						)
						(arc
							(start 0.1778 -0.2794)
							(mid 0.249642 -0.249642)
							(end 0.2794 -0.1778)
						)
						(arc
							(start 0.2794 0.1778)
							(mid 0.249642 0.249642)
							(end 0.1778 0.2794)
						)
					)
					(width 0)
					(fill yes)
				)
			)
		)
	)
	(footprint ""
		(layer "B.Cu")
		(at 121.3866 -59.4487)
		(property "Reference" "C251"
			(at 0 0 0)
			(layer "B.SilkS")
			(hide yes)
			(effects
				(font
					(size 1.27 1.27)
				)
				(justify mirror)
			)
		)
		(property "Value" "SCD1U6D3V1KX-GP"
			(at 2.8321 -1.7399 0)
			(unlocked yes)
			(layer "B.Fab")
			(hide yes)
			(effects
				(font
					(size 1.016 1.016)
					(thickness 0.1524)
				)
				(justify mirror)
			)
		)
		(property "Device Type" "C0201H13"
			(at 2.8321 -3.2639 0)
			(unlocked yes)
			(layer "B.Fab")
			(hide yes)
			(effects
				(font
					(size 1.016 1.016)
					(thickness 0.1524)
				)
				(justify mirror)
			)
		)
		(duplicate_pad_numbers_are_jumpers no)
		(fp_rect
			(start 0.2794 0.6477)
			(end -0.2794 -0.6477)
			(stroke
				(width 0)
				(type default)
			)
			(fill no)
			(layer "B.CrtYd")
		)
		(fp_rect
			(start 0.2794 0.6477)
			(end -0.2794 -0.6477)
			(stroke
				(width 0)
				(type default)
			)
			(fill no)
			(layer "B.Fab")
		)
		(pad "1" smd custom
			(at 0 -0.2794 180)
			(size 0.0762 0.0762)
			(layers "B.Cu" "B.Mask" "B.Paste")
			(net "GB_VDDA")
			(options
				(clearance outline)
				(anchor circle)
			)
			(primitives
				(gr_poly
					(pts
						(arc
							(start 0.1524 0.127)
							(mid 0.137521 0.162921)
							(end 0.1016 0.1778)
						)
						(arc
							(start -0.1016 0.1778)
							(mid -0.137521 0.162921)
							(end -0.1524 0.127)
						)
						(arc
							(start -0.1524 -0.127)
							(mid -0.137521 -0.162921)
							(end -0.1016 -0.1778)
						)
						(arc
							(start 0.1016 -0.1778)
							(mid 0.137521 -0.162921)
							(end 0.1524 -0.127)
						)
					)
					(width 0)
					(fill yes)
				)
			)
		)
		(pad "2" smd custom
			(at 0 0.2794 180)
			(size 0.0762 0.0762)
			(layers "B.Cu" "B.Mask" "B.Paste")
			(net "GND")
			(options
				(clearance outline)
				(anchor circle)
			)
			(primitives
				(gr_poly
					(pts
						(arc
							(start 0.1524 0.127)
							(mid 0.137521 0.162921)
							(end 0.1016 0.1778)
						)
						(arc
							(start -0.1016 0.1778)
							(mid -0.137521 0.162921)
							(end -0.1524 0.127)
						)
						(arc
							(start -0.1524 -0.127)
							(mid -0.137521 -0.162921)
							(end -0.1016 -0.1778)
						)
						(arc
							(start 0.1016 -0.1778)
							(mid 0.137521 -0.162921)
							(end 0.1524 -0.127)
						)
					)
					(width 0)
					(fill yes)
				)
			)
		)
	)
	(footprint ""
		(layer "B.Cu")
		(at 93.6244 -82.55)
		(property "Reference" "U42"
			(at 0 0 0)
			(layer "B.SilkS")
			(hide yes)
			(effects
				(font
					(size 1.27 1.27)
				)
				(justify mirror)
			)
		)
		(property "Value" "SN74LVC1G11DCKR-GP"
			(at -0.0508 -11.5824 0)
			(unlocked yes)
			(layer "B.Fab")
			(hide yes)
			(effects
				(font
					(size 1.016 1.016)
					(thickness 0.1524)
				)
				(justify mirror)
			)
		)
		(property "Device Type" "UMT6H44"
			(at -0.0508 -13.1572 0)
			(unlocked yes)
			(layer "B.Fab")
			(hide yes)
			(effects
				(font
					(size 1.016 1.016)
					(thickness 0.1524)
				)
				(justify mirror)
			)
		)
		(duplicate_pad_numbers_are_jumpers no)
		(fp_line
			(start -1.524 -0.36449)
			(end -1.524 -1.82245)
			(stroke
				(width 0.508)
				(type default)
			)
			(layer "B.SilkS")
		)
		(fp_line
			(start -1.524 -0.36449)
			(end -1.524 0.36449)
			(stroke
				(width 0.1524)
				(type default)
			)
			(layer "B.SilkS")
		)
		(fp_line
			(start -1.524 -0.36449)
			(end -1.45796 -0.36449)
			(stroke
				(width 0.1524)
				(type default)
			)
			(layer "B.SilkS")
		)
		(fp_line
			(start -1.524 0.36449)
			(end 1.27 0.36449)
			(stroke
				(width 0.1524)
				(type default)
			)
			(layer "B.SilkS")
		)
		(fp_line
			(start -1.45796 -0.36449)
			(end -1.09347 0)
			(stroke
				(width 0.1524)
				(type default)
			)
			(layer "B.SilkS")
		)
		(fp_line
			(start -1.09347 0)
			(end -1.45796 0.36449)
			(stroke
				(width 0.1524)
				(type default)
			)
			(layer "B.SilkS")
		)
		(fp_line
			(start 1.27 -0.36449)
			(end -1.524 -0.36449)
			(stroke
				(width 0.1524)
				(type default)
			)
			(layer "B.SilkS")
		)
		(fp_line
			(start 1.27 -0.36449)
			(end 1.27 0.36449)
			(stroke
				(width 0.1524)
				(type default)
			)
			(layer "B.SilkS")
		)
		(fp_poly
			(pts
				(xy 0.65024 0.36449) (xy 0.65024 -0.36449) (xy -0.65024 -0.36449) (xy -0.65024 0.36449)
			)
			(stroke
				(width 0)
				(type default)
			)
			(fill yes)
			(layer "B.SilkS")
		)
		(fp_poly
			(pts
				(xy -1.016 -1.0668) (xy -1.016 1.0668) (xy 1.016 1.0668) (xy 1.016 -1.0668)
			)
			(stroke
				(width 0)
				(type default)
			)
			(fill no)
			(layer "B.CrtYd")
		)
		(fp_poly
			(pts
				(xy 1.524 1.905) (xy -1.524 1.905) (xy -1.524 -1.06426) (xy -1.016 -1.06426) (xy -1.016 1.0668)
				(xy 1.016 1.0668) (xy 1.016 -1.0668) (xy -1.524 -1.0668) (xy -1.524 -1.905) (xy 1.524 -1.905)
			)
			(stroke
				(width 0)
				(type default)
			)
			(fill no)
			(layer "B.CrtYd")
		)
		(fp_poly
			(pts
				(xy 1.524 -1.905) (xy 1.524 1.905) (xy -1.524 1.905) (xy -1.524 -1.905)
			)
			(stroke
				(width 0)
				(type default)
			)
			(fill no)
			(layer "B.Fab")
		)
		(pad "1" smd rect
			(at -0.65024 -1.02489 180)
			(size 0.4064 0.8128)
			(layers "B.Cu" "B.Mask" "B.Paste")
			(net "EXP_RESET_N")
		)
		(pad "2" smd rect
			(at 0 -1.02489 180)
			(size 0.4064 0.8128)
			(layers "B.Cu" "B.Mask" "B.Paste")
			(net "GND")
		)
		(pad "3" smd rect
			(at 0.65024 -1.02489 180)
			(size 0.4064 0.8128)
			(layers "B.Cu" "B.Mask" "B.Paste")
			(net "ICE_RESET_N")
		)
		(pad "4" smd rect
			(at 0.65024 1.02489 180)
			(size 0.4064 0.8128)
			(layers "B.Cu" "B.Mask" "B.Paste")
			(net "EXP_SYS_RST_N")
		)
		(pad "5" smd rect
			(at 0 1.02489 180)
			(size 0.4064 0.8128)
			(layers "B.Cu" "B.Mask" "B.Paste")
			(net "P1V8_E")
		)
		(pad "6" smd rect
			(at -0.65024 1.02489 180)
			(size 0.4064 0.8128)
			(layers "B.Cu" "B.Mask" "B.Paste")
			(net "SCC_RESET_LS_R_N")
		)
	)
	(footprint ""
		(layer "B.Cu")
		(at 120.5738 -63.2968 -90)
		(property "Reference" "C217"
			(at 0 0 90)
			(layer "B.SilkS")
			(hide yes)
			(effects
				(font
					(size 1.27 1.27)
				)
				(justify mirror)
			)
		)
		(property "Value" "SCD1U16V2KX-3GP"
			(at -1.1811 -2.7051 270)
			(unlocked yes)
			(layer "B.Fab")
			(hide yes)
			(effects
				(font
					(size 1.016 1.016)
					(thickness 0.1524)
				)
				(justify mirror)
			)
		)
		(property "Device Type" "C402H22"
			(at -1.1811 -4.2291 270)
			(unlocked yes)
			(layer "B.Fab")
			(hide yes)
			(effects
				(font
					(size 1.016 1.016)
					(thickness 0.1524)
				)
				(justify mirror)
			)
		)
		(duplicate_pad_numbers_are_jumpers no)
		(fp_rect
			(start 0.4318 0.9525)
			(end -0.4318 -0.9525)
			(stroke
				(width 0)
				(type default)
			)
			(fill no)
			(layer "B.CrtYd")
		)
		(fp_rect
			(start 0.4318 0.9525)
			(end -0.4318 -0.9525)
			(stroke
				(width 0)
				(type default)
			)
			(fill no)
			(layer "B.Fab")
		)
		(pad "1" smd custom
			(at 0 -0.4445 90)
			(size 0.1524 0.1524)
			(layers "B.Cu" "B.Mask" "B.Paste")
			(net "GB_VDDH")
			(options
				(clearance outline)
				(anchor circle)
			)
			(primitives
				(gr_poly
					(pts
						(arc
							(start 0.3048 0.2032)
							(mid 0.275042 0.275042)
							(end 0.2032 0.3048)
						)
						(arc
							(start -0.2032 0.3048)
							(mid -0.275042 0.275042)
							(end -0.3048 0.2032)
						)
						(arc
							(start -0.3048 -0.2032)
							(mid -0.275042 -0.275042)
							(end -0.2032 -0.3048)
						)
						(arc
							(start 0.2032 -0.3048)
							(mid 0.275042 -0.275042)
							(end 0.3048 -0.2032)
						)
					)
					(width 0)
					(fill yes)
				)
			)
		)
		(pad "2" smd custom
			(at 0 0.4445 90)
			(size 0.1524 0.1524)
			(layers "B.Cu" "B.Mask" "B.Paste")
			(net "GND")
			(options
				(clearance outline)
				(anchor circle)
			)
			(primitives
				(gr_poly
					(pts
						(arc
							(start 0.3048 0.2032)
							(mid 0.275042 0.275042)
							(end 0.2032 0.3048)
						)
						(arc
							(start -0.2032 0.3048)
							(mid -0.275042 0.275042)
							(end -0.3048 0.2032)
						)
						(arc
							(start -0.3048 -0.2032)
							(mid -0.275042 -0.275042)
							(end -0.2032 -0.3048)
						)
						(arc
							(start 0.2032 -0.3048)
							(mid 0.275042 -0.275042)
							(end 0.3048 -0.2032)
						)
					)
					(width 0)
					(fill yes)
				)
			)
		)
	)
	(footprint ""
		(layer "B.Cu")
		(at 129.54 -89.7382)
		(property "Reference" "R65"
			(at 0 0 0)
			(layer "B.SilkS")
			(hide yes)
			(effects
				(font
					(size 1.27 1.27)
				)
				(justify mirror)
			)
		)
		(property "Value" "4K7R2F-GP"
			(at -0.064008 -3.993896 0)
			(unlocked yes)
			(layer "B.Fab")
			(hide yes)
			(effects
				(font
					(size 1.016 1.016)
					(thickness 0.1524)
				)
				(justify mirror)
			)
		)
		(property "Device Type" "R402H16"
			(at -0.064008 -5.517896 0)
			(unlocked yes)
			(layer "B.Fab")
			(hide yes)
			(effects
				(font
					(size 1.016 1.016)
					(thickness 0.1524)
				)
				(justify mirror)
			)
		)
		(duplicate_pad_numbers_are_jumpers no)
		(fp_line
			(start -0.508 -0.9398)
			(end 0.508 -0.9398)
			(stroke
				(width 0.1524)
				(type default)
			)
			(layer "B.SilkS")
		)
		(fp_line
			(start 0.508 -0.9398)
			(end 0.508 0.9398)
			(stroke
				(width 0.1524)
				(type default)
			)
			(layer "B.SilkS")
		)
		(fp_rect
			(start 0.508 0.9398)
			(end -0.508 -0.9398)
			(stroke
				(width 0)
				(type default)
			)
			(fill no)
			(layer "B.CrtYd")
		)
		(fp_rect
			(start 0.508 0.9398)
			(end -0.508 -0.9398)
			(stroke
				(width 0)
				(type default)
			)
			(fill no)
			(layer "B.Fab")
		)
		(pad "1" smd custom
			(at 0 -0.4445 180)
			(size 0.1397 0.1397)
			(layers "B.Cu" "B.Mask" "B.Paste")
			(net "P1V8_E")
			(options
				(clearance outline)
				(anchor circle)
			)
			(primitives
				(gr_poly
					(pts
						(arc
							(start -0.1778 0.2794)
							(mid -0.249642 0.249642)
							(end -0.2794 0.1778)
						)
						(arc
							(start -0.2794 -0.1778)
							(mid -0.249642 -0.249642)
							(end -0.1778 -0.2794)
						)
						(arc
							(start 0.1778 -0.2794)
							(mid 0.249642 -0.249642)
							(end 0.2794 -0.1778)
						)
						(arc
							(start 0.2794 0.1778)
							(mid 0.249642 0.249642)
							(end 0.1778 0.2794)
						)
					)
					(width 0)
					(fill yes)
				)
			)
		)
		(pad "2" smd custom
			(at 0 0.4445 180)
			(size 0.1397 0.1397)
			(layers "B.Cu" "B.Mask" "B.Paste")
			(net "I2C_CLIP_SDA7_LS")
			(options
				(clearance outline)
				(anchor circle)
			)
			(primitives
				(gr_poly
					(pts
						(arc
							(start -0.1778 0.2794)
							(mid -0.249642 0.249642)
							(end -0.2794 0.1778)
						)
						(arc
							(start -0.2794 -0.1778)
							(mid -0.249642 -0.249642)
							(end -0.1778 -0.2794)
						)
						(arc
							(start 0.1778 -0.2794)
							(mid 0.249642 -0.249642)
							(end 0.2794 -0.1778)
						)
						(arc
							(start 0.2794 0.1778)
							(mid 0.249642 0.249642)
							(end 0.1778 0.2794)
						)
					)
					(width 0)
					(fill yes)
				)
			)
		)
	)
	(footprint ""
		(layer "B.Cu")
		(at 176.977294 -46.096682 180)
		(property "Reference" "C405"
			(at 0 0 0)
			(layer "B.SilkS")
			(hide yes)
			(effects
				(font
					(size 1.27 1.27)
				)
				(justify mirror)
			)
		)
		(property "Value" "SC10U6D3V5KX-4GP"
			(at 0.0762 -6.1214 180)
			(unlocked yes)
			(layer "B.Fab")
			(hide yes)
			(effects
				(font
					(size 1.016 1.016)
					(thickness 0.1524)
				)
				(justify mirror)
			)
		)
		(property "Device Type" "C805H58"
			(at 0.0762 -8.1534 180)
			(unlocked yes)
			(layer "B.Fab")
			(hide yes)
			(effects
				(font
					(size 1.016 1.016)
					(thickness 0.1524)
				)
				(justify mirror)
			)
		)
		(duplicate_pad_numbers_are_jumpers no)
		(fp_line
			(start -0.635 0)
			(end 0.635 0)
			(stroke
				(width 0.508)
				(type default)
			)
			(layer "B.SilkS")
		)
		(fp_rect
			(start 0.9652 1.778)
			(end -0.9652 -1.778)
			(stroke
				(width 0)
				(type default)
			)
			(fill no)
			(layer "B.CrtYd")
		)
		(fp_poly
			(pts
				(xy 0.9652 -1.778) (xy -0.9652 -1.778) (xy -0.9652 1.778) (xy 0.9652 1.778)
			)
			(stroke
				(width 0)
				(type default)
			)
			(fill no)
			(layer "B.Fab")
		)
		(pad "1" smd rect
			(at 0 -0.9652)
			(size 1.397 1.143)
			(layers "B.Cu" "B.Mask" "B.Paste")
			(net "P0V975")
		)
		(pad "2" smd rect
			(at 0 0.9652)
			(size 1.397 1.143)
			(layers "B.Cu" "B.Mask" "B.Paste")
			(net "GND")
		)
	)
	(footprint ""
		(layer "B.Cu")
		(at 116.7638 -59.4487)
		(property "Reference" "C512"
			(at 0 0 0)
			(layer "B.SilkS")
			(hide yes)
			(effects
				(font
					(size 1.27 1.27)
				)
				(justify mirror)
			)
		)
		(property "Value" "SCD1U6D3V1KX-GP"
			(at 2.8321 -1.7399 0)
			(unlocked yes)
			(layer "B.Fab")
			(hide yes)
			(effects
				(font
					(size 1.016 1.016)
					(thickness 0.1524)
				)
				(justify mirror)
			)
		)
		(property "Device Type" "C0201H13"
			(at 2.8321 -3.2639 0)
			(unlocked yes)
			(layer "B.Fab")
			(hide yes)
			(effects
				(font
					(size 1.016 1.016)
					(thickness 0.1524)
				)
				(justify mirror)
			)
		)
		(duplicate_pad_numbers_are_jumpers no)
		(fp_rect
			(start 0.2794 0.6477)
			(end -0.2794 -0.6477)
			(stroke
				(width 0)
				(type default)
			)
			(fill no)
			(layer "B.CrtYd")
		)
		(fp_rect
			(start 0.2794 0.6477)
			(end -0.2794 -0.6477)
			(stroke
				(width 0)
				(type default)
			)
			(fill no)
			(layer "B.Fab")
		)
		(pad "1" smd custom
			(at 0 -0.2794 180)
			(size 0.0762 0.0762)
			(layers "B.Cu" "B.Mask" "B.Paste")
			(net "GB_VDDA")
			(options
				(clearance outline)
				(anchor circle)
			)
			(primitives
				(gr_poly
					(pts
						(arc
							(start 0.1524 0.127)
							(mid 0.137521 0.162921)
							(end 0.1016 0.1778)
						)
						(arc
							(start -0.1016 0.1778)
							(mid -0.137521 0.162921)
							(end -0.1524 0.127)
						)
						(arc
							(start -0.1524 -0.127)
							(mid -0.137521 -0.162921)
							(end -0.1016 -0.1778)
						)
						(arc
							(start 0.1016 -0.1778)
							(mid 0.137521 -0.162921)
							(end 0.1524 -0.127)
						)
					)
					(width 0)
					(fill yes)
				)
			)
		)
		(pad "2" smd custom
			(at 0 0.2794 180)
			(size 0.0762 0.0762)
			(layers "B.Cu" "B.Mask" "B.Paste")
			(net "GND")
			(options
				(clearance outline)
				(anchor circle)
			)
			(primitives
				(gr_poly
					(pts
						(arc
							(start 0.1524 0.127)
							(mid 0.137521 0.162921)
							(end 0.1016 0.1778)
						)
						(arc
							(start -0.1016 0.1778)
							(mid -0.137521 0.162921)
							(end -0.1524 0.127)
						)
						(arc
							(start -0.1524 -0.127)
							(mid -0.137521 -0.162921)
							(end -0.1016 -0.1778)
						)
						(arc
							(start 0.1016 -0.1778)
							(mid 0.137521 -0.162921)
							(end 0.1524 -0.127)
						)
					)
					(width 0)
					(fill yes)
				)
			)
		)
	)
	(footprint ""
		(layer "B.Cu")
		(at 106.254042 -72.605392)
		(property "Reference" "C120"
			(at 0 0 0)
			(layer "B.SilkS")
			(hide yes)
			(effects
				(font
					(size 1.27 1.27)
				)
				(justify mirror)
			)
		)
		(property "Value" "SC10U6D3V2MX-GP-U"
			(at 1.524 -1.905 0)
			(unlocked yes)
			(layer "B.Fab")
			(hide yes)
			(effects
				(font
					(size 1.016 1.016)
					(thickness 0.1524)
				)
				(justify mirror)
			)
		)
		(property "Device Type" "C402-TO0D2H28"
			(at 1.524 -3.429 0)
			(unlocked yes)
			(layer "B.Fab")
			(hide yes)
			(effects
				(font
					(size 1.016 1.016)
					(thickness 0.1524)
				)
				(justify mirror)
			)
		)
		(duplicate_pad_numbers_are_jumpers no)
		(fp_rect
			(start 0.4826 0.889)
			(end -0.4826 -0.889)
			(stroke
				(width 0)
				(type default)
			)
			(fill no)
			(layer "B.CrtYd")
		)
		(fp_rect
			(start 0.4826 0.889)
			(end -0.4826 -0.889)
			(stroke
				(width 0)
				(type default)
			)
			(fill no)
			(layer "B.Fab")
		)
		(pad "1" smd custom
			(at 0 -0.4572 180)
			(size 0.1524 0.1524)
			(layers "B.Cu" "B.Mask" "B.Paste")
			(net "P1V8_E")
			(options
				(clearance outline)
				(anchor circle)
			)
			(primitives
				(gr_poly
					(pts
						(arc
							(start -0.254 -0.3048)
							(mid -0.325842 -0.275042)
							(end -0.3556 -0.2032)
						)
						(arc
							(start -0.3556 0.2032)
							(mid -0.325842 0.275042)
							(end -0.254 0.3048)
						)
						(arc
							(start 0.254 0.3048)
							(mid 0.325842 0.275042)
							(end 0.3556 0.2032)
						)
						(arc
							(start 0.3556 -0.2032)
							(mid 0.325842 -0.275042)
							(end 0.254 -0.3048)
						)
					)
					(width 0)
					(fill yes)
				)
			)
		)
		(pad "2" smd custom
			(at 0 0.4572 180)
			(size 0.1524 0.1524)
			(layers "B.Cu" "B.Mask" "B.Paste")
			(net "GND")
			(options
				(clearance outline)
				(anchor circle)
			)
			(primitives
				(gr_poly
					(pts
						(arc
							(start -0.254 -0.3048)
							(mid -0.325842 -0.275042)
							(end -0.3556 -0.2032)
						)
						(arc
							(start -0.3556 0.2032)
							(mid -0.325842 0.275042)
							(end -0.254 0.3048)
						)
						(arc
							(start 0.254 0.3048)
							(mid 0.325842 0.275042)
							(end 0.3556 0.2032)
						)
						(arc
							(start 0.3556 -0.2032)
							(mid 0.325842 -0.275042)
							(end 0.254 -0.3048)
						)
					)
					(width 0)
					(fill yes)
				)
			)
		)
	)
	(footprint ""
		(layer "B.Cu")
		(at 167.259 -93.98 180)
		(property "Reference" "PSP2"
			(at 0 0 0)
			(layer "B.SilkS")
			(hide yes)
			(effects
				(font
					(size 1.27 1.27)
				)
				(justify mirror)
			)
		)
		(property "Value" "COPPER-CLOSE-GP-U"
			(at -0.0762 -2.8702 180)
			(unlocked yes)
			(layer "B.Fab")
			(hide yes)
			(effects
				(font
					(size 1.016 1.016)
					(thickness 0.1524)
				)
				(justify mirror)
			)
		)
		(property "Device Type" "CON2C-U"
			(at -0.0762 -4.3942 180)
			(unlocked yes)
			(layer "B.Fab")
			(hide yes)
			(effects
				(font
					(size 1.016 1.016)
					(thickness 0.1524)
				)
				(justify mirror)
			)
		)
		(duplicate_pad_numbers_are_jumpers no)
		(fp_rect
			(start 0.9398 0.9652)
			(end -0.9398 -0.9652)
			(stroke
				(width 0)
				(type default)
			)
			(fill no)
			(layer "B.CrtYd")
		)
		(fp_rect
			(start 0.9398 0.9652)
			(end -0.9398 -0.9652)
			(stroke
				(width 0)
				(type default)
			)
			(fill no)
			(layer "B.Fab")
		)
		(pad "1" smd custom
			(at 0 -0.5334)
			(size 0.17145 0.17145)
			(layers "B.Cu" "B.Mask" "B.Paste")
			(net "GND")
			(options
				(clearance outline)
				(anchor circle)
			)
			(primitives
				(gr_poly
					(pts
						(xy -0.127 -0.3429) (xy -0.127 -0.1651) (xy -0.635 0.3429) (xy 0.635 0.3429) (xy 0.127 -0.1651)
						(xy 0.127 -0.3429)
					)
					(width 0)
					(fill yes)
				)
			)
		)
		(pad "2" smd custom
			(at 0 0.5334)
			(size 0.17145 0.17145)
			(layers "B.Cu" "B.Mask" "B.Paste")
			(net "AGND_P0V975")
			(options
				(clearance outline)
				(anchor circle)
			)
			(primitives
				(gr_poly
					(pts
						(xy -0.635 -0.3429) (xy -0.127 0.1651) (xy -0.127 0.3429) (xy 0.127 0.3429) (xy 0.127 0.1651)
						(xy 0.635 -0.3429)
					)
					(width 0)
					(fill yes)
				)
			)
		)
	)
	(footprint ""
		(layer "B.Cu")
		(at 114.681 -53.467 180)
		(property "Reference" "C233"
			(at 0 0 0)
			(layer "B.SilkS")
			(hide yes)
			(effects
				(font
					(size 1.27 1.27)
				)
				(justify mirror)
			)
		)
		(property "Value" "SCD1U6D3V1KX-GP"
			(at 2.8321 -1.7399 180)
			(unlocked yes)
			(layer "B.Fab")
			(hide yes)
			(effects
				(font
					(size 1.016 1.016)
					(thickness 0.1524)
				)
				(justify mirror)
			)
		)
		(property "Device Type" "C0201H13"
			(at 2.8321 -3.2639 180)
			(unlocked yes)
			(layer "B.Fab")
			(hide yes)
			(effects
				(font
					(size 1.016 1.016)
					(thickness 0.1524)
				)
				(justify mirror)
			)
		)
		(duplicate_pad_numbers_are_jumpers no)
		(fp_rect
			(start 0.2794 0.6477)
			(end -0.2794 -0.6477)
			(stroke
				(width 0)
				(type default)
			)
			(fill no)
			(layer "B.CrtYd")
		)
		(fp_rect
			(start 0.2794 0.6477)
			(end -0.2794 -0.6477)
			(stroke
				(width 0)
				(type default)
			)
			(fill no)
			(layer "B.Fab")
		)
		(pad "1" smd custom
			(at 0 -0.2794)
			(size 0.0762 0.0762)
			(layers "B.Cu" "B.Mask" "B.Paste")
			(net "GB_VDDA")
			(options
				(clearance outline)
				(anchor circle)
			)
			(primitives
				(gr_poly
					(pts
						(arc
							(start 0.1524 0.127)
							(mid 0.137521 0.162921)
							(end 0.1016 0.1778)
						)
						(arc
							(start -0.1016 0.1778)
							(mid -0.137521 0.162921)
							(end -0.1524 0.127)
						)
						(arc
							(start -0.1524 -0.127)
							(mid -0.137521 -0.162921)
							(end -0.1016 -0.1778)
						)
						(arc
							(start 0.1016 -0.1778)
							(mid 0.137521 -0.162921)
							(end 0.1524 -0.127)
						)
					)
					(width 0)
					(fill yes)
				)
			)
		)
		(pad "2" smd custom
			(at 0 0.2794)
			(size 0.0762 0.0762)
			(layers "B.Cu" "B.Mask" "B.Paste")
			(net "GND")
			(options
				(clearance outline)
				(anchor circle)
			)
			(primitives
				(gr_poly
					(pts
						(arc
							(start 0.1524 0.127)
							(mid 0.137521 0.162921)
							(end 0.1016 0.1778)
						)
						(arc
							(start -0.1016 0.1778)
							(mid -0.137521 0.162921)
							(end -0.1524 0.127)
						)
						(arc
							(start -0.1524 -0.127)
							(mid -0.137521 -0.162921)
							(end -0.1016 -0.1778)
						)
						(arc
							(start 0.1016 -0.1778)
							(mid 0.137521 -0.162921)
							(end 0.1524 -0.127)
						)
					)
					(width 0)
					(fill yes)
				)
			)
		)
	)
	(footprint ""
		(layer "B.Cu")
		(at 189.5856 -34.1884 90)
		(property "Reference" "TP93"
			(at 0 0 90)
			(layer "B.SilkS")
			(hide yes)
			(effects
				(font
					(size 1.27 1.27)
				)
				(justify mirror)
			)
		)
		(property "Value" "TPAD28-2-GP"
			(at 0.0127 -1.6637 90)
			(unlocked yes)
			(layer "B.Fab")
			(hide yes)
			(effects
				(font
					(size 1.016 1.016)
					(thickness 0.1524)
				)
				(justify mirror)
			)
		)
		(property "Device Type" "TPAD28"
			(at 0.0127 -3.1877 90)
			(unlocked yes)
			(layer "B.Fab")
			(hide yes)
			(effects
				(font
					(size 1.016 1.016)
					(thickness 0.1524)
				)
				(justify mirror)
			)
		)
		(duplicate_pad_numbers_are_jumpers no)
		(fp_poly
			(pts
				(arc
					(start 0 0.3556)
					(mid 0 -0.3556)
					(end 0 0.3556)
				)
			)
			(stroke
				(width 0)
				(type default)
			)
			(fill no)
			(layer "B.CrtYd")
		)
		(fp_poly
			(pts
				(arc
					(start 0 0.6096)
					(mid 0 -0.6096)
					(end 0 0.6096)
				)
			)
			(stroke
				(width 0)
				(type default)
			)
			(fill no)
			(layer "B.Fab")
		)
		(pad "1" smd circle
			(at 0 0 270)
			(size 0.7112 0.7112)
			(layers "B.Cu" "B.Mask" "B.Paste")
			(net "IOC_GPIO_33")
		)
	)
	(footprint ""
		(layer "B.Cu")
		(at 96.497394 -55.141368 90)
		(property "Reference" "C96"
			(at 0 0 90)
			(layer "B.SilkS")
			(hide yes)
			(effects
				(font
					(size 1.27 1.27)
				)
				(justify mirror)
			)
		)
		(property "Value" "SCD01U16V1KX-GP"
			(at 2.8321 -1.7399 90)
			(unlocked yes)
			(layer "B.Fab")
			(hide yes)
			(effects
				(font
					(size 1.016 1.016)
					(thickness 0.1524)
				)
				(justify mirror)
			)
		)
		(property "Device Type" "C0201H13"
			(at 2.8321 -3.2639 90)
			(unlocked yes)
			(layer "B.Fab")
			(hide yes)
			(effects
				(font
					(size 1.016 1.016)
					(thickness 0.1524)
				)
				(justify mirror)
			)
		)
		(duplicate_pad_numbers_are_jumpers no)
		(fp_rect
			(start 0.2794 0.6477)
			(end -0.2794 -0.6477)
			(stroke
				(width 0)
				(type default)
			)
			(fill no)
			(layer "B.CrtYd")
		)
		(fp_rect
			(start 0.2794 0.6477)
			(end -0.2794 -0.6477)
			(stroke
				(width 0)
				(type default)
			)
			(fill no)
			(layer "B.Fab")
		)
		(pad "1" smd custom
			(at 0 -0.2794 270)
			(size 0.0762 0.0762)
			(layers "B.Cu" "B.Mask" "B.Paste")
			(net "PHY_DPB_TO_SCC_12_DN")
			(options
				(clearance outline)
				(anchor circle)
			)
			(primitives
				(gr_poly
					(pts
						(arc
							(start 0.1524 0.127)
							(mid 0.137521 0.162921)
							(end 0.1016 0.1778)
						)
						(arc
							(start -0.1016 0.1778)
							(mid -0.137521 0.162921)
							(end -0.1524 0.127)
						)
						(arc
							(start -0.1524 -0.127)
							(mid -0.137521 -0.162921)
							(end -0.1016 -0.1778)
						)
						(arc
							(start 0.1016 -0.1778)
							(mid 0.137521 -0.162921)
							(end 0.1524 -0.127)
						)
					)
					(width 0)
					(fill yes)
				)
			)
		)
		(pad "2" smd custom
			(at 0 0.2794 270)
			(size 0.0762 0.0762)
			(layers "B.Cu" "B.Mask" "B.Paste")
			(net "PHY_DPB_TO_SCC_C_12_DN")
			(options
				(clearance outline)
				(anchor circle)
			)
			(primitives
				(gr_poly
					(pts
						(arc
							(start 0.1524 0.127)
							(mid 0.137521 0.162921)
							(end 0.1016 0.1778)
						)
						(arc
							(start -0.1016 0.1778)
							(mid -0.137521 0.162921)
							(end -0.1524 0.127)
						)
						(arc
							(start -0.1524 -0.127)
							(mid -0.137521 -0.162921)
							(end -0.1016 -0.1778)
						)
						(arc
							(start 0.1016 -0.1778)
							(mid 0.137521 -0.162921)
							(end 0.1524 -0.127)
						)
					)
					(width 0)
					(fill yes)
				)
			)
		)
	)
	(footprint ""
		(layer "B.Cu")
		(at 38.521132 -106.24058 90)
		(property "Reference" "C594"
			(at 0 0 90)
			(layer "B.SilkS")
			(hide yes)
			(effects
				(font
					(size 1.27 1.27)
				)
				(justify mirror)
			)
		)
		(property "Value" "SCD1U16V2KX-3GP"
			(at -1.1811 -2.7051 90)
			(unlocked yes)
			(layer "B.Fab")
			(hide yes)
			(effects
				(font
					(size 1.016 1.016)
					(thickness 0.1524)
				)
				(justify mirror)
			)
		)
		(property "Device Type" "C402H22"
			(at -1.1811 -4.2291 90)
			(unlocked yes)
			(layer "B.Fab")
			(hide yes)
			(effects
				(font
					(size 1.016 1.016)
					(thickness 0.1524)
				)
				(justify mirror)
			)
		)
		(duplicate_pad_numbers_are_jumpers no)
		(fp_rect
			(start 0.4318 0.9525)
			(end -0.4318 -0.9525)
			(stroke
				(width 0)
				(type default)
			)
			(fill no)
			(layer "B.CrtYd")
		)
		(fp_rect
			(start 0.4318 0.9525)
			(end -0.4318 -0.9525)
			(stroke
				(width 0)
				(type default)
			)
			(fill no)
			(layer "B.Fab")
		)
		(pad "1" smd custom
			(at 0 -0.4445 270)
			(size 0.1524 0.1524)
			(layers "B.Cu" "B.Mask" "B.Paste")
			(net "P5V")
			(options
				(clearance outline)
				(anchor circle)
			)
			(primitives
				(gr_poly
					(pts
						(arc
							(start 0.3048 0.2032)
							(mid 0.275042 0.275042)
							(end 0.2032 0.3048)
						)
						(arc
							(start -0.2032 0.3048)
							(mid -0.275042 0.275042)
							(end -0.3048 0.2032)
						)
						(arc
							(start -0.3048 -0.2032)
							(mid -0.275042 -0.275042)
							(end -0.2032 -0.3048)
						)
						(arc
							(start 0.2032 -0.3048)
							(mid 0.275042 -0.275042)
							(end 0.3048 -0.2032)
						)
					)
					(width 0)
					(fill yes)
				)
			)
		)
		(pad "2" smd custom
			(at 0 0.4445 270)
			(size 0.1524 0.1524)
			(layers "B.Cu" "B.Mask" "B.Paste")
			(net "GND")
			(options
				(clearance outline)
				(anchor circle)
			)
			(primitives
				(gr_poly
					(pts
						(arc
							(start 0.3048 0.2032)
							(mid 0.275042 0.275042)
							(end 0.2032 0.3048)
						)
						(arc
							(start -0.2032 0.3048)
							(mid -0.275042 0.275042)
							(end -0.3048 0.2032)
						)
						(arc
							(start -0.3048 -0.2032)
							(mid -0.275042 -0.275042)
							(end -0.2032 -0.3048)
						)
						(arc
							(start 0.2032 -0.3048)
							(mid 0.275042 -0.275042)
							(end 0.3048 -0.2032)
						)
					)
					(width 0)
					(fill yes)
				)
			)
		)
	)
	(footprint ""
		(layer "B.Cu")
		(at 91.018868 -71.192898 180)
		(property "Reference" "R152"
			(at 0 0 0)
			(layer "B.SilkS")
			(hide yes)
			(effects
				(font
					(size 1.27 1.27)
				)
				(justify mirror)
			)
		)
		(property "Value" "10R2F-L-GP"
			(at -0.064008 -3.993896 180)
			(unlocked yes)
			(layer "B.Fab")
			(hide yes)
			(effects
				(font
					(size 1.016 1.016)
					(thickness 0.1524)
				)
				(justify mirror)
			)
		)
		(property "Device Type" "R402H14"
			(at -0.064008 -5.517896 180)
			(unlocked yes)
			(layer "B.Fab")
			(hide yes)
			(effects
				(font
					(size 1.016 1.016)
					(thickness 0.1524)
				)
				(justify mirror)
			)
		)
		(duplicate_pad_numbers_are_jumpers no)
		(fp_line
			(start 0.508 -0.9398)
			(end 0.508 0.9398)
			(stroke
				(width 0.1524)
				(type default)
			)
			(layer "B.SilkS")
		)
		(fp_line
			(start -0.508 -0.9398)
			(end 0.508 -0.9398)
			(stroke
				(width 0.1524)
				(type default)
			)
			(layer "B.SilkS")
		)
		(fp_rect
			(start 0.508 0.9398)
			(end -0.508 -0.9398)
			(stroke
				(width 0)
				(type default)
			)
			(fill no)
			(layer "B.CrtYd")
		)
		(fp_rect
			(start 0.508 0.9398)
			(end -0.508 -0.9398)
			(stroke
				(width 0)
				(type default)
			)
			(fill no)
			(layer "B.Fab")
		)
		(pad "1" smd custom
			(at 0 -0.4445)
			(size 0.1397 0.1397)
			(layers "B.Cu" "B.Mask" "B.Paste")
			(net "P1V8_E")
			(options
				(clearance outline)
				(anchor circle)
			)
			(primitives
				(gr_poly
					(pts
						(arc
							(start -0.1778 0.2794)
							(mid -0.249642 0.249642)
							(end -0.2794 0.1778)
						)
						(arc
							(start -0.2794 -0.1778)
							(mid -0.249642 -0.249642)
							(end -0.1778 -0.2794)
						)
						(arc
							(start 0.1778 -0.2794)
							(mid 0.249642 -0.249642)
							(end 0.2794 -0.1778)
						)
						(arc
							(start 0.2794 0.1778)
							(mid 0.249642 0.249642)
							(end 0.1778 0.2794)
						)
					)
					(width 0)
					(fill yes)
				)
			)
		)
		(pad "2" smd custom
			(at 0 0.4445)
			(size 0.1397 0.1397)
			(layers "B.Cu" "B.Mask" "B.Paste")
			(net "SYSPLL_VDDA18")
			(options
				(clearance outline)
				(anchor circle)
			)
			(primitives
				(gr_poly
					(pts
						(arc
							(start -0.1778 0.2794)
							(mid -0.249642 0.249642)
							(end -0.2794 0.1778)
						)
						(arc
							(start -0.2794 -0.1778)
							(mid -0.249642 -0.249642)
							(end -0.1778 -0.2794)
						)
						(arc
							(start 0.1778 -0.2794)
							(mid 0.249642 -0.249642)
							(end 0.2794 -0.1778)
						)
						(arc
							(start 0.2794 0.1778)
							(mid 0.249642 0.249642)
							(end 0.1778 0.2794)
						)
					)
					(width 0)
					(fill yes)
				)
			)
		)
	)
	(footprint ""
		(layer "B.Cu")
		(at 173.7868 -41.30802 -90)
		(property "Reference" "C443"
			(at 0 0 90)
			(layer "B.SilkS")
			(hide yes)
			(effects
				(font
					(size 1.27 1.27)
				)
				(justify mirror)
			)
		)
		(property "Value" "SCD1U6D3V1KX-GP"
			(at 2.8321 -1.7399 270)
			(unlocked yes)
			(layer "B.Fab")
			(hide yes)
			(effects
				(font
					(size 1.016 1.016)
					(thickness 0.1524)
				)
				(justify mirror)
			)
		)
		(property "Device Type" "C0201H13"
			(at 2.8321 -3.2639 270)
			(unlocked yes)
			(layer "B.Fab")
			(hide yes)
			(effects
				(font
					(size 1.016 1.016)
					(thickness 0.1524)
				)
				(justify mirror)
			)
		)
		(duplicate_pad_numbers_are_jumpers no)
		(fp_rect
			(start 0.2794 0.6477)
			(end -0.2794 -0.6477)
			(stroke
				(width 0)
				(type default)
			)
			(fill no)
			(layer "B.CrtYd")
		)
		(fp_rect
			(start 0.2794 0.6477)
			(end -0.2794 -0.6477)
			(stroke
				(width 0)
				(type default)
			)
			(fill no)
			(layer "B.Fab")
		)
		(pad "1" smd custom
			(at 0 -0.2794 90)
			(size 0.0762 0.0762)
			(layers "B.Cu" "B.Mask" "B.Paste")
			(net "P0V975")
			(options
				(clearance outline)
				(anchor circle)
			)
			(primitives
				(gr_poly
					(pts
						(arc
							(start 0.1524 0.127)
							(mid 0.137521 0.162921)
							(end 0.1016 0.1778)
						)
						(arc
							(start -0.1016 0.1778)
							(mid -0.137521 0.162921)
							(end -0.1524 0.127)
						)
						(arc
							(start -0.1524 -0.127)
							(mid -0.137521 -0.162921)
							(end -0.1016 -0.1778)
						)
						(arc
							(start 0.1016 -0.1778)
							(mid 0.137521 -0.162921)
							(end 0.1524 -0.127)
						)
					)
					(width 0)
					(fill yes)
				)
			)
		)
		(pad "2" smd custom
			(at 0 0.2794 90)
			(size 0.0762 0.0762)
			(layers "B.Cu" "B.Mask" "B.Paste")
			(net "GND")
			(options
				(clearance outline)
				(anchor circle)
			)
			(primitives
				(gr_poly
					(pts
						(arc
							(start 0.1524 0.127)
							(mid 0.137521 0.162921)
							(end 0.1016 0.1778)
						)
						(arc
							(start -0.1016 0.1778)
							(mid -0.137521 0.162921)
							(end -0.1524 0.127)
						)
						(arc
							(start -0.1524 -0.127)
							(mid -0.137521 -0.162921)
							(end -0.1016 -0.1778)
						)
						(arc
							(start 0.1016 -0.1778)
							(mid 0.137521 -0.162921)
							(end 0.1524 -0.127)
						)
					)
					(width 0)
					(fill yes)
				)
			)
		)
	)
	(footprint ""
		(layer "B.Cu")
		(at 171.838874 -97.188782)
		(property "Reference" "C626"
			(at 0 0 0)
			(layer "B.SilkS")
			(hide yes)
			(effects
				(font
					(size 1.27 1.27)
				)
				(justify mirror)
			)
		)
		(property "Value" "SCD33U16V3KX-1GP"
			(at 0 -2.8194 0)
			(unlocked yes)
			(layer "B.Fab")
			(hide yes)
			(effects
				(font
					(size 1.016 1.016)
					(thickness 0.1524)
				)
				(justify mirror)
			)
		)
		(property "Device Type" "C603H36"
			(at 0 -4.3434 0)
			(unlocked yes)
			(layer "B.Fab")
			(hide yes)
			(effects
				(font
					(size 1.016 1.016)
					(thickness 0.1524)
				)
				(justify mirror)
			)
		)
		(duplicate_pad_numbers_are_jumpers no)
		(fp_line
			(start -0.508 0)
			(end 0.508 0)
			(stroke
				(width 0.2032)
				(type default)
			)
			(layer "B.SilkS")
		)
		(fp_rect
			(start 0.5842 1.3335)
			(end -0.5842 -1.3335)
			(stroke
				(width 0)
				(type default)
			)
			(fill no)
			(layer "B.CrtYd")
		)
		(fp_rect
			(start 0.5842 1.3335)
			(end -0.5842 -1.3335)
			(stroke
				(width 0)
				(type default)
			)
			(fill no)
			(layer "B.Fab")
		)
		(pad "1" smd custom
			(at 0 -0.762 180)
			(size 0.2159 0.2159)
			(layers "B.Cu" "B.Mask" "B.Paste")
			(net "AVSO_VREF")
			(options
				(clearance outline)
				(anchor circle)
			)
			(primitives
				(gr_poly
					(pts
						(arc
							(start -0.3302 0.4318)
							(mid -0.402042 0.402042)
							(end -0.4318 0.3302)
						)
						(arc
							(start -0.4318 -0.3302)
							(mid -0.402042 -0.402042)
							(end -0.3302 -0.4318)
						)
						(arc
							(start 0.3302 -0.4318)
							(mid 0.402042 -0.402042)
							(end 0.4318 -0.3302)
						)
						(arc
							(start 0.4318 0.3302)
							(mid 0.402042 0.402042)
							(end 0.3302 0.4318)
						)
					)
					(width 0)
					(fill yes)
				)
			)
		)
		(pad "2" smd custom
			(at 0 0.762 180)
			(size 0.2159 0.2159)
			(layers "B.Cu" "B.Mask" "B.Paste")
			(net "GND")
			(options
				(clearance outline)
				(anchor circle)
			)
			(primitives
				(gr_poly
					(pts
						(arc
							(start -0.3302 0.4318)
							(mid -0.402042 0.402042)
							(end -0.4318 0.3302)
						)
						(arc
							(start -0.4318 -0.3302)
							(mid -0.402042 -0.402042)
							(end -0.3302 -0.4318)
						)
						(arc
							(start 0.3302 -0.4318)
							(mid 0.402042 -0.402042)
							(end 0.4318 -0.3302)
						)
						(arc
							(start 0.4318 0.3302)
							(mid 0.402042 0.402042)
							(end 0.3302 0.4318)
						)
					)
					(width 0)
					(fill yes)
				)
			)
		)
	)
	(footprint ""
		(layer "B.Cu")
		(at 136.2202 -79.6036 -90)
		(property "Reference" "C4"
			(at 0 0 90)
			(layer "B.SilkS")
			(hide yes)
			(effects
				(font
					(size 1.27 1.27)
				)
				(justify mirror)
			)
		)
		(property "Value" "SCD01U16V1KX-GP"
			(at 2.8321 -1.7399 270)
			(unlocked yes)
			(layer "B.Fab")
			(hide yes)
			(effects
				(font
					(size 1.016 1.016)
					(thickness 0.1524)
				)
				(justify mirror)
			)
		)
		(property "Device Type" "C0201H13"
			(at 2.8321 -3.2639 270)
			(unlocked yes)
			(layer "B.Fab")
			(hide yes)
			(effects
				(font
					(size 1.016 1.016)
					(thickness 0.1524)
				)
				(justify mirror)
			)
		)
		(duplicate_pad_numbers_are_jumpers no)
		(fp_rect
			(start 0.2794 0.6477)
			(end -0.2794 -0.6477)
			(stroke
				(width 0)
				(type default)
			)
			(fill no)
			(layer "B.CrtYd")
		)
		(fp_rect
			(start 0.2794 0.6477)
			(end -0.2794 -0.6477)
			(stroke
				(width 0)
				(type default)
			)
			(fill no)
			(layer "B.Fab")
		)
		(pad "1" smd custom
			(at 0 -0.2794 90)
			(size 0.0762 0.0762)
			(layers "B.Cu" "B.Mask" "B.Paste")
			(net "PHY_CONN_TO_EXP_10_DN")
			(options
				(clearance outline)
				(anchor circle)
			)
			(primitives
				(gr_poly
					(pts
						(arc
							(start 0.1524 0.127)
							(mid 0.137521 0.162921)
							(end 0.1016 0.1778)
						)
						(arc
							(start -0.1016 0.1778)
							(mid -0.137521 0.162921)
							(end -0.1524 0.127)
						)
						(arc
							(start -0.1524 -0.127)
							(mid -0.137521 -0.162921)
							(end -0.1016 -0.1778)
						)
						(arc
							(start 0.1016 -0.1778)
							(mid 0.137521 -0.162921)
							(end 0.1524 -0.127)
						)
					)
					(width 0)
					(fill yes)
				)
			)
		)
		(pad "2" smd custom
			(at 0 0.2794 90)
			(size 0.0762 0.0762)
			(layers "B.Cu" "B.Mask" "B.Paste")
			(net "PHY_CONN_TO_EXP_C_10_DN")
			(options
				(clearance outline)
				(anchor circle)
			)
			(primitives
				(gr_poly
					(pts
						(arc
							(start 0.1524 0.127)
							(mid 0.137521 0.162921)
							(end 0.1016 0.1778)
						)
						(arc
							(start -0.1016 0.1778)
							(mid -0.137521 0.162921)
							(end -0.1524 0.127)
						)
						(arc
							(start -0.1524 -0.127)
							(mid -0.137521 -0.162921)
							(end -0.1016 -0.1778)
						)
						(arc
							(start 0.1016 -0.1778)
							(mid 0.137521 -0.162921)
							(end 0.1524 -0.127)
						)
					)
					(width 0)
					(fill yes)
				)
			)
		)
	)
	(footprint ""
		(layer "B.Cu")
		(at 125.984 -85.344)
		(property "Reference" "TP160"
			(at 0 0 0)
			(layer "B.SilkS")
			(hide yes)
			(effects
				(font
					(size 1.27 1.27)
				)
				(justify mirror)
			)
		)
		(property "Value" "TPAD28-2-GP"
			(at 0.0127 -1.6637 0)
			(unlocked yes)
			(layer "B.Fab")
			(hide yes)
			(effects
				(font
					(size 1.016 1.016)
					(thickness 0.1524)
				)
				(justify mirror)
			)
		)
		(property "Device Type" "TPAD28"
			(at 0.0127 -3.1877 0)
			(unlocked yes)
			(layer "B.Fab")
			(hide yes)
			(effects
				(font
					(size 1.016 1.016)
					(thickness 0.1524)
				)
				(justify mirror)
			)
		)
		(duplicate_pad_numbers_are_jumpers no)
		(fp_poly
			(pts
				(arc
					(start 0.3556 0)
					(mid -0.3556 0)
					(end 0.3556 0)
				)
			)
			(stroke
				(width 0)
				(type default)
			)
			(fill no)
			(layer "B.CrtYd")
		)
		(fp_poly
			(pts
				(arc
					(start 0.6096 0)
					(mid -0.6096 0)
					(end 0.6096 0)
				)
			)
			(stroke
				(width 0)
				(type default)
			)
			(fill no)
			(layer "B.Fab")
		)
		(pad "1" smd circle
			(at 0 0 180)
			(size 0.7112 0.7112)
			(layers "B.Cu" "B.Mask" "B.Paste")
			(net "ICE_TRST_N")
		)
	)
	(footprint ""
		(layer "B.Cu")
		(at 163.1442 -50.419)
		(property "Reference" "TP94"
			(at 0 0 0)
			(layer "B.SilkS")
			(hide yes)
			(effects
				(font
					(size 1.27 1.27)
				)
				(justify mirror)
			)
		)
		(property "Value" "TPAD28-2-GP"
			(at 0.0127 -1.6637 0)
			(unlocked yes)
			(layer "B.Fab")
			(hide yes)
			(effects
				(font
					(size 1.016 1.016)
					(thickness 0.1524)
				)
				(justify mirror)
			)
		)
		(property "Device Type" "TPAD28"
			(at 0.0127 -3.1877 0)
			(unlocked yes)
			(layer "B.Fab")
			(hide yes)
			(effects
				(font
					(size 1.016 1.016)
					(thickness 0.1524)
				)
				(justify mirror)
			)
		)
		(duplicate_pad_numbers_are_jumpers no)
		(fp_poly
			(pts
				(arc
					(start 0.3556 0)
					(mid -0.3556 0)
					(end 0.3556 0)
				)
			)
			(stroke
				(width 0)
				(type default)
			)
			(fill no)
			(layer "B.CrtYd")
		)
		(fp_poly
			(pts
				(arc
					(start 0.6096 0)
					(mid -0.6096 0)
					(end 0.6096 0)
				)
			)
			(stroke
				(width 0)
				(type default)
			)
			(fill no)
			(layer "B.Fab")
		)
		(pad "1" smd circle
			(at 0 0 180)
			(size 0.7112 0.7112)
			(layers "B.Cu" "B.Mask" "B.Paste")
			(net "SIO_LOAD_1")
		)
	)
	(footprint ""
		(layer "B.Cu")
		(at 135.405622 -56.379618 180)
		(property "Reference" "C25"
			(at 0 0 0)
			(layer "B.SilkS")
			(hide yes)
			(effects
				(font
					(size 1.27 1.27)
				)
				(justify mirror)
			)
		)
		(property "Value" "SCD01U16V1KX-GP"
			(at 2.8321 -1.7399 180)
			(unlocked yes)
			(layer "B.Fab")
			(hide yes)
			(effects
				(font
					(size 1.016 1.016)
					(thickness 0.1524)
				)
				(justify mirror)
			)
		)
		(property "Device Type" "C0201H13"
			(at 2.8321 -3.2639 180)
			(unlocked yes)
			(layer "B.Fab")
			(hide yes)
			(effects
				(font
					(size 1.016 1.016)
					(thickness 0.1524)
				)
				(justify mirror)
			)
		)
		(duplicate_pad_numbers_are_jumpers no)
		(fp_rect
			(start 0.2794 0.6477)
			(end -0.2794 -0.6477)
			(stroke
				(width 0)
				(type default)
			)
			(fill no)
			(layer "B.CrtYd")
		)
		(fp_rect
			(start 0.2794 0.6477)
			(end -0.2794 -0.6477)
			(stroke
				(width 0)
				(type default)
			)
			(fill no)
			(layer "B.Fab")
		)
		(pad "1" smd custom
			(at 0 -0.2794)
			(size 0.0762 0.0762)
			(layers "B.Cu" "B.Mask" "B.Paste")
			(net "PHY_DPB_TO_SCC_31_DP")
			(options
				(clearance outline)
				(anchor circle)
			)
			(primitives
				(gr_poly
					(pts
						(arc
							(start 0.1524 0.127)
							(mid 0.137521 0.162921)
							(end 0.1016 0.1778)
						)
						(arc
							(start -0.1016 0.1778)
							(mid -0.137521 0.162921)
							(end -0.1524 0.127)
						)
						(arc
							(start -0.1524 -0.127)
							(mid -0.137521 -0.162921)
							(end -0.1016 -0.1778)
						)
						(arc
							(start 0.1016 -0.1778)
							(mid 0.137521 -0.162921)
							(end 0.1524 -0.127)
						)
					)
					(width 0)
					(fill yes)
				)
			)
		)
		(pad "2" smd custom
			(at 0 0.2794)
			(size 0.0762 0.0762)
			(layers "B.Cu" "B.Mask" "B.Paste")
			(net "PHY_DPB_TO_SCC_C_31_DP")
			(options
				(clearance outline)
				(anchor circle)
			)
			(primitives
				(gr_poly
					(pts
						(arc
							(start 0.1524 0.127)
							(mid 0.137521 0.162921)
							(end 0.1016 0.1778)
						)
						(arc
							(start -0.1016 0.1778)
							(mid -0.137521 0.162921)
							(end -0.1524 0.127)
						)
						(arc
							(start -0.1524 -0.127)
							(mid -0.137521 -0.162921)
							(end -0.1016 -0.1778)
						)
						(arc
							(start 0.1016 -0.1778)
							(mid 0.137521 -0.162921)
							(end 0.1524 -0.127)
						)
					)
					(width 0)
					(fill yes)
				)
			)
		)
	)
	(footprint ""
		(layer "B.Cu")
		(at 133.482588 -87.260684)
		(property "Reference" "R71"
			(at 0 0 0)
			(layer "B.SilkS")
			(hide yes)
			(effects
				(font
					(size 1.27 1.27)
				)
				(justify mirror)
			)
		)
		(property "Value" "1KR2F-3-GP"
			(at -0.064008 -3.993896 0)
			(unlocked yes)
			(layer "B.Fab")
			(hide yes)
			(effects
				(font
					(size 1.016 1.016)
					(thickness 0.1524)
				)
				(justify mirror)
			)
		)
		(property "Device Type" "R402H16"
			(at -0.064008 -5.517896 0)
			(unlocked yes)
			(layer "B.Fab")
			(hide yes)
			(effects
				(font
					(size 1.016 1.016)
					(thickness 0.1524)
				)
				(justify mirror)
			)
		)
		(duplicate_pad_numbers_are_jumpers no)
		(fp_line
			(start -0.508 -0.9398)
			(end 0.508 -0.9398)
			(stroke
				(width 0.1524)
				(type default)
			)
			(layer "B.SilkS")
		)
		(fp_line
			(start 0.508 -0.9398)
			(end 0.508 0.9398)
			(stroke
				(width 0.1524)
				(type default)
			)
			(layer "B.SilkS")
		)
		(fp_rect
			(start 0.508 0.9398)
			(end -0.508 -0.9398)
			(stroke
				(width 0)
				(type default)
			)
			(fill no)
			(layer "B.CrtYd")
		)
		(fp_rect
			(start 0.508 0.9398)
			(end -0.508 -0.9398)
			(stroke
				(width 0)
				(type default)
			)
			(fill no)
			(layer "B.Fab")
		)
		(pad "1" smd custom
			(at 0 -0.4445 180)
			(size 0.1397 0.1397)
			(layers "B.Cu" "B.Mask" "B.Paste")
			(net "P1V8_E")
			(options
				(clearance outline)
				(anchor circle)
			)
			(primitives
				(gr_poly
					(pts
						(arc
							(start -0.1778 0.2794)
							(mid -0.249642 0.249642)
							(end -0.2794 0.1778)
						)
						(arc
							(start -0.2794 -0.1778)
							(mid -0.249642 -0.249642)
							(end -0.1778 -0.2794)
						)
						(arc
							(start 0.1778 -0.2794)
							(mid 0.249642 -0.249642)
							(end 0.2794 -0.1778)
						)
						(arc
							(start 0.2794 0.1778)
							(mid 0.249642 0.249642)
							(end 0.1778 0.2794)
						)
					)
					(width 0)
					(fill yes)
				)
			)
		)
		(pad "2" smd custom
			(at 0 0.4445 180)
			(size 0.1397 0.1397)
			(layers "B.Cu" "B.Mask" "B.Paste")
			(net "EXP_I2C_SDA11")
			(options
				(clearance outline)
				(anchor circle)
			)
			(primitives
				(gr_poly
					(pts
						(arc
							(start -0.1778 0.2794)
							(mid -0.249642 0.249642)
							(end -0.2794 0.1778)
						)
						(arc
							(start -0.2794 -0.1778)
							(mid -0.249642 -0.249642)
							(end -0.1778 -0.2794)
						)
						(arc
							(start 0.1778 -0.2794)
							(mid 0.249642 -0.249642)
							(end 0.2794 -0.1778)
						)
						(arc
							(start 0.2794 0.1778)
							(mid 0.249642 0.249642)
							(end 0.1778 0.2794)
						)
					)
					(width 0)
					(fill yes)
				)
			)
		)
	)
	(footprint ""
		(layer "B.Cu")
		(at 103.9114 -86.9442 180)
		(property "Reference" "R567"
			(at 0 0 0)
			(layer "B.SilkS")
			(hide yes)
			(effects
				(font
					(size 1.27 1.27)
				)
				(justify mirror)
			)
		)
		(property "Value" "10KR2F-2-GP"
			(at -0.064008 -3.993896 180)
			(unlocked yes)
			(layer "B.Fab")
			(hide yes)
			(effects
				(font
					(size 1.016 1.016)
					(thickness 0.1524)
				)
				(justify mirror)
			)
		)
		(property "Device Type" "R402H16"
			(at -0.064008 -5.517896 180)
			(unlocked yes)
			(layer "B.Fab")
			(hide yes)
			(effects
				(font
					(size 1.016 1.016)
					(thickness 0.1524)
				)
				(justify mirror)
			)
		)
		(duplicate_pad_numbers_are_jumpers no)
		(fp_line
			(start 0.508 -0.9398)
			(end 0.508 0.9398)
			(stroke
				(width 0.1524)
				(type default)
			)
			(layer "B.SilkS")
		)
		(fp_line
			(start -0.508 -0.9398)
			(end 0.508 -0.9398)
			(stroke
				(width 0.1524)
				(type default)
			)
			(layer "B.SilkS")
		)
		(fp_rect
			(start 0.508 0.9398)
			(end -0.508 -0.9398)
			(stroke
				(width 0)
				(type default)
			)
			(fill no)
			(layer "B.CrtYd")
		)
		(fp_rect
			(start 0.508 0.9398)
			(end -0.508 -0.9398)
			(stroke
				(width 0)
				(type default)
			)
			(fill no)
			(layer "B.Fab")
		)
		(pad "1" smd custom
			(at 0 -0.4445)
			(size 0.1397 0.1397)
			(layers "B.Cu" "B.Mask" "B.Paste")
			(net "SYS_PWR_LED_LS_N")
			(options
				(clearance outline)
				(anchor circle)
			)
			(primitives
				(gr_poly
					(pts
						(arc
							(start -0.1778 0.2794)
							(mid -0.249642 0.249642)
							(end -0.2794 0.1778)
						)
						(arc
							(start -0.2794 -0.1778)
							(mid -0.249642 -0.249642)
							(end -0.1778 -0.2794)
						)
						(arc
							(start 0.1778 -0.2794)
							(mid 0.249642 -0.249642)
							(end 0.2794 -0.1778)
						)
						(arc
							(start 0.2794 0.1778)
							(mid 0.249642 0.249642)
							(end 0.1778 0.2794)
						)
					)
					(width 0)
					(fill yes)
				)
			)
		)
		(pad "2" smd custom
			(at 0 0.4445)
			(size 0.1397 0.1397)
			(layers "B.Cu" "B.Mask" "B.Paste")
			(net "P1V8_E")
			(options
				(clearance outline)
				(anchor circle)
			)
			(primitives
				(gr_poly
					(pts
						(arc
							(start -0.1778 0.2794)
							(mid -0.249642 0.249642)
							(end -0.2794 0.1778)
						)
						(arc
							(start -0.2794 -0.1778)
							(mid -0.249642 -0.249642)
							(end -0.1778 -0.2794)
						)
						(arc
							(start 0.1778 -0.2794)
							(mid 0.249642 -0.249642)
							(end 0.2794 -0.1778)
						)
						(arc
							(start 0.2794 0.1778)
							(mid 0.249642 0.249642)
							(end 0.1778 0.2794)
						)
					)
					(width 0)
					(fill yes)
				)
			)
		)
	)
	(footprint ""
		(layer "B.Cu")
		(at 148.209 -114.173 90)
		(property "Reference" "C674"
			(at 0 0 90)
			(layer "B.SilkS")
			(hide yes)
			(effects
				(font
					(size 1.27 1.27)
				)
				(justify mirror)
			)
		)
		(property "Value" "SCD1U16V2KX-3GP"
			(at -1.1811 -2.7051 90)
			(unlocked yes)
			(layer "B.Fab")
			(hide yes)
			(effects
				(font
					(size 1.016 1.016)
					(thickness 0.1524)
				)
				(justify mirror)
			)
		)
		(property "Device Type" "C402H22"
			(at -1.1811 -4.2291 90)
			(unlocked yes)
			(layer "B.Fab")
			(hide yes)
			(effects
				(font
					(size 1.016 1.016)
					(thickness 0.1524)
				)
				(justify mirror)
			)
		)
		(duplicate_pad_numbers_are_jumpers no)
		(fp_rect
			(start 0.4318 0.9525)
			(end -0.4318 -0.9525)
			(stroke
				(width 0)
				(type default)
			)
			(fill no)
			(layer "B.CrtYd")
		)
		(fp_rect
			(start 0.4318 0.9525)
			(end -0.4318 -0.9525)
			(stroke
				(width 0)
				(type default)
			)
			(fill no)
			(layer "B.Fab")
		)
		(pad "1" smd custom
			(at 0 -0.4445 270)
			(size 0.1524 0.1524)
			(layers "B.Cu" "B.Mask" "B.Paste")
			(net "P1V5_E_RC")
			(options
				(clearance outline)
				(anchor circle)
			)
			(primitives
				(gr_poly
					(pts
						(arc
							(start 0.3048 0.2032)
							(mid 0.275042 0.275042)
							(end 0.2032 0.3048)
						)
						(arc
							(start -0.2032 0.3048)
							(mid -0.275042 0.275042)
							(end -0.3048 0.2032)
						)
						(arc
							(start -0.3048 -0.2032)
							(mid -0.275042 -0.275042)
							(end -0.2032 -0.3048)
						)
						(arc
							(start 0.2032 -0.3048)
							(mid 0.275042 -0.275042)
							(end 0.3048 -0.2032)
						)
					)
					(width 0)
					(fill yes)
				)
			)
		)
		(pad "2" smd custom
			(at 0 0.4445 270)
			(size 0.1524 0.1524)
			(layers "B.Cu" "B.Mask" "B.Paste")
			(net "P1V5_E_LL")
			(options
				(clearance outline)
				(anchor circle)
			)
			(primitives
				(gr_poly
					(pts
						(arc
							(start 0.3048 0.2032)
							(mid 0.275042 0.275042)
							(end 0.2032 0.3048)
						)
						(arc
							(start -0.2032 0.3048)
							(mid -0.275042 0.275042)
							(end -0.3048 0.2032)
						)
						(arc
							(start -0.3048 -0.2032)
							(mid -0.275042 -0.275042)
							(end -0.2032 -0.3048)
						)
						(arc
							(start 0.2032 -0.3048)
							(mid 0.275042 -0.275042)
							(end 0.3048 -0.2032)
						)
					)
					(width 0)
					(fill yes)
				)
			)
		)
	)
	(footprint ""
		(layer "B.Cu")
		(at 104.648 -67.056)
		(property "Reference" "C210"
			(at 0 0 0)
			(layer "B.SilkS")
			(hide yes)
			(effects
				(font
					(size 1.27 1.27)
				)
				(justify mirror)
			)
		)
		(property "Value" "SC1U6D3V1MX-GP"
			(at -1.9177 2.0193 0)
			(unlocked yes)
			(layer "B.Fab")
			(hide yes)
			(effects
				(font
					(size 1.016 1.016)
					(thickness 0.1524)
				)
				(justify mirror)
			)
		)
		(property "Device Type" "C0201H14"
			(at -1.9177 0.4953 0)
			(unlocked yes)
			(layer "B.Fab")
			(hide yes)
			(effects
				(font
					(size 1.016 1.016)
					(thickness 0.1524)
				)
				(justify mirror)
			)
		)
		(duplicate_pad_numbers_are_jumpers no)
		(fp_rect
			(start 0.1524 0.3048)
			(end -0.1524 -0.3048)
			(stroke
				(width 0)
				(type default)
			)
			(fill no)
			(layer "B.CrtYd")
		)
		(fp_poly
			(pts
				(xy 0.2794 0.6477) (xy 0.2794 -0.6477) (xy -0.2794 -0.6477) (xy -0.2794 -0.1905) (xy -0.1524 -0.1905)
				(xy -0.1524 -0.3048) (xy 0.1524 -0.3048) (xy 0.1524 0.3048) (xy -0.1524 0.3048) (xy -0.1524 -0.1778)
				(xy -0.2794 -0.1778) (xy -0.2794 0.6477)
			)
			(stroke
				(width 0)
				(type default)
			)
			(fill no)
			(layer "B.CrtYd")
		)
		(fp_rect
			(start 0.2794 0.6477)
			(end -0.2794 -0.6477)
			(stroke
				(width 0)
				(type default)
			)
			(fill no)
			(layer "B.Fab")
		)
		(pad "1" smd custom
			(at 0 -0.2794 180)
			(size 0.0762 0.0762)
			(layers "B.Cu" "B.Mask" "B.Paste")
			(net "SYSPLL_VDDA09")
			(options
				(clearance outline)
				(anchor circle)
			)
			(primitives
				(gr_poly
					(pts
						(arc
							(start 0.1524 0.127)
							(mid 0.137521 0.162921)
							(end 0.1016 0.1778)
						)
						(arc
							(start -0.1016 0.1778)
							(mid -0.137521 0.162921)
							(end -0.1524 0.127)
						)
						(arc
							(start -0.1524 -0.127)
							(mid -0.137521 -0.162921)
							(end -0.1016 -0.1778)
						)
						(arc
							(start 0.1016 -0.1778)
							(mid 0.137521 -0.162921)
							(end 0.1524 -0.127)
						)
					)
					(width 0)
					(fill yes)
				)
			)
		)
		(pad "2" smd custom
			(at 0 0.2794 180)
			(size 0.0762 0.0762)
			(layers "B.Cu" "B.Mask" "B.Paste")
			(net "GND")
			(options
				(clearance outline)
				(anchor circle)
			)
			(primitives
				(gr_poly
					(pts
						(arc
							(start 0.1524 0.127)
							(mid 0.137521 0.162921)
							(end 0.1016 0.1778)
						)
						(arc
							(start -0.1016 0.1778)
							(mid -0.137521 0.162921)
							(end -0.1524 0.127)
						)
						(arc
							(start -0.1524 -0.127)
							(mid -0.137521 -0.162921)
							(end -0.1016 -0.1778)
						)
						(arc
							(start 0.1016 -0.1778)
							(mid 0.137521 -0.162921)
							(end 0.1524 -0.127)
						)
					)
					(width 0)
					(fill yes)
				)
			)
		)
	)
	(footprint ""
		(layer "B.Cu")
		(at 117.0178 -44.2214 180)
		(property "Reference" "C61"
			(at 0 0 0)
			(layer "B.SilkS")
			(hide yes)
			(effects
				(font
					(size 1.27 1.27)
				)
				(justify mirror)
			)
		)
		(property "Value" "SCD01U16V1KX-GP"
			(at 2.8321 -1.7399 180)
			(unlocked yes)
			(layer "B.Fab")
			(hide yes)
			(effects
				(font
					(size 1.016 1.016)
					(thickness 0.1524)
				)
				(justify mirror)
			)
		)
		(property "Device Type" "C0201H13"
			(at 2.8321 -3.2639 180)
			(unlocked yes)
			(layer "B.Fab")
			(hide yes)
			(effects
				(font
					(size 1.016 1.016)
					(thickness 0.1524)
				)
				(justify mirror)
			)
		)
		(duplicate_pad_numbers_are_jumpers no)
		(fp_rect
			(start 0.2794 0.6477)
			(end -0.2794 -0.6477)
			(stroke
				(width 0)
				(type default)
			)
			(fill no)
			(layer "B.CrtYd")
		)
		(fp_rect
			(start 0.2794 0.6477)
			(end -0.2794 -0.6477)
			(stroke
				(width 0)
				(type default)
			)
			(fill no)
			(layer "B.Fab")
		)
		(pad "1" smd custom
			(at 0 -0.2794)
			(size 0.0762 0.0762)
			(layers "B.Cu" "B.Mask" "B.Paste")
			(net "PHY_DPB_TO_SCC_33_DP")
			(options
				(clearance outline)
				(anchor circle)
			)
			(primitives
				(gr_poly
					(pts
						(arc
							(start 0.1524 0.127)
							(mid 0.137521 0.162921)
							(end 0.1016 0.1778)
						)
						(arc
							(start -0.1016 0.1778)
							(mid -0.137521 0.162921)
							(end -0.1524 0.127)
						)
						(arc
							(start -0.1524 -0.127)
							(mid -0.137521 -0.162921)
							(end -0.1016 -0.1778)
						)
						(arc
							(start 0.1016 -0.1778)
							(mid 0.137521 -0.162921)
							(end 0.1524 -0.127)
						)
					)
					(width 0)
					(fill yes)
				)
			)
		)
		(pad "2" smd custom
			(at 0 0.2794)
			(size 0.0762 0.0762)
			(layers "B.Cu" "B.Mask" "B.Paste")
			(net "PHY_DPB_TO_SCC_C_33_DP")
			(options
				(clearance outline)
				(anchor circle)
			)
			(primitives
				(gr_poly
					(pts
						(arc
							(start 0.1524 0.127)
							(mid 0.137521 0.162921)
							(end 0.1016 0.1778)
						)
						(arc
							(start -0.1016 0.1778)
							(mid -0.137521 0.162921)
							(end -0.1524 0.127)
						)
						(arc
							(start -0.1524 -0.127)
							(mid -0.137521 -0.162921)
							(end -0.1016 -0.1778)
						)
						(arc
							(start 0.1016 -0.1778)
							(mid 0.137521 -0.162921)
							(end 0.1524 -0.127)
						)
					)
					(width 0)
					(fill yes)
				)
			)
		)
	)
	(footprint ""
		(layer "B.Cu")
		(at 181.2798 -28.575)
		(property "Reference" "TP146"
			(at 0 0 0)
			(layer "B.SilkS")
			(hide yes)
			(effects
				(font
					(size 1.27 1.27)
				)
				(justify mirror)
			)
		)
		(property "Value" "TPAD28-2-GP"
			(at 0.0127 -1.6637 0)
			(unlocked yes)
			(layer "B.Fab")
			(hide yes)
			(effects
				(font
					(size 1.016 1.016)
					(thickness 0.1524)
				)
				(justify mirror)
			)
		)
		(property "Device Type" "TPAD28"
			(at 0.0127 -3.1877 0)
			(unlocked yes)
			(layer "B.Fab")
			(hide yes)
			(effects
				(font
					(size 1.016 1.016)
					(thickness 0.1524)
				)
				(justify mirror)
			)
		)
		(duplicate_pad_numbers_are_jumpers no)
		(fp_poly
			(pts
				(arc
					(start 0.3556 0)
					(mid -0.3556 0)
					(end 0.3556 0)
				)
			)
			(stroke
				(width 0)
				(type default)
			)
			(fill no)
			(layer "B.CrtYd")
		)
		(fp_poly
			(pts
				(arc
					(start 0.6096 0)
					(mid -0.6096 0)
					(end 0.6096 0)
				)
			)
			(stroke
				(width 0)
				(type default)
			)
			(fill no)
			(layer "B.Fab")
		)
		(pad "1" smd circle
			(at 0 0 180)
			(size 0.7112 0.7112)
			(layers "B.Cu" "B.Mask" "B.Paste")
			(net "SPARE2")
		)
	)
	(footprint ""
		(layer "B.Cu")
		(at 113.9698 -44.2214 180)
		(property "Reference" "C65"
			(at 0 0 0)
			(layer "B.SilkS")
			(hide yes)
			(effects
				(font
					(size 1.27 1.27)
				)
				(justify mirror)
			)
		)
		(property "Value" "SCD01U16V1KX-GP"
			(at 2.8321 -1.7399 180)
			(unlocked yes)
			(layer "B.Fab")
			(hide yes)
			(effects
				(font
					(size 1.016 1.016)
					(thickness 0.1524)
				)
				(justify mirror)
			)
		)
		(property "Device Type" "C0201H13"
			(at 2.8321 -3.2639 180)
			(unlocked yes)
			(layer "B.Fab")
			(hide yes)
			(effects
				(font
					(size 1.016 1.016)
					(thickness 0.1524)
				)
				(justify mirror)
			)
		)
		(duplicate_pad_numbers_are_jumpers no)
		(fp_rect
			(start 0.2794 0.6477)
			(end -0.2794 -0.6477)
			(stroke
				(width 0)
				(type default)
			)
			(fill no)
			(layer "B.CrtYd")
		)
		(fp_rect
			(start 0.2794 0.6477)
			(end -0.2794 -0.6477)
			(stroke
				(width 0)
				(type default)
			)
			(fill no)
			(layer "B.Fab")
		)
		(pad "1" smd custom
			(at 0 -0.2794)
			(size 0.0762 0.0762)
			(layers "B.Cu" "B.Mask" "B.Paste")
			(net "PHY_DPB_TO_SCC_27_DP")
			(options
				(clearance outline)
				(anchor circle)
			)
			(primitives
				(gr_poly
					(pts
						(arc
							(start 0.1524 0.127)
							(mid 0.137521 0.162921)
							(end 0.1016 0.1778)
						)
						(arc
							(start -0.1016 0.1778)
							(mid -0.137521 0.162921)
							(end -0.1524 0.127)
						)
						(arc
							(start -0.1524 -0.127)
							(mid -0.137521 -0.162921)
							(end -0.1016 -0.1778)
						)
						(arc
							(start 0.1016 -0.1778)
							(mid 0.137521 -0.162921)
							(end 0.1524 -0.127)
						)
					)
					(width 0)
					(fill yes)
				)
			)
		)
		(pad "2" smd custom
			(at 0 0.2794)
			(size 0.0762 0.0762)
			(layers "B.Cu" "B.Mask" "B.Paste")
			(net "PHY_DPB_TO_SCC_C_27_DP")
			(options
				(clearance outline)
				(anchor circle)
			)
			(primitives
				(gr_poly
					(pts
						(arc
							(start 0.1524 0.127)
							(mid 0.137521 0.162921)
							(end 0.1016 0.1778)
						)
						(arc
							(start -0.1016 0.1778)
							(mid -0.137521 0.162921)
							(end -0.1524 0.127)
						)
						(arc
							(start -0.1524 -0.127)
							(mid -0.137521 -0.162921)
							(end -0.1016 -0.1778)
						)
						(arc
							(start 0.1016 -0.1778)
							(mid 0.137521 -0.162921)
							(end 0.1524 -0.127)
						)
					)
					(width 0)
					(fill yes)
				)
			)
		)
	)
	(footprint ""
		(layer "B.Cu")
		(at 141.605 -87.2109)
		(property "Reference" "TP20"
			(at 0 0 0)
			(layer "B.SilkS")
			(hide yes)
			(effects
				(font
					(size 1.27 1.27)
				)
				(justify mirror)
			)
		)
		(property "Value" "TPAD28-2-GP"
			(at 0.0127 -1.6637 0)
			(unlocked yes)
			(layer "B.Fab")
			(hide yes)
			(effects
				(font
					(size 1.016 1.016)
					(thickness 0.1524)
				)
				(justify mirror)
			)
		)
		(property "Device Type" "TPAD28"
			(at 0.0127 -3.1877 0)
			(unlocked yes)
			(layer "B.Fab")
			(hide yes)
			(effects
				(font
					(size 1.016 1.016)
					(thickness 0.1524)
				)
				(justify mirror)
			)
		)
		(duplicate_pad_numbers_are_jumpers no)
		(fp_poly
			(pts
				(arc
					(start 0.3556 0)
					(mid -0.3556 0)
					(end 0.3556 0)
				)
			)
			(stroke
				(width 0)
				(type default)
			)
			(fill no)
			(layer "B.CrtYd")
		)
		(fp_poly
			(pts
				(arc
					(start 0.6096 0)
					(mid -0.6096 0)
					(end 0.6096 0)
				)
			)
			(stroke
				(width 0)
				(type default)
			)
			(fill no)
			(layer "B.Fab")
		)
		(pad "1" smd circle
			(at 0 0 180)
			(size 0.7112 0.7112)
			(layers "B.Cu" "B.Mask" "B.Paste")
			(net "EXP_I2C_SDA9")
		)
	)
	(footprint ""
		(layer "B.Cu")
		(at 117.3353 -64.4779)
		(property "Reference" "C160"
			(at 0 0 0)
			(layer "B.SilkS")
			(hide yes)
			(effects
				(font
					(size 1.27 1.27)
				)
				(justify mirror)
			)
		)
		(property "Value" "SCD1U6D3V1KX-GP"
			(at 2.8321 -1.7399 0)
			(unlocked yes)
			(layer "B.Fab")
			(hide yes)
			(effects
				(font
					(size 1.016 1.016)
					(thickness 0.1524)
				)
				(justify mirror)
			)
		)
		(property "Device Type" "C0201H13"
			(at 2.8321 -3.2639 0)
			(unlocked yes)
			(layer "B.Fab")
			(hide yes)
			(effects
				(font
					(size 1.016 1.016)
					(thickness 0.1524)
				)
				(justify mirror)
			)
		)
		(duplicate_pad_numbers_are_jumpers no)
		(fp_rect
			(start 0.2794 0.6477)
			(end -0.2794 -0.6477)
			(stroke
				(width 0)
				(type default)
			)
			(fill no)
			(layer "B.CrtYd")
		)
		(fp_rect
			(start 0.2794 0.6477)
			(end -0.2794 -0.6477)
			(stroke
				(width 0)
				(type default)
			)
			(fill no)
			(layer "B.Fab")
		)
		(pad "1" smd custom
			(at 0 -0.2794 180)
			(size 0.0762 0.0762)
			(layers "B.Cu" "B.Mask" "B.Paste")
			(net "P0V9")
			(options
				(clearance outline)
				(anchor circle)
			)
			(primitives
				(gr_poly
					(pts
						(arc
							(start 0.1524 0.127)
							(mid 0.137521 0.162921)
							(end 0.1016 0.1778)
						)
						(arc
							(start -0.1016 0.1778)
							(mid -0.137521 0.162921)
							(end -0.1524 0.127)
						)
						(arc
							(start -0.1524 -0.127)
							(mid -0.137521 -0.162921)
							(end -0.1016 -0.1778)
						)
						(arc
							(start 0.1016 -0.1778)
							(mid 0.137521 -0.162921)
							(end 0.1524 -0.127)
						)
					)
					(width 0)
					(fill yes)
				)
			)
		)
		(pad "2" smd custom
			(at 0 0.2794 180)
			(size 0.0762 0.0762)
			(layers "B.Cu" "B.Mask" "B.Paste")
			(net "GND")
			(options
				(clearance outline)
				(anchor circle)
			)
			(primitives
				(gr_poly
					(pts
						(arc
							(start 0.1524 0.127)
							(mid 0.137521 0.162921)
							(end 0.1016 0.1778)
						)
						(arc
							(start -0.1016 0.1778)
							(mid -0.137521 0.162921)
							(end -0.1524 0.127)
						)
						(arc
							(start -0.1524 -0.127)
							(mid -0.137521 -0.162921)
							(end -0.1016 -0.1778)
						)
						(arc
							(start 0.1016 -0.1778)
							(mid 0.137521 -0.162921)
							(end 0.1524 -0.127)
						)
					)
					(width 0)
					(fill yes)
				)
			)
		)
	)
	(footprint ""
		(layer "B.Cu")
		(at 173.7741 -42.90822 -90)
		(property "Reference" "C427"
			(at 0 0 90)
			(layer "B.SilkS")
			(hide yes)
			(effects
				(font
					(size 1.27 1.27)
				)
				(justify mirror)
			)
		)
		(property "Value" "SCD1U6D3V1KX-GP"
			(at 2.8321 -1.7399 270)
			(unlocked yes)
			(layer "B.Fab")
			(hide yes)
			(effects
				(font
					(size 1.016 1.016)
					(thickness 0.1524)
				)
				(justify mirror)
			)
		)
		(property "Device Type" "C0201H13"
			(at 2.8321 -3.2639 270)
			(unlocked yes)
			(layer "B.Fab")
			(hide yes)
			(effects
				(font
					(size 1.016 1.016)
					(thickness 0.1524)
				)
				(justify mirror)
			)
		)
		(duplicate_pad_numbers_are_jumpers no)
		(fp_rect
			(start 0.2794 0.6477)
			(end -0.2794 -0.6477)
			(stroke
				(width 0)
				(type default)
			)
			(fill no)
			(layer "B.CrtYd")
		)
		(fp_rect
			(start 0.2794 0.6477)
			(end -0.2794 -0.6477)
			(stroke
				(width 0)
				(type default)
			)
			(fill no)
			(layer "B.Fab")
		)
		(pad "1" smd custom
			(at 0 -0.2794 90)
			(size 0.0762 0.0762)
			(layers "B.Cu" "B.Mask" "B.Paste")
			(net "P0V975")
			(options
				(clearance outline)
				(anchor circle)
			)
			(primitives
				(gr_poly
					(pts
						(arc
							(start 0.1524 0.127)
							(mid 0.137521 0.162921)
							(end 0.1016 0.1778)
						)
						(arc
							(start -0.1016 0.1778)
							(mid -0.137521 0.162921)
							(end -0.1524 0.127)
						)
						(arc
							(start -0.1524 -0.127)
							(mid -0.137521 -0.162921)
							(end -0.1016 -0.1778)
						)
						(arc
							(start 0.1016 -0.1778)
							(mid 0.137521 -0.162921)
							(end 0.1524 -0.127)
						)
					)
					(width 0)
					(fill yes)
				)
			)
		)
		(pad "2" smd custom
			(at 0 0.2794 90)
			(size 0.0762 0.0762)
			(layers "B.Cu" "B.Mask" "B.Paste")
			(net "GND")
			(options
				(clearance outline)
				(anchor circle)
			)
			(primitives
				(gr_poly
					(pts
						(arc
							(start 0.1524 0.127)
							(mid 0.137521 0.162921)
							(end 0.1016 0.1778)
						)
						(arc
							(start -0.1016 0.1778)
							(mid -0.137521 0.162921)
							(end -0.1524 0.127)
						)
						(arc
							(start -0.1524 -0.127)
							(mid -0.137521 -0.162921)
							(end -0.1016 -0.1778)
						)
						(arc
							(start 0.1016 -0.1778)
							(mid 0.137521 -0.162921)
							(end 0.1524 -0.127)
						)
					)
					(width 0)
					(fill yes)
				)
			)
		)
	)
	(footprint ""
		(layer "B.Cu")
		(at 122.4788 -70.5104 -90)
		(property "Reference" "C280"
			(at 0 0 90)
			(layer "B.SilkS")
			(hide yes)
			(effects
				(font
					(size 1.27 1.27)
				)
				(justify mirror)
			)
		)
		(property "Value" "SCD1U6D3V1KX-GP"
			(at 2.8321 -1.7399 270)
			(unlocked yes)
			(layer "B.Fab")
			(hide yes)
			(effects
				(font
					(size 1.016 1.016)
					(thickness 0.1524)
				)
				(justify mirror)
			)
		)
		(property "Device Type" "C0201H13"
			(at 2.8321 -3.2639 270)
			(unlocked yes)
			(layer "B.Fab")
			(hide yes)
			(effects
				(font
					(size 1.016 1.016)
					(thickness 0.1524)
				)
				(justify mirror)
			)
		)
		(duplicate_pad_numbers_are_jumpers no)
		(fp_rect
			(start 0.2794 0.6477)
			(end -0.2794 -0.6477)
			(stroke
				(width 0)
				(type default)
			)
			(fill no)
			(layer "B.CrtYd")
		)
		(fp_rect
			(start 0.2794 0.6477)
			(end -0.2794 -0.6477)
			(stroke
				(width 0)
				(type default)
			)
			(fill no)
			(layer "B.Fab")
		)
		(pad "1" smd custom
			(at 0 -0.2794 90)
			(size 0.0762 0.0762)
			(layers "B.Cu" "B.Mask" "B.Paste")
			(net "GB_VDDA")
			(options
				(clearance outline)
				(anchor circle)
			)
			(primitives
				(gr_poly
					(pts
						(arc
							(start 0.1524 0.127)
							(mid 0.137521 0.162921)
							(end 0.1016 0.1778)
						)
						(arc
							(start -0.1016 0.1778)
							(mid -0.137521 0.162921)
							(end -0.1524 0.127)
						)
						(arc
							(start -0.1524 -0.127)
							(mid -0.137521 -0.162921)
							(end -0.1016 -0.1778)
						)
						(arc
							(start 0.1016 -0.1778)
							(mid 0.137521 -0.162921)
							(end 0.1524 -0.127)
						)
					)
					(width 0)
					(fill yes)
				)
			)
		)
		(pad "2" smd custom
			(at 0 0.2794 90)
			(size 0.0762 0.0762)
			(layers "B.Cu" "B.Mask" "B.Paste")
			(net "GND")
			(options
				(clearance outline)
				(anchor circle)
			)
			(primitives
				(gr_poly
					(pts
						(arc
							(start 0.1524 0.127)
							(mid 0.137521 0.162921)
							(end 0.1016 0.1778)
						)
						(arc
							(start -0.1016 0.1778)
							(mid -0.137521 0.162921)
							(end -0.1524 0.127)
						)
						(arc
							(start -0.1524 -0.127)
							(mid -0.137521 -0.162921)
							(end -0.1016 -0.1778)
						)
						(arc
							(start 0.1016 -0.1778)
							(mid 0.137521 -0.162921)
							(end 0.1524 -0.127)
						)
					)
					(width 0)
					(fill yes)
				)
			)
		)
	)
	(footprint ""
		(layer "B.Cu")
		(at 106.5022 -65.786 180)
		(property "Reference" "C207"
			(at 0 0 0)
			(layer "B.SilkS")
			(hide yes)
			(effects
				(font
					(size 1.27 1.27)
				)
				(justify mirror)
			)
		)
		(property "Value" "SCD1U6D3V1KX-GP"
			(at 2.8321 -1.7399 180)
			(unlocked yes)
			(layer "B.Fab")
			(hide yes)
			(effects
				(font
					(size 1.016 1.016)
					(thickness 0.1524)
				)
				(justify mirror)
			)
		)
		(property "Device Type" "C0201H13"
			(at 2.8321 -3.2639 180)
			(unlocked yes)
			(layer "B.Fab")
			(hide yes)
			(effects
				(font
					(size 1.016 1.016)
					(thickness 0.1524)
				)
				(justify mirror)
			)
		)
		(duplicate_pad_numbers_are_jumpers no)
		(fp_rect
			(start 0.2794 0.6477)
			(end -0.2794 -0.6477)
			(stroke
				(width 0)
				(type default)
			)
			(fill no)
			(layer "B.CrtYd")
		)
		(fp_rect
			(start 0.2794 0.6477)
			(end -0.2794 -0.6477)
			(stroke
				(width 0)
				(type default)
			)
			(fill no)
			(layer "B.Fab")
		)
		(pad "1" smd custom
			(at 0 -0.2794)
			(size 0.0762 0.0762)
			(layers "B.Cu" "B.Mask" "B.Paste")
			(net "XTAL_VDDA09")
			(options
				(clearance outline)
				(anchor circle)
			)
			(primitives
				(gr_poly
					(pts
						(arc
							(start 0.1524 0.127)
							(mid 0.137521 0.162921)
							(end 0.1016 0.1778)
						)
						(arc
							(start -0.1016 0.1778)
							(mid -0.137521 0.162921)
							(end -0.1524 0.127)
						)
						(arc
							(start -0.1524 -0.127)
							(mid -0.137521 -0.162921)
							(end -0.1016 -0.1778)
						)
						(arc
							(start 0.1016 -0.1778)
							(mid 0.137521 -0.162921)
							(end 0.1524 -0.127)
						)
					)
					(width 0)
					(fill yes)
				)
			)
		)
		(pad "2" smd custom
			(at 0 0.2794)
			(size 0.0762 0.0762)
			(layers "B.Cu" "B.Mask" "B.Paste")
			(net "GND")
			(options
				(clearance outline)
				(anchor circle)
			)
			(primitives
				(gr_poly
					(pts
						(arc
							(start 0.1524 0.127)
							(mid 0.137521 0.162921)
							(end 0.1016 0.1778)
						)
						(arc
							(start -0.1016 0.1778)
							(mid -0.137521 0.162921)
							(end -0.1524 0.127)
						)
						(arc
							(start -0.1524 -0.127)
							(mid -0.137521 -0.162921)
							(end -0.1016 -0.1778)
						)
						(arc
							(start 0.1016 -0.1778)
							(mid 0.137521 -0.162921)
							(end 0.1524 -0.127)
						)
					)
					(width 0)
					(fill yes)
				)
			)
		)
	)
	(footprint ""
		(layer "B.Cu")
		(at 38.592252 -107.66298 90)
		(property "Reference" "C511"
			(at 0 0 90)
			(layer "B.SilkS")
			(hide yes)
			(effects
				(font
					(size 1.27 1.27)
				)
				(justify mirror)
			)
		)
		(property "Value" "SC4D7U25V5KX-1-GP"
			(at 0.0762 -6.1214 90)
			(unlocked yes)
			(layer "B.Fab")
			(hide yes)
			(effects
				(font
					(size 1.016 1.016)
					(thickness 0.1524)
				)
				(justify mirror)
			)
		)
		(property "Device Type" "C805H58"
			(at 0.0762 -8.1534 90)
			(unlocked yes)
			(layer "B.Fab")
			(hide yes)
			(effects
				(font
					(size 1.016 1.016)
					(thickness 0.1524)
				)
				(justify mirror)
			)
		)
		(duplicate_pad_numbers_are_jumpers no)
		(fp_line
			(start -0.635 0)
			(end 0.635 0)
			(stroke
				(width 0.508)
				(type default)
			)
			(layer "B.SilkS")
		)
		(fp_rect
			(start 0.9652 1.778)
			(end -0.9652 -1.778)
			(stroke
				(width 0)
				(type default)
			)
			(fill no)
			(layer "B.CrtYd")
		)
		(fp_poly
			(pts
				(xy 0.9652 -1.778) (xy -0.9652 -1.778) (xy -0.9652 1.778) (xy 0.9652 1.778)
			)
			(stroke
				(width 0)
				(type default)
			)
			(fill no)
			(layer "B.Fab")
		)
		(pad "1" smd rect
			(at 0 -0.9652 270)
			(size 1.397 1.143)
			(layers "B.Cu" "B.Mask" "B.Paste")
			(net "P5V")
		)
		(pad "2" smd rect
			(at 0 0.9652 270)
			(size 1.397 1.143)
			(layers "B.Cu" "B.Mask" "B.Paste")
			(net "GND")
		)
	)
	(footprint ""
		(layer "B.Cu")
		(at 176.202848 -41.87571 90)
		(property "Reference" "C416"
			(at 0 0 90)
			(layer "B.SilkS")
			(hide yes)
			(effects
				(font
					(size 1.27 1.27)
				)
				(justify mirror)
			)
		)
		(property "Value" "SC1U6D3V1MX-GP"
			(at -1.9177 2.0193 90)
			(unlocked yes)
			(layer "B.Fab")
			(hide yes)
			(effects
				(font
					(size 1.016 1.016)
					(thickness 0.1524)
				)
				(justify mirror)
			)
		)
		(property "Device Type" "C0201H14"
			(at -1.9177 0.4953 90)
			(unlocked yes)
			(layer "B.Fab")
			(hide yes)
			(effects
				(font
					(size 1.016 1.016)
					(thickness 0.1524)
				)
				(justify mirror)
			)
		)
		(duplicate_pad_numbers_are_jumpers no)
		(fp_rect
			(start 0.1524 0.3048)
			(end -0.1524 -0.3048)
			(stroke
				(width 0)
				(type default)
			)
			(fill no)
			(layer "B.CrtYd")
		)
		(fp_poly
			(pts
				(xy 0.2794 0.6477) (xy 0.2794 -0.6477) (xy -0.2794 -0.6477) (xy -0.2794 -0.1905) (xy -0.1524 -0.1905)
				(xy -0.1524 -0.3048) (xy 0.1524 -0.3048) (xy 0.1524 0.3048) (xy -0.1524 0.3048) (xy -0.1524 -0.1778)
				(xy -0.2794 -0.1778) (xy -0.2794 0.6477)
			)
			(stroke
				(width 0)
				(type default)
			)
			(fill no)
			(layer "B.CrtYd")
		)
		(fp_rect
			(start 0.2794 0.6477)
			(end -0.2794 -0.6477)
			(stroke
				(width 0)
				(type default)
			)
			(fill no)
			(layer "B.Fab")
		)
		(pad "1" smd custom
			(at 0 -0.2794 270)
			(size 0.0762 0.0762)
			(layers "B.Cu" "B.Mask" "B.Paste")
			(net "P0V975")
			(options
				(clearance outline)
				(anchor circle)
			)
			(primitives
				(gr_poly
					(pts
						(arc
							(start 0.1524 0.127)
							(mid 0.137521 0.162921)
							(end 0.1016 0.1778)
						)
						(arc
							(start -0.1016 0.1778)
							(mid -0.137521 0.162921)
							(end -0.1524 0.127)
						)
						(arc
							(start -0.1524 -0.127)
							(mid -0.137521 -0.162921)
							(end -0.1016 -0.1778)
						)
						(arc
							(start 0.1016 -0.1778)
							(mid 0.137521 -0.162921)
							(end 0.1524 -0.127)
						)
					)
					(width 0)
					(fill yes)
				)
			)
		)
		(pad "2" smd custom
			(at 0 0.2794 270)
			(size 0.0762 0.0762)
			(layers "B.Cu" "B.Mask" "B.Paste")
			(net "GND")
			(options
				(clearance outline)
				(anchor circle)
			)
			(primitives
				(gr_poly
					(pts
						(arc
							(start 0.1524 0.127)
							(mid 0.137521 0.162921)
							(end 0.1016 0.1778)
						)
						(arc
							(start -0.1016 0.1778)
							(mid -0.137521 0.162921)
							(end -0.1524 0.127)
						)
						(arc
							(start -0.1524 -0.127)
							(mid -0.137521 -0.162921)
							(end -0.1016 -0.1778)
						)
						(arc
							(start 0.1016 -0.1778)
							(mid 0.137521 -0.162921)
							(end 0.1524 -0.127)
						)
					)
					(width 0)
					(fill yes)
				)
			)
		)
	)
	(footprint ""
		(layer "B.Cu")
		(at 115.3541 -57.4802)
		(property "Reference" "C266"
			(at 0 0 0)
			(layer "B.SilkS")
			(hide yes)
			(effects
				(font
					(size 1.27 1.27)
				)
				(justify mirror)
			)
		)
		(property "Value" "SCD1U6D3V1KX-GP"
			(at 2.8321 -1.7399 0)
			(unlocked yes)
			(layer "B.Fab")
			(hide yes)
			(effects
				(font
					(size 1.016 1.016)
					(thickness 0.1524)
				)
				(justify mirror)
			)
		)
		(property "Device Type" "C0201H13"
			(at 2.8321 -3.2639 0)
			(unlocked yes)
			(layer "B.Fab")
			(hide yes)
			(effects
				(font
					(size 1.016 1.016)
					(thickness 0.1524)
				)
				(justify mirror)
			)
		)
		(duplicate_pad_numbers_are_jumpers no)
		(fp_rect
			(start 0.2794 0.6477)
			(end -0.2794 -0.6477)
			(stroke
				(width 0)
				(type default)
			)
			(fill no)
			(layer "B.CrtYd")
		)
		(fp_rect
			(start 0.2794 0.6477)
			(end -0.2794 -0.6477)
			(stroke
				(width 0)
				(type default)
			)
			(fill no)
			(layer "B.Fab")
		)
		(pad "1" smd custom
			(at 0 -0.2794 180)
			(size 0.0762 0.0762)
			(layers "B.Cu" "B.Mask" "B.Paste")
			(net "GB_VDDA")
			(options
				(clearance outline)
				(anchor circle)
			)
			(primitives
				(gr_poly
					(pts
						(arc
							(start 0.1524 0.127)
							(mid 0.137521 0.162921)
							(end 0.1016 0.1778)
						)
						(arc
							(start -0.1016 0.1778)
							(mid -0.137521 0.162921)
							(end -0.1524 0.127)
						)
						(arc
							(start -0.1524 -0.127)
							(mid -0.137521 -0.162921)
							(end -0.1016 -0.1778)
						)
						(arc
							(start 0.1016 -0.1778)
							(mid 0.137521 -0.162921)
							(end 0.1524 -0.127)
						)
					)
					(width 0)
					(fill yes)
				)
			)
		)
		(pad "2" smd custom
			(at 0 0.2794 180)
			(size 0.0762 0.0762)
			(layers "B.Cu" "B.Mask" "B.Paste")
			(net "GND")
			(options
				(clearance outline)
				(anchor circle)
			)
			(primitives
				(gr_poly
					(pts
						(arc
							(start 0.1524 0.127)
							(mid 0.137521 0.162921)
							(end 0.1016 0.1778)
						)
						(arc
							(start -0.1016 0.1778)
							(mid -0.137521 0.162921)
							(end -0.1524 0.127)
						)
						(arc
							(start -0.1524 -0.127)
							(mid -0.137521 -0.162921)
							(end -0.1016 -0.1778)
						)
						(arc
							(start 0.1016 -0.1778)
							(mid 0.137521 -0.162921)
							(end 0.1524 -0.127)
						)
					)
					(width 0)
					(fill yes)
				)
			)
		)
	)
	(footprint ""
		(layer "B.Cu")
		(at 172.08627 -28.736798 180)
		(property "Reference" "C389"
			(at 0 0 0)
			(layer "B.SilkS")
			(hide yes)
			(effects
				(font
					(size 1.27 1.27)
				)
				(justify mirror)
			)
		)
		(property "Value" "SCD1U6D3V1KX-GP"
			(at 2.8321 -1.7399 180)
			(unlocked yes)
			(layer "B.Fab")
			(hide yes)
			(effects
				(font
					(size 1.016 1.016)
					(thickness 0.1524)
				)
				(justify mirror)
			)
		)
		(property "Device Type" "C0201H13"
			(at 2.8321 -3.2639 180)
			(unlocked yes)
			(layer "B.Fab")
			(hide yes)
			(effects
				(font
					(size 1.016 1.016)
					(thickness 0.1524)
				)
				(justify mirror)
			)
		)
		(duplicate_pad_numbers_are_jumpers no)
		(fp_rect
			(start 0.2794 0.6477)
			(end -0.2794 -0.6477)
			(stroke
				(width 0)
				(type default)
			)
			(fill no)
			(layer "B.CrtYd")
		)
		(fp_rect
			(start 0.2794 0.6477)
			(end -0.2794 -0.6477)
			(stroke
				(width 0)
				(type default)
			)
			(fill no)
			(layer "B.Fab")
		)
		(pad "1" smd custom
			(at 0 -0.2794)
			(size 0.0762 0.0762)
			(layers "B.Cu" "B.Mask" "B.Paste")
			(net "PCE_AVDD")
			(options
				(clearance outline)
				(anchor circle)
			)
			(primitives
				(gr_poly
					(pts
						(arc
							(start 0.1524 0.127)
							(mid 0.137521 0.162921)
							(end 0.1016 0.1778)
						)
						(arc
							(start -0.1016 0.1778)
							(mid -0.137521 0.162921)
							(end -0.1524 0.127)
						)
						(arc
							(start -0.1524 -0.127)
							(mid -0.137521 -0.162921)
							(end -0.1016 -0.1778)
						)
						(arc
							(start 0.1016 -0.1778)
							(mid 0.137521 -0.162921)
							(end 0.1524 -0.127)
						)
					)
					(width 0)
					(fill yes)
				)
			)
		)
		(pad "2" smd custom
			(at 0 0.2794)
			(size 0.0762 0.0762)
			(layers "B.Cu" "B.Mask" "B.Paste")
			(net "GND")
			(options
				(clearance outline)
				(anchor circle)
			)
			(primitives
				(gr_poly
					(pts
						(arc
							(start 0.1524 0.127)
							(mid 0.137521 0.162921)
							(end 0.1016 0.1778)
						)
						(arc
							(start -0.1016 0.1778)
							(mid -0.137521 0.162921)
							(end -0.1524 0.127)
						)
						(arc
							(start -0.1524 -0.127)
							(mid -0.137521 -0.162921)
							(end -0.1016 -0.1778)
						)
						(arc
							(start 0.1016 -0.1778)
							(mid 0.137521 -0.162921)
							(end 0.1524 -0.127)
						)
					)
					(width 0)
					(fill yes)
				)
			)
		)
	)
	(footprint ""
		(layer "B.Cu")
		(at 122.474228 -67.35953 -90)
		(property "Reference" "C587"
			(at 0 0 90)
			(layer "B.SilkS")
			(hide yes)
			(effects
				(font
					(size 1.27 1.27)
				)
				(justify mirror)
			)
		)
		(property "Value" "SCD1U6D3V1KX-GP"
			(at 2.8321 -1.7399 270)
			(unlocked yes)
			(layer "B.Fab")
			(hide yes)
			(effects
				(font
					(size 1.016 1.016)
					(thickness 0.1524)
				)
				(justify mirror)
			)
		)
		(property "Device Type" "C0201H13"
			(at 2.8321 -3.2639 270)
			(unlocked yes)
			(layer "B.Fab")
			(hide yes)
			(effects
				(font
					(size 1.016 1.016)
					(thickness 0.1524)
				)
				(justify mirror)
			)
		)
		(duplicate_pad_numbers_are_jumpers no)
		(fp_rect
			(start 0.2794 0.6477)
			(end -0.2794 -0.6477)
			(stroke
				(width 0)
				(type default)
			)
			(fill no)
			(layer "B.CrtYd")
		)
		(fp_rect
			(start 0.2794 0.6477)
			(end -0.2794 -0.6477)
			(stroke
				(width 0)
				(type default)
			)
			(fill no)
			(layer "B.Fab")
		)
		(pad "1" smd custom
			(at 0 -0.2794 90)
			(size 0.0762 0.0762)
			(layers "B.Cu" "B.Mask" "B.Paste")
			(net "GB_VDDA")
			(options
				(clearance outline)
				(anchor circle)
			)
			(primitives
				(gr_poly
					(pts
						(arc
							(start 0.1524 0.127)
							(mid 0.137521 0.162921)
							(end 0.1016 0.1778)
						)
						(arc
							(start -0.1016 0.1778)
							(mid -0.137521 0.162921)
							(end -0.1524 0.127)
						)
						(arc
							(start -0.1524 -0.127)
							(mid -0.137521 -0.162921)
							(end -0.1016 -0.1778)
						)
						(arc
							(start 0.1016 -0.1778)
							(mid 0.137521 -0.162921)
							(end 0.1524 -0.127)
						)
					)
					(width 0)
					(fill yes)
				)
			)
		)
		(pad "2" smd custom
			(at 0 0.2794 90)
			(size 0.0762 0.0762)
			(layers "B.Cu" "B.Mask" "B.Paste")
			(net "GND")
			(options
				(clearance outline)
				(anchor circle)
			)
			(primitives
				(gr_poly
					(pts
						(arc
							(start 0.1524 0.127)
							(mid 0.137521 0.162921)
							(end 0.1016 0.1778)
						)
						(arc
							(start -0.1016 0.1778)
							(mid -0.137521 0.162921)
							(end -0.1524 0.127)
						)
						(arc
							(start -0.1524 -0.127)
							(mid -0.137521 -0.162921)
							(end -0.1016 -0.1778)
						)
						(arc
							(start 0.1016 -0.1778)
							(mid 0.137521 -0.162921)
							(end 0.1524 -0.127)
						)
					)
					(width 0)
					(fill yes)
				)
			)
		)
	)
	(footprint ""
		(layer "B.Cu")
		(at 161.798 -50.419)
		(property "Reference" "TP92"
			(at 0 0 0)
			(layer "B.SilkS")
			(hide yes)
			(effects
				(font
					(size 1.27 1.27)
				)
				(justify mirror)
			)
		)
		(property "Value" "TPAD28-2-GP"
			(at 0.0127 -1.6637 0)
			(unlocked yes)
			(layer "B.Fab")
			(hide yes)
			(effects
				(font
					(size 1.016 1.016)
					(thickness 0.1524)
				)
				(justify mirror)
			)
		)
		(property "Device Type" "TPAD28"
			(at 0.0127 -3.1877 0)
			(unlocked yes)
			(layer "B.Fab")
			(hide yes)
			(effects
				(font
					(size 1.016 1.016)
					(thickness 0.1524)
				)
				(justify mirror)
			)
		)
		(duplicate_pad_numbers_are_jumpers no)
		(fp_poly
			(pts
				(arc
					(start 0.3556 0)
					(mid -0.3556 0)
					(end 0.3556 0)
				)
			)
			(stroke
				(width 0)
				(type default)
			)
			(fill no)
			(layer "B.CrtYd")
		)
		(fp_poly
			(pts
				(arc
					(start 0.6096 0)
					(mid -0.6096 0)
					(end 0.6096 0)
				)
			)
			(stroke
				(width 0)
				(type default)
			)
			(fill no)
			(layer "B.Fab")
		)
		(pad "1" smd circle
			(at 0 0 180)
			(size 0.7112 0.7112)
			(layers "B.Cu" "B.Mask" "B.Paste")
			(net "SIO_DOUT_1")
		)
	)
	(footprint ""
		(layer "B.Cu")
		(at 187.5028 -29.8704 90)
		(property "Reference" "TP78"
			(at 0 0 90)
			(layer "B.SilkS")
			(hide yes)
			(effects
				(font
					(size 1.27 1.27)
				)
				(justify mirror)
			)
		)
		(property "Value" "TPAD28-2-GP"
			(at 0.0127 -1.6637 90)
			(unlocked yes)
			(layer "B.Fab")
			(hide yes)
			(effects
				(font
					(size 1.016 1.016)
					(thickness 0.1524)
				)
				(justify mirror)
			)
		)
		(property "Device Type" "TPAD28"
			(at 0.0127 -3.1877 90)
			(unlocked yes)
			(layer "B.Fab")
			(hide yes)
			(effects
				(font
					(size 1.016 1.016)
					(thickness 0.1524)
				)
				(justify mirror)
			)
		)
		(duplicate_pad_numbers_are_jumpers no)
		(fp_poly
			(pts
				(arc
					(start 0 0.3556)
					(mid 0 -0.3556)
					(end 0 0.3556)
				)
			)
			(stroke
				(width 0)
				(type default)
			)
			(fill no)
			(layer "B.CrtYd")
		)
		(fp_poly
			(pts
				(arc
					(start 0 0.6096)
					(mid 0 -0.6096)
					(end 0 0.6096)
				)
			)
			(stroke
				(width 0)
				(type default)
			)
			(fill no)
			(layer "B.Fab")
		)
		(pad "1" smd circle
			(at 0 0 270)
			(size 0.7112 0.7112)
			(layers "B.Cu" "B.Mask" "B.Paste")
			(net "IOC_GPIO_25")
		)
	)
	(footprint ""
		(layer "B.Cu")
		(at 157.867604 -62.090808 90)
		(property "Reference" "C360"
			(at 0 0 90)
			(layer "B.SilkS")
			(hide yes)
			(effects
				(font
					(size 1.27 1.27)
				)
				(justify mirror)
			)
		)
		(property "Value" "SC10U6D3V5KX-4GP"
			(at 0.0762 -6.1214 90)
			(unlocked yes)
			(layer "B.Fab")
			(hide yes)
			(effects
				(font
					(size 1.016 1.016)
					(thickness 0.1524)
				)
				(justify mirror)
			)
		)
		(property "Device Type" "C805H58"
			(at 0.0762 -8.1534 90)
			(unlocked yes)
			(layer "B.Fab")
			(hide yes)
			(effects
				(font
					(size 1.016 1.016)
					(thickness 0.1524)
				)
				(justify mirror)
			)
		)
		(duplicate_pad_numbers_are_jumpers no)
		(fp_line
			(start -0.635 0)
			(end 0.635 0)
			(stroke
				(width 0.508)
				(type default)
			)
			(layer "B.SilkS")
		)
		(fp_rect
			(start 0.9652 1.778)
			(end -0.9652 -1.778)
			(stroke
				(width 0)
				(type default)
			)
			(fill no)
			(layer "B.CrtYd")
		)
		(fp_poly
			(pts
				(xy 0.9652 -1.778) (xy -0.9652 -1.778) (xy -0.9652 1.778) (xy 0.9652 1.778)
			)
			(stroke
				(width 0)
				(type default)
			)
			(fill no)
			(layer "B.Fab")
		)
		(pad "1" smd rect
			(at 0 -0.9652 270)
			(size 1.397 1.143)
			(layers "B.Cu" "B.Mask" "B.Paste")
			(net "SHELL_PLL_VDD")
		)
		(pad "2" smd rect
			(at 0 0.9652 270)
			(size 1.397 1.143)
			(layers "B.Cu" "B.Mask" "B.Paste")
			(net "GND")
		)
	)
	(footprint ""
		(layer "B.Cu")
		(at 62.1792 -54.7878 -90)
		(property "Reference" "C685"
			(at 0 0 90)
			(layer "B.SilkS")
			(hide yes)
			(effects
				(font
					(size 1.27 1.27)
				)
				(justify mirror)
			)
		)
		(property "Value" "SC10U6D3V5KX-4GP"
			(at 0.0762 -6.1214 270)
			(unlocked yes)
			(layer "B.Fab")
			(hide yes)
			(effects
				(font
					(size 1.016 1.016)
					(thickness 0.1524)
				)
				(justify mirror)
			)
		)
		(property "Device Type" "C805H58"
			(at 0.0762 -8.1534 270)
			(unlocked yes)
			(layer "B.Fab")
			(hide yes)
			(effects
				(font
					(size 1.016 1.016)
					(thickness 0.1524)
				)
				(justify mirror)
			)
		)
		(duplicate_pad_numbers_are_jumpers no)
		(fp_line
			(start -0.635 0)
			(end 0.635 0)
			(stroke
				(width 0.508)
				(type default)
			)
			(layer "B.SilkS")
		)
		(fp_rect
			(start 0.9652 1.778)
			(end -0.9652 -1.778)
			(stroke
				(width 0)
				(type default)
			)
			(fill no)
			(layer "B.CrtYd")
		)
		(fp_poly
			(pts
				(xy 0.9652 -1.778) (xy -0.9652 -1.778) (xy -0.9652 1.778) (xy 0.9652 1.778)
			)
			(stroke
				(width 0)
				(type default)
			)
			(fill no)
			(layer "B.Fab")
		)
		(pad "1" smd rect
			(at 0 -0.9652 90)
			(size 1.397 1.143)
			(layers "B.Cu" "B.Mask" "B.Paste")
			(net "P0V9")
		)
		(pad "2" smd rect
			(at 0 0.9652 90)
			(size 1.397 1.143)
			(layers "B.Cu" "B.Mask" "B.Paste")
			(net "GND")
		)
	)
	(footprint ""
		(layer "B.Cu")
		(at 108.839 -44.2214 180)
		(property "Reference" "C73"
			(at 0 0 0)
			(layer "B.SilkS")
			(hide yes)
			(effects
				(font
					(size 1.27 1.27)
				)
				(justify mirror)
			)
		)
		(property "Value" "SCD01U16V1KX-GP"
			(at 2.8321 -1.7399 180)
			(unlocked yes)
			(layer "B.Fab")
			(hide yes)
			(effects
				(font
					(size 1.016 1.016)
					(thickness 0.1524)
				)
				(justify mirror)
			)
		)
		(property "Device Type" "C0201H13"
			(at 2.8321 -3.2639 180)
			(unlocked yes)
			(layer "B.Fab")
			(hide yes)
			(effects
				(font
					(size 1.016 1.016)
					(thickness 0.1524)
				)
				(justify mirror)
			)
		)
		(duplicate_pad_numbers_are_jumpers no)
		(fp_rect
			(start 0.2794 0.6477)
			(end -0.2794 -0.6477)
			(stroke
				(width 0)
				(type default)
			)
			(fill no)
			(layer "B.CrtYd")
		)
		(fp_rect
			(start 0.2794 0.6477)
			(end -0.2794 -0.6477)
			(stroke
				(width 0)
				(type default)
			)
			(fill no)
			(layer "B.Fab")
		)
		(pad "1" smd custom
			(at 0 -0.2794)
			(size 0.0762 0.0762)
			(layers "B.Cu" "B.Mask" "B.Paste")
			(net "PHY_DPB_TO_SCC_24_DN")
			(options
				(clearance outline)
				(anchor circle)
			)
			(primitives
				(gr_poly
					(pts
						(arc
							(start 0.1524 0.127)
							(mid 0.137521 0.162921)
							(end 0.1016 0.1778)
						)
						(arc
							(start -0.1016 0.1778)
							(mid -0.137521 0.162921)
							(end -0.1524 0.127)
						)
						(arc
							(start -0.1524 -0.127)
							(mid -0.137521 -0.162921)
							(end -0.1016 -0.1778)
						)
						(arc
							(start 0.1016 -0.1778)
							(mid 0.137521 -0.162921)
							(end 0.1524 -0.127)
						)
					)
					(width 0)
					(fill yes)
				)
			)
		)
		(pad "2" smd custom
			(at 0 0.2794)
			(size 0.0762 0.0762)
			(layers "B.Cu" "B.Mask" "B.Paste")
			(net "PHY_DPB_TO_SCC_C_24_DN")
			(options
				(clearance outline)
				(anchor circle)
			)
			(primitives
				(gr_poly
					(pts
						(arc
							(start 0.1524 0.127)
							(mid 0.137521 0.162921)
							(end 0.1016 0.1778)
						)
						(arc
							(start -0.1016 0.1778)
							(mid -0.137521 0.162921)
							(end -0.1524 0.127)
						)
						(arc
							(start -0.1524 -0.127)
							(mid -0.137521 -0.162921)
							(end -0.1016 -0.1778)
						)
						(arc
							(start 0.1016 -0.1778)
							(mid 0.137521 -0.162921)
							(end 0.1524 -0.127)
						)
					)
					(width 0)
					(fill yes)
				)
			)
		)
	)
	(footprint ""
		(layer "B.Cu")
		(at 72.517 -14.558772 180)
		(property "Reference" "C97"
			(at 0 0 0)
			(layer "B.SilkS")
			(hide yes)
			(effects
				(font
					(size 1.27 1.27)
				)
				(justify mirror)
			)
		)
		(property "Value" "SCD1U16V2KX-3GP"
			(at -1.1811 -2.7051 180)
			(unlocked yes)
			(layer "B.Fab")
			(hide yes)
			(effects
				(font
					(size 1.016 1.016)
					(thickness 0.1524)
				)
				(justify mirror)
			)
		)
		(property "Device Type" "C402H22"
			(at -1.1811 -4.2291 180)
			(unlocked yes)
			(layer "B.Fab")
			(hide yes)
			(effects
				(font
					(size 1.016 1.016)
					(thickness 0.1524)
				)
				(justify mirror)
			)
		)
		(duplicate_pad_numbers_are_jumpers no)
		(fp_rect
			(start 0.4318 0.9525)
			(end -0.4318 -0.9525)
			(stroke
				(width 0)
				(type default)
			)
			(fill no)
			(layer "B.CrtYd")
		)
		(fp_rect
			(start 0.4318 0.9525)
			(end -0.4318 -0.9525)
			(stroke
				(width 0)
				(type default)
			)
			(fill no)
			(layer "B.Fab")
		)
		(pad "1" smd custom
			(at 0 -0.4445)
			(size 0.1524 0.1524)
			(layers "B.Cu" "B.Mask" "B.Paste")
			(net "P3V3")
			(options
				(clearance outline)
				(anchor circle)
			)
			(primitives
				(gr_poly
					(pts
						(arc
							(start 0.3048 0.2032)
							(mid 0.275042 0.275042)
							(end 0.2032 0.3048)
						)
						(arc
							(start -0.2032 0.3048)
							(mid -0.275042 0.275042)
							(end -0.3048 0.2032)
						)
						(arc
							(start -0.3048 -0.2032)
							(mid -0.275042 -0.275042)
							(end -0.2032 -0.3048)
						)
						(arc
							(start 0.2032 -0.3048)
							(mid 0.275042 -0.275042)
							(end 0.3048 -0.2032)
						)
					)
					(width 0)
					(fill yes)
				)
			)
		)
		(pad "2" smd custom
			(at 0 0.4445)
			(size 0.1524 0.1524)
			(layers "B.Cu" "B.Mask" "B.Paste")
			(net "GND")
			(options
				(clearance outline)
				(anchor circle)
			)
			(primitives
				(gr_poly
					(pts
						(arc
							(start 0.3048 0.2032)
							(mid 0.275042 0.275042)
							(end 0.2032 0.3048)
						)
						(arc
							(start -0.2032 0.3048)
							(mid -0.275042 0.275042)
							(end -0.3048 0.2032)
						)
						(arc
							(start -0.3048 -0.2032)
							(mid -0.275042 -0.275042)
							(end -0.2032 -0.3048)
						)
						(arc
							(start 0.2032 -0.3048)
							(mid 0.275042 -0.275042)
							(end 0.3048 -0.2032)
						)
					)
					(width 0)
					(fill yes)
				)
			)
		)
	)
	(footprint ""
		(layer "B.Cu")
		(at 142.01267 -119.51716 90)
		(property "Reference" "Q13"
			(at 0 0 90)
			(layer "B.SilkS")
			(hide yes)
			(effects
				(font
					(size 1.27 1.27)
				)
				(justify mirror)
			)
		)
		(property "Value" "2N7002E-2-GP"
			(at -0.127 -8.9662 90)
			(unlocked yes)
			(layer "B.Fab")
			(hide yes)
			(effects
				(font
					(size 1.016 1.016)
					(thickness 0.1524)
				)
				(justify mirror)
			)
		)
		(property "Device Type" "SOT23DGS2D4H44"
			(at -0.127 -10.4902 90)
			(unlocked yes)
			(layer "B.Fab")
			(hide yes)
			(effects
				(font
					(size 1.016 1.016)
					(thickness 0.1524)
				)
				(justify mirror)
			)
		)
		(duplicate_pad_numbers_are_jumpers no)
		(fp_line
			(start 1.651 -1.778)
			(end 1.651 1.778)
			(stroke
				(width 0.1524)
				(type default)
			)
			(layer "B.SilkS")
		)
		(fp_line
			(start -1.651 -1.778)
			(end 1.651 -1.778)
			(stroke
				(width 0.1524)
				(type default)
			)
			(layer "B.SilkS")
		)
		(fp_line
			(start 1.651 1.778)
			(end -1.651 1.778)
			(stroke
				(width 0.1524)
				(type default)
			)
			(layer "B.SilkS")
		)
		(fp_line
			(start -1.651 1.778)
			(end -1.651 -1.778)
			(stroke
				(width 0.1524)
				(type default)
			)
			(layer "B.SilkS")
		)
		(fp_poly
			(pts
				(xy 1.778 1.8796) (xy 1.778 -1.8796) (xy -1.778 -1.8796) (xy -1.778 1.8796)
			)
			(stroke
				(width 0)
				(type default)
			)
			(fill no)
			(layer "B.CrtYd")
		)
		(fp_poly
			(pts
				(xy 1.778 1.8796) (xy 1.778 -1.8796) (xy -1.778 -1.8796) (xy -1.778 1.8796)
			)
			(stroke
				(width 0)
				(type default)
			)
			(fill no)
			(layer "B.Fab")
		)
		(pad "D" smd custom
			(at 0 -0.9525 270)
			(size 0.1905 0.1905)
			(layers "B.Cu" "B.Mask" "B.Paste")
			(net "P1V5_C_PG_G")
			(options
				(clearance outline)
				(anchor circle)
			)
			(primitives
				(gr_poly
					(pts
						(arc
							(start -0.1778 -0.5715)
							(mid -0.321484 -0.511984)
							(end -0.381 -0.3683)
						)
						(arc
							(start -0.381 0.3683)
							(mid -0.321484 0.511984)
							(end -0.1778 0.5715)
						)
						(arc
							(start 0.1778 0.5715)
							(mid 0.321484 0.511984)
							(end 0.381 0.3683)
						)
						(arc
							(start 0.381 -0.3683)
							(mid 0.321484 -0.511984)
							(end 0.1778 -0.5715)
						)
					)
					(width 0)
					(fill yes)
				)
			)
		)
		(pad "G" smd custom
			(at 0.98425 0.9525 270)
			(size 0.1905 0.1905)
			(layers "B.Cu" "B.Mask" "B.Paste")
			(net "P1V8_C_PG_G")
			(options
				(clearance outline)
				(anchor circle)
			)
			(primitives
				(gr_poly
					(pts
						(arc
							(start -0.1778 -0.5715)
							(mid -0.321484 -0.511984)
							(end -0.381 -0.3683)
						)
						(arc
							(start -0.381 0.3683)
							(mid -0.321484 0.511984)
							(end -0.1778 0.5715)
						)
						(arc
							(start 0.1778 0.5715)
							(mid 0.321484 0.511984)
							(end 0.381 0.3683)
						)
						(arc
							(start 0.381 -0.3683)
							(mid 0.321484 -0.511984)
							(end 0.1778 -0.5715)
						)
					)
					(width 0)
					(fill yes)
				)
			)
		)
		(pad "S" smd custom
			(at -0.98425 0.9525 270)
			(size 0.1905 0.1905)
			(layers "B.Cu" "B.Mask" "B.Paste")
			(net "P1V5_C_S")
			(options
				(clearance outline)
				(anchor circle)
			)
			(primitives
				(gr_poly
					(pts
						(arc
							(start -0.1778 -0.5715)
							(mid -0.321484 -0.511984)
							(end -0.381 -0.3683)
						)
						(arc
							(start -0.381 0.3683)
							(mid -0.321484 0.511984)
							(end -0.1778 0.5715)
						)
						(arc
							(start 0.1778 0.5715)
							(mid 0.321484 0.511984)
							(end 0.381 0.3683)
						)
						(arc
							(start 0.381 -0.3683)
							(mid 0.321484 -0.511984)
							(end 0.1778 -0.5715)
						)
					)
					(width 0)
					(fill yes)
				)
			)
		)
	)
	(footprint ""
		(layer "B.Cu")
		(at 161.798762 -16.258286 180)
		(property "Reference" "R313"
			(at 0 0 0)
			(layer "B.SilkS")
			(hide yes)
			(effects
				(font
					(size 1.27 1.27)
				)
				(justify mirror)
			)
		)
		(property "Value" "3K83R2F-GP"
			(at -0.064008 -3.993896 180)
			(unlocked yes)
			(layer "B.Fab")
			(hide yes)
			(effects
				(font
					(size 1.016 1.016)
					(thickness 0.1524)
				)
				(justify mirror)
			)
		)
		(property "Device Type" "R402H16"
			(at -0.064008 -5.517896 180)
			(unlocked yes)
			(layer "B.Fab")
			(hide yes)
			(effects
				(font
					(size 1.016 1.016)
					(thickness 0.1524)
				)
				(justify mirror)
			)
		)
		(duplicate_pad_numbers_are_jumpers no)
		(fp_line
			(start 0.508 -0.9398)
			(end 0.508 0.9398)
			(stroke
				(width 0.1524)
				(type default)
			)
			(layer "B.SilkS")
		)
		(fp_line
			(start -0.508 -0.9398)
			(end 0.508 -0.9398)
			(stroke
				(width 0.1524)
				(type default)
			)
			(layer "B.SilkS")
		)
		(fp_rect
			(start 0.508 0.9398)
			(end -0.508 -0.9398)
			(stroke
				(width 0)
				(type default)
			)
			(fill no)
			(layer "B.CrtYd")
		)
		(fp_rect
			(start 0.508 0.9398)
			(end -0.508 -0.9398)
			(stroke
				(width 0)
				(type default)
			)
			(fill no)
			(layer "B.Fab")
		)
		(pad "1" smd custom
			(at 0 -0.4445)
			(size 0.1397 0.1397)
			(layers "B.Cu" "B.Mask" "B.Paste")
			(net "LS_EN_N")
			(options
				(clearance outline)
				(anchor circle)
			)
			(primitives
				(gr_poly
					(pts
						(arc
							(start -0.1778 0.2794)
							(mid -0.249642 0.249642)
							(end -0.2794 0.1778)
						)
						(arc
							(start -0.2794 -0.1778)
							(mid -0.249642 -0.249642)
							(end -0.1778 -0.2794)
						)
						(arc
							(start 0.1778 -0.2794)
							(mid 0.249642 -0.249642)
							(end 0.2794 -0.1778)
						)
						(arc
							(start 0.2794 0.1778)
							(mid 0.249642 0.249642)
							(end 0.1778 0.2794)
						)
					)
					(width 0)
					(fill yes)
				)
			)
		)
		(pad "2" smd custom
			(at 0 0.4445)
			(size 0.1397 0.1397)
			(layers "B.Cu" "B.Mask" "B.Paste")
			(net "GND")
			(options
				(clearance outline)
				(anchor circle)
			)
			(primitives
				(gr_poly
					(pts
						(arc
							(start -0.1778 0.2794)
							(mid -0.249642 0.249642)
							(end -0.2794 0.1778)
						)
						(arc
							(start -0.2794 -0.1778)
							(mid -0.249642 -0.249642)
							(end -0.1778 -0.2794)
						)
						(arc
							(start 0.1778 -0.2794)
							(mid 0.249642 -0.249642)
							(end 0.2794 -0.1778)
						)
						(arc
							(start 0.2794 0.1778)
							(mid 0.249642 0.249642)
							(end 0.1778 0.2794)
						)
					)
					(width 0)
					(fill yes)
				)
			)
		)
	)
	(footprint ""
		(layer "B.Cu")
		(at 178.420776 -21.15058 90)
		(property "Reference" "C324"
			(at 0 0 90)
			(layer "B.SilkS")
			(hide yes)
			(effects
				(font
					(size 1.27 1.27)
				)
				(justify mirror)
			)
		)
		(property "Value" "SCD22U10V1KX-GP"
			(at 2.8321 -1.7399 90)
			(unlocked yes)
			(layer "B.Fab")
			(hide yes)
			(effects
				(font
					(size 1.016 1.016)
					(thickness 0.1524)
				)
				(justify mirror)
			)
		)
		(property "Device Type" "C0201H13"
			(at 2.8321 -3.2639 90)
			(unlocked yes)
			(layer "B.Fab")
			(hide yes)
			(effects
				(font
					(size 1.016 1.016)
					(thickness 0.1524)
				)
				(justify mirror)
			)
		)
		(duplicate_pad_numbers_are_jumpers no)
		(fp_rect
			(start 0.2794 0.6477)
			(end -0.2794 -0.6477)
			(stroke
				(width 0)
				(type default)
			)
			(fill no)
			(layer "B.CrtYd")
		)
		(fp_rect
			(start 0.2794 0.6477)
			(end -0.2794 -0.6477)
			(stroke
				(width 0)
				(type default)
			)
			(fill no)
			(layer "B.Fab")
		)
		(pad "1" smd custom
			(at 0 -0.2794 270)
			(size 0.0762 0.0762)
			(layers "B.Cu" "B.Mask" "B.Paste")
			(net "PCIE_SCC_TO_COMP_C_6_DN")
			(options
				(clearance outline)
				(anchor circle)
			)
			(primitives
				(gr_poly
					(pts
						(arc
							(start 0.1524 0.127)
							(mid 0.137521 0.162921)
							(end 0.1016 0.1778)
						)
						(arc
							(start -0.1016 0.1778)
							(mid -0.137521 0.162921)
							(end -0.1524 0.127)
						)
						(arc
							(start -0.1524 -0.127)
							(mid -0.137521 -0.162921)
							(end -0.1016 -0.1778)
						)
						(arc
							(start 0.1016 -0.1778)
							(mid 0.137521 -0.162921)
							(end 0.1524 -0.127)
						)
					)
					(width 0)
					(fill yes)
				)
			)
		)
		(pad "2" smd custom
			(at 0 0.2794 270)
			(size 0.0762 0.0762)
			(layers "B.Cu" "B.Mask" "B.Paste")
			(net "PCIE_SCC_TO_COMP_6_DN")
			(options
				(clearance outline)
				(anchor circle)
			)
			(primitives
				(gr_poly
					(pts
						(arc
							(start 0.1524 0.127)
							(mid 0.137521 0.162921)
							(end 0.1016 0.1778)
						)
						(arc
							(start -0.1016 0.1778)
							(mid -0.137521 0.162921)
							(end -0.1524 0.127)
						)
						(arc
							(start -0.1524 -0.127)
							(mid -0.137521 -0.162921)
							(end -0.1016 -0.1778)
						)
						(arc
							(start 0.1016 -0.1778)
							(mid 0.137521 -0.162921)
							(end 0.1524 -0.127)
						)
					)
					(width 0)
					(fill yes)
				)
			)
		)
	)
	(footprint ""
		(layer "B.Cu")
		(at 127.970788 -55.499 -90)
		(property "Reference" "C302"
			(at 0 0 90)
			(layer "B.SilkS")
			(hide yes)
			(effects
				(font
					(size 1.27 1.27)
				)
				(justify mirror)
			)
		)
		(property "Value" "SC1U6D3V1MX-GP"
			(at -1.9177 2.0193 270)
			(unlocked yes)
			(layer "B.Fab")
			(hide yes)
			(effects
				(font
					(size 1.016 1.016)
					(thickness 0.1524)
				)
				(justify mirror)
			)
		)
		(property "Device Type" "C0201H14"
			(at -1.9177 0.4953 270)
			(unlocked yes)
			(layer "B.Fab")
			(hide yes)
			(effects
				(font
					(size 1.016 1.016)
					(thickness 0.1524)
				)
				(justify mirror)
			)
		)
		(duplicate_pad_numbers_are_jumpers no)
		(fp_rect
			(start 0.1524 0.3048)
			(end -0.1524 -0.3048)
			(stroke
				(width 0)
				(type default)
			)
			(fill no)
			(layer "B.CrtYd")
		)
		(fp_poly
			(pts
				(xy 0.2794 0.6477) (xy 0.2794 -0.6477) (xy -0.2794 -0.6477) (xy -0.2794 -0.1905) (xy -0.1524 -0.1905)
				(xy -0.1524 -0.3048) (xy 0.1524 -0.3048) (xy 0.1524 0.3048) (xy -0.1524 0.3048) (xy -0.1524 -0.1778)
				(xy -0.2794 -0.1778) (xy -0.2794 0.6477)
			)
			(stroke
				(width 0)
				(type default)
			)
			(fill no)
			(layer "B.CrtYd")
		)
		(fp_rect
			(start 0.2794 0.6477)
			(end -0.2794 -0.6477)
			(stroke
				(width 0)
				(type default)
			)
			(fill no)
			(layer "B.Fab")
		)
		(pad "1" smd custom
			(at 0 -0.2794 90)
			(size 0.0762 0.0762)
			(layers "B.Cu" "B.Mask" "B.Paste")
			(net "GB_VDDA")
			(options
				(clearance outline)
				(anchor circle)
			)
			(primitives
				(gr_poly
					(pts
						(arc
							(start 0.1524 0.127)
							(mid 0.137521 0.162921)
							(end 0.1016 0.1778)
						)
						(arc
							(start -0.1016 0.1778)
							(mid -0.137521 0.162921)
							(end -0.1524 0.127)
						)
						(arc
							(start -0.1524 -0.127)
							(mid -0.137521 -0.162921)
							(end -0.1016 -0.1778)
						)
						(arc
							(start 0.1016 -0.1778)
							(mid 0.137521 -0.162921)
							(end 0.1524 -0.127)
						)
					)
					(width 0)
					(fill yes)
				)
			)
		)
		(pad "2" smd custom
			(at 0 0.2794 90)
			(size 0.0762 0.0762)
			(layers "B.Cu" "B.Mask" "B.Paste")
			(net "GND")
			(options
				(clearance outline)
				(anchor circle)
			)
			(primitives
				(gr_poly
					(pts
						(arc
							(start 0.1524 0.127)
							(mid 0.137521 0.162921)
							(end 0.1016 0.1778)
						)
						(arc
							(start -0.1016 0.1778)
							(mid -0.137521 0.162921)
							(end -0.1524 0.127)
						)
						(arc
							(start -0.1524 -0.127)
							(mid -0.137521 -0.162921)
							(end -0.1016 -0.1778)
						)
						(arc
							(start 0.1016 -0.1778)
							(mid 0.137521 -0.162921)
							(end 0.1524 -0.127)
						)
					)
					(width 0)
					(fill yes)
				)
			)
		)
	)
	(footprint ""
		(layer "B.Cu")
		(at 112.9919 -61.488066)
		(property "Reference" "C223"
			(at 0 0 0)
			(layer "B.SilkS")
			(hide yes)
			(effects
				(font
					(size 1.27 1.27)
				)
				(justify mirror)
			)
		)
		(property "Value" "SCD1U16V2KX-3GP"
			(at -1.1811 -2.7051 0)
			(unlocked yes)
			(layer "B.Fab")
			(hide yes)
			(effects
				(font
					(size 1.016 1.016)
					(thickness 0.1524)
				)
				(justify mirror)
			)
		)
		(property "Device Type" "C402H22"
			(at -1.1811 -4.2291 0)
			(unlocked yes)
			(layer "B.Fab")
			(hide yes)
			(effects
				(font
					(size 1.016 1.016)
					(thickness 0.1524)
				)
				(justify mirror)
			)
		)
		(duplicate_pad_numbers_are_jumpers no)
		(fp_rect
			(start 0.4318 0.9525)
			(end -0.4318 -0.9525)
			(stroke
				(width 0)
				(type default)
			)
			(fill no)
			(layer "B.CrtYd")
		)
		(fp_rect
			(start 0.4318 0.9525)
			(end -0.4318 -0.9525)
			(stroke
				(width 0)
				(type default)
			)
			(fill no)
			(layer "B.Fab")
		)
		(pad "1" smd custom
			(at 0 -0.4445 180)
			(size 0.1524 0.1524)
			(layers "B.Cu" "B.Mask" "B.Paste")
			(net "GB_VDDH")
			(options
				(clearance outline)
				(anchor circle)
			)
			(primitives
				(gr_poly
					(pts
						(arc
							(start 0.3048 0.2032)
							(mid 0.275042 0.275042)
							(end 0.2032 0.3048)
						)
						(arc
							(start -0.2032 0.3048)
							(mid -0.275042 0.275042)
							(end -0.3048 0.2032)
						)
						(arc
							(start -0.3048 -0.2032)
							(mid -0.275042 -0.275042)
							(end -0.2032 -0.3048)
						)
						(arc
							(start 0.2032 -0.3048)
							(mid 0.275042 -0.275042)
							(end 0.3048 -0.2032)
						)
					)
					(width 0)
					(fill yes)
				)
			)
		)
		(pad "2" smd custom
			(at 0 0.4445 180)
			(size 0.1524 0.1524)
			(layers "B.Cu" "B.Mask" "B.Paste")
			(net "GND")
			(options
				(clearance outline)
				(anchor circle)
			)
			(primitives
				(gr_poly
					(pts
						(arc
							(start 0.3048 0.2032)
							(mid 0.275042 0.275042)
							(end 0.2032 0.3048)
						)
						(arc
							(start -0.2032 0.3048)
							(mid -0.275042 0.275042)
							(end -0.3048 0.2032)
						)
						(arc
							(start -0.3048 -0.2032)
							(mid -0.275042 -0.275042)
							(end -0.2032 -0.3048)
						)
						(arc
							(start 0.2032 -0.3048)
							(mid 0.275042 -0.275042)
							(end 0.3048 -0.2032)
						)
					)
					(width 0)
					(fill yes)
				)
			)
		)
	)
	(footprint ""
		(layer "B.Cu")
		(at 114.3508 -82.2706)
		(property "Reference" "R145"
			(at 0 0 0)
			(layer "B.SilkS")
			(hide yes)
			(effects
				(font
					(size 1.27 1.27)
				)
				(justify mirror)
			)
		)
		(property "Value" "4K7R2F-GP"
			(at -0.064008 -3.993896 0)
			(unlocked yes)
			(layer "B.Fab")
			(hide yes)
			(effects
				(font
					(size 1.016 1.016)
					(thickness 0.1524)
				)
				(justify mirror)
			)
		)
		(property "Device Type" "R402H16"
			(at -0.064008 -5.517896 0)
			(unlocked yes)
			(layer "B.Fab")
			(hide yes)
			(effects
				(font
					(size 1.016 1.016)
					(thickness 0.1524)
				)
				(justify mirror)
			)
		)
		(duplicate_pad_numbers_are_jumpers no)
		(fp_line
			(start -0.508 -0.9398)
			(end 0.508 -0.9398)
			(stroke
				(width 0.1524)
				(type default)
			)
			(layer "B.SilkS")
		)
		(fp_line
			(start 0.508 -0.9398)
			(end 0.508 0.9398)
			(stroke
				(width 0.1524)
				(type default)
			)
			(layer "B.SilkS")
		)
		(fp_rect
			(start 0.508 0.9398)
			(end -0.508 -0.9398)
			(stroke
				(width 0)
				(type default)
			)
			(fill no)
			(layer "B.CrtYd")
		)
		(fp_rect
			(start 0.508 0.9398)
			(end -0.508 -0.9398)
			(stroke
				(width 0)
				(type default)
			)
			(fill no)
			(layer "B.Fab")
		)
		(pad "1" smd custom
			(at 0 -0.4445 180)
			(size 0.1397 0.1397)
			(layers "B.Cu" "B.Mask" "B.Paste")
			(net "EXP_XM_ADDR_19")
			(options
				(clearance outline)
				(anchor circle)
			)
			(primitives
				(gr_poly
					(pts
						(arc
							(start -0.1778 0.2794)
							(mid -0.249642 0.249642)
							(end -0.2794 0.1778)
						)
						(arc
							(start -0.2794 -0.1778)
							(mid -0.249642 -0.249642)
							(end -0.1778 -0.2794)
						)
						(arc
							(start 0.1778 -0.2794)
							(mid 0.249642 -0.249642)
							(end 0.2794 -0.1778)
						)
						(arc
							(start 0.2794 0.1778)
							(mid 0.249642 0.249642)
							(end 0.1778 0.2794)
						)
					)
					(width 0)
					(fill yes)
				)
			)
		)
		(pad "2" smd custom
			(at 0 0.4445 180)
			(size 0.1397 0.1397)
			(layers "B.Cu" "B.Mask" "B.Paste")
			(net "GND")
			(options
				(clearance outline)
				(anchor circle)
			)
			(primitives
				(gr_poly
					(pts
						(arc
							(start -0.1778 0.2794)
							(mid -0.249642 0.249642)
							(end -0.2794 0.1778)
						)
						(arc
							(start -0.2794 -0.1778)
							(mid -0.249642 -0.249642)
							(end -0.1778 -0.2794)
						)
						(arc
							(start 0.1778 -0.2794)
							(mid 0.249642 -0.249642)
							(end 0.2794 -0.1778)
						)
						(arc
							(start 0.2794 0.1778)
							(mid 0.249642 0.249642)
							(end 0.1778 0.2794)
						)
					)
					(width 0)
					(fill yes)
				)
			)
		)
	)
	(footprint ""
		(layer "B.Cu")
		(at 127.970788 -59.491626 -90)
		(property "Reference" "C272"
			(at 0 0 90)
			(layer "B.SilkS")
			(hide yes)
			(effects
				(font
					(size 1.27 1.27)
				)
				(justify mirror)
			)
		)
		(property "Value" "SCD1U6D3V1KX-GP"
			(at 2.8321 -1.7399 270)
			(unlocked yes)
			(layer "B.Fab")
			(hide yes)
			(effects
				(font
					(size 1.016 1.016)
					(thickness 0.1524)
				)
				(justify mirror)
			)
		)
		(property "Device Type" "C0201H13"
			(at 2.8321 -3.2639 270)
			(unlocked yes)
			(layer "B.Fab")
			(hide yes)
			(effects
				(font
					(size 1.016 1.016)
					(thickness 0.1524)
				)
				(justify mirror)
			)
		)
		(duplicate_pad_numbers_are_jumpers no)
		(fp_rect
			(start 0.2794 0.6477)
			(end -0.2794 -0.6477)
			(stroke
				(width 0)
				(type default)
			)
			(fill no)
			(layer "B.CrtYd")
		)
		(fp_rect
			(start 0.2794 0.6477)
			(end -0.2794 -0.6477)
			(stroke
				(width 0)
				(type default)
			)
			(fill no)
			(layer "B.Fab")
		)
		(pad "1" smd custom
			(at 0 -0.2794 90)
			(size 0.0762 0.0762)
			(layers "B.Cu" "B.Mask" "B.Paste")
			(net "GB_VDDA")
			(options
				(clearance outline)
				(anchor circle)
			)
			(primitives
				(gr_poly
					(pts
						(arc
							(start 0.1524 0.127)
							(mid 0.137521 0.162921)
							(end 0.1016 0.1778)
						)
						(arc
							(start -0.1016 0.1778)
							(mid -0.137521 0.162921)
							(end -0.1524 0.127)
						)
						(arc
							(start -0.1524 -0.127)
							(mid -0.137521 -0.162921)
							(end -0.1016 -0.1778)
						)
						(arc
							(start 0.1016 -0.1778)
							(mid 0.137521 -0.162921)
							(end 0.1524 -0.127)
						)
					)
					(width 0)
					(fill yes)
				)
			)
		)
		(pad "2" smd custom
			(at 0 0.2794 90)
			(size 0.0762 0.0762)
			(layers "B.Cu" "B.Mask" "B.Paste")
			(net "GND")
			(options
				(clearance outline)
				(anchor circle)
			)
			(primitives
				(gr_poly
					(pts
						(arc
							(start 0.1524 0.127)
							(mid 0.137521 0.162921)
							(end 0.1016 0.1778)
						)
						(arc
							(start -0.1016 0.1778)
							(mid -0.137521 0.162921)
							(end -0.1524 0.127)
						)
						(arc
							(start -0.1524 -0.127)
							(mid -0.137521 -0.162921)
							(end -0.1016 -0.1778)
						)
						(arc
							(start 0.1016 -0.1778)
							(mid 0.137521 -0.162921)
							(end 0.1524 -0.127)
						)
					)
					(width 0)
					(fill yes)
				)
			)
		)
	)
	(footprint ""
		(layer "B.Cu")
		(at 168.530778 -47.79772)
		(property "Reference" "C464"
			(at 0 0 0)
			(layer "B.SilkS")
			(hide yes)
			(effects
				(font
					(size 1.27 1.27)
				)
				(justify mirror)
			)
		)
		(property "Value" "SCD1U6D3V1KX-GP"
			(at 2.8321 -1.7399 0)
			(unlocked yes)
			(layer "B.Fab")
			(hide yes)
			(effects
				(font
					(size 1.016 1.016)
					(thickness 0.1524)
				)
				(justify mirror)
			)
		)
		(property "Device Type" "C0201H13"
			(at 2.8321 -3.2639 0)
			(unlocked yes)
			(layer "B.Fab")
			(hide yes)
			(effects
				(font
					(size 1.016 1.016)
					(thickness 0.1524)
				)
				(justify mirror)
			)
		)
		(duplicate_pad_numbers_are_jumpers no)
		(fp_rect
			(start 0.2794 0.6477)
			(end -0.2794 -0.6477)
			(stroke
				(width 0)
				(type default)
			)
			(fill no)
			(layer "B.CrtYd")
		)
		(fp_rect
			(start 0.2794 0.6477)
			(end -0.2794 -0.6477)
			(stroke
				(width 0)
				(type default)
			)
			(fill no)
			(layer "B.Fab")
		)
		(pad "1" smd custom
			(at 0 -0.2794 180)
			(size 0.0762 0.0762)
			(layers "B.Cu" "B.Mask" "B.Paste")
			(net "P1V8_C")
			(options
				(clearance outline)
				(anchor circle)
			)
			(primitives
				(gr_poly
					(pts
						(arc
							(start 0.1524 0.127)
							(mid 0.137521 0.162921)
							(end 0.1016 0.1778)
						)
						(arc
							(start -0.1016 0.1778)
							(mid -0.137521 0.162921)
							(end -0.1524 0.127)
						)
						(arc
							(start -0.1524 -0.127)
							(mid -0.137521 -0.162921)
							(end -0.1016 -0.1778)
						)
						(arc
							(start 0.1016 -0.1778)
							(mid 0.137521 -0.162921)
							(end 0.1524 -0.127)
						)
					)
					(width 0)
					(fill yes)
				)
			)
		)
		(pad "2" smd custom
			(at 0 0.2794 180)
			(size 0.0762 0.0762)
			(layers "B.Cu" "B.Mask" "B.Paste")
			(net "GND")
			(options
				(clearance outline)
				(anchor circle)
			)
			(primitives
				(gr_poly
					(pts
						(arc
							(start 0.1524 0.127)
							(mid 0.137521 0.162921)
							(end 0.1016 0.1778)
						)
						(arc
							(start -0.1016 0.1778)
							(mid -0.137521 0.162921)
							(end -0.1524 0.127)
						)
						(arc
							(start -0.1524 -0.127)
							(mid -0.137521 -0.162921)
							(end -0.1016 -0.1778)
						)
						(arc
							(start 0.1016 -0.1778)
							(mid 0.137521 -0.162921)
							(end 0.1524 -0.127)
						)
					)
					(width 0)
					(fill yes)
				)
			)
		)
	)
	(footprint ""
		(layer "B.Cu")
		(at 126.1872 -93.5609 90)
		(property "Reference" "R350"
			(at 0 0 90)
			(layer "B.SilkS")
			(hide yes)
			(effects
				(font
					(size 1.27 1.27)
				)
				(justify mirror)
			)
		)
		(property "Value" "4K75R2F-1-GP"
			(at -0.064008 -3.993896 90)
			(unlocked yes)
			(layer "B.Fab")
			(hide yes)
			(effects
				(font
					(size 1.016 1.016)
					(thickness 0.1524)
				)
				(justify mirror)
			)
		)
		(property "Device Type" "R402H16"
			(at -0.064008 -5.517896 90)
			(unlocked yes)
			(layer "B.Fab")
			(hide yes)
			(effects
				(font
					(size 1.016 1.016)
					(thickness 0.1524)
				)
				(justify mirror)
			)
		)
		(duplicate_pad_numbers_are_jumpers no)
		(fp_line
			(start 0.508 -0.9398)
			(end 0.508 0.9398)
			(stroke
				(width 0.1524)
				(type default)
			)
			(layer "B.SilkS")
		)
		(fp_line
			(start -0.508 -0.9398)
			(end 0.508 -0.9398)
			(stroke
				(width 0.1524)
				(type default)
			)
			(layer "B.SilkS")
		)
		(fp_rect
			(start 0.508 0.9398)
			(end -0.508 -0.9398)
			(stroke
				(width 0)
				(type default)
			)
			(fill no)
			(layer "B.CrtYd")
		)
		(fp_rect
			(start 0.508 0.9398)
			(end -0.508 -0.9398)
			(stroke
				(width 0)
				(type default)
			)
			(fill no)
			(layer "B.Fab")
		)
		(pad "1" smd custom
			(at 0 -0.4445 270)
			(size 0.1397 0.1397)
			(layers "B.Cu" "B.Mask" "B.Paste")
			(net "EXP_RGMII_RXC")
			(options
				(clearance outline)
				(anchor circle)
			)
			(primitives
				(gr_poly
					(pts
						(arc
							(start -0.1778 0.2794)
							(mid -0.249642 0.249642)
							(end -0.2794 0.1778)
						)
						(arc
							(start -0.2794 -0.1778)
							(mid -0.249642 -0.249642)
							(end -0.1778 -0.2794)
						)
						(arc
							(start 0.1778 -0.2794)
							(mid 0.249642 -0.249642)
							(end 0.2794 -0.1778)
						)
						(arc
							(start 0.2794 0.1778)
							(mid 0.249642 0.249642)
							(end 0.1778 0.2794)
						)
					)
					(width 0)
					(fill yes)
				)
			)
		)
		(pad "2" smd custom
			(at 0 0.4445 270)
			(size 0.1397 0.1397)
			(layers "B.Cu" "B.Mask" "B.Paste")
			(net "GND")
			(options
				(clearance outline)
				(anchor circle)
			)
			(primitives
				(gr_poly
					(pts
						(arc
							(start -0.1778 0.2794)
							(mid -0.249642 0.249642)
							(end -0.2794 0.1778)
						)
						(arc
							(start -0.2794 -0.1778)
							(mid -0.249642 -0.249642)
							(end -0.1778 -0.2794)
						)
						(arc
							(start 0.1778 -0.2794)
							(mid 0.249642 -0.249642)
							(end 0.2794 -0.1778)
						)
						(arc
							(start 0.2794 0.1778)
							(mid 0.249642 0.249642)
							(end 0.1778 0.2794)
						)
					)
					(width 0)
					(fill yes)
				)
			)
		)
	)
	(footprint ""
		(layer "B.Cu")
		(at 183.668416 -83.728052 90)
		(property "Reference" "C659"
			(at 0 0 90)
			(layer "B.SilkS")
			(hide yes)
			(effects
				(font
					(size 1.27 1.27)
				)
				(justify mirror)
			)
		)
		(property "Value" "SC6K8P50V2KX-GP"
			(at -1.1811 -2.7051 90)
			(unlocked yes)
			(layer "B.Fab")
			(hide yes)
			(effects
				(font
					(size 1.016 1.016)
					(thickness 0.1524)
				)
				(justify mirror)
			)
		)
		(property "Device Type" "C402H22"
			(at -1.1811 -4.2291 90)
			(unlocked yes)
			(layer "B.Fab")
			(hide yes)
			(effects
				(font
					(size 1.016 1.016)
					(thickness 0.1524)
				)
				(justify mirror)
			)
		)
		(duplicate_pad_numbers_are_jumpers no)
		(fp_rect
			(start 0.4318 0.9525)
			(end -0.4318 -0.9525)
			(stroke
				(width 0)
				(type default)
			)
			(fill no)
			(layer "B.CrtYd")
		)
		(fp_rect
			(start 0.4318 0.9525)
			(end -0.4318 -0.9525)
			(stroke
				(width 0)
				(type default)
			)
			(fill no)
			(layer "B.Fab")
		)
		(pad "1" smd custom
			(at 0 -0.4445 270)
			(size 0.1524 0.1524)
			(layers "B.Cu" "B.Mask" "B.Paste")
			(net "P0V975")
			(options
				(clearance outline)
				(anchor circle)
			)
			(primitives
				(gr_poly
					(pts
						(arc
							(start 0.3048 0.2032)
							(mid 0.275042 0.275042)
							(end 0.2032 0.3048)
						)
						(arc
							(start -0.2032 0.3048)
							(mid -0.275042 0.275042)
							(end -0.3048 0.2032)
						)
						(arc
							(start -0.3048 -0.2032)
							(mid -0.275042 -0.275042)
							(end -0.2032 -0.3048)
						)
						(arc
							(start 0.2032 -0.3048)
							(mid 0.275042 -0.275042)
							(end 0.3048 -0.2032)
						)
					)
					(width 0)
					(fill yes)
				)
			)
		)
		(pad "2" smd custom
			(at 0 0.4445 270)
			(size 0.1524 0.1524)
			(layers "B.Cu" "B.Mask" "B.Paste")
			(net "GND")
			(options
				(clearance outline)
				(anchor circle)
			)
			(primitives
				(gr_poly
					(pts
						(arc
							(start 0.3048 0.2032)
							(mid 0.275042 0.275042)
							(end 0.2032 0.3048)
						)
						(arc
							(start -0.2032 0.3048)
							(mid -0.275042 0.275042)
							(end -0.3048 0.2032)
						)
						(arc
							(start -0.3048 -0.2032)
							(mid -0.275042 -0.275042)
							(end -0.2032 -0.3048)
						)
						(arc
							(start 0.2032 -0.3048)
							(mid 0.275042 -0.275042)
							(end 0.3048 -0.2032)
						)
					)
					(width 0)
					(fill yes)
				)
			)
		)
	)
	(footprint ""
		(layer "B.Cu")
		(at 172.890434 -34.120328 180)
		(property "Reference" "C391"
			(at 0 0 0)
			(layer "B.SilkS")
			(hide yes)
			(effects
				(font
					(size 1.27 1.27)
				)
				(justify mirror)
			)
		)
		(property "Value" "SCD1U6D3V1KX-GP"
			(at 2.8321 -1.7399 180)
			(unlocked yes)
			(layer "B.Fab")
			(hide yes)
			(effects
				(font
					(size 1.016 1.016)
					(thickness 0.1524)
				)
				(justify mirror)
			)
		)
		(property "Device Type" "C0201H13"
			(at 2.8321 -3.2639 180)
			(unlocked yes)
			(layer "B.Fab")
			(hide yes)
			(effects
				(font
					(size 1.016 1.016)
					(thickness 0.1524)
				)
				(justify mirror)
			)
		)
		(duplicate_pad_numbers_are_jumpers no)
		(fp_rect
			(start 0.2794 0.6477)
			(end -0.2794 -0.6477)
			(stroke
				(width 0)
				(type default)
			)
			(fill no)
			(layer "B.CrtYd")
		)
		(fp_rect
			(start 0.2794 0.6477)
			(end -0.2794 -0.6477)
			(stroke
				(width 0)
				(type default)
			)
			(fill no)
			(layer "B.Fab")
		)
		(pad "1" smd custom
			(at 0 -0.2794)
			(size 0.0762 0.0762)
			(layers "B.Cu" "B.Mask" "B.Paste")
			(net "PCE_AVDD")
			(options
				(clearance outline)
				(anchor circle)
			)
			(primitives
				(gr_poly
					(pts
						(arc
							(start 0.1524 0.127)
							(mid 0.137521 0.162921)
							(end 0.1016 0.1778)
						)
						(arc
							(start -0.1016 0.1778)
							(mid -0.137521 0.162921)
							(end -0.1524 0.127)
						)
						(arc
							(start -0.1524 -0.127)
							(mid -0.137521 -0.162921)
							(end -0.1016 -0.1778)
						)
						(arc
							(start 0.1016 -0.1778)
							(mid 0.137521 -0.162921)
							(end 0.1524 -0.127)
						)
					)
					(width 0)
					(fill yes)
				)
			)
		)
		(pad "2" smd custom
			(at 0 0.2794)
			(size 0.0762 0.0762)
			(layers "B.Cu" "B.Mask" "B.Paste")
			(net "GND")
			(options
				(clearance outline)
				(anchor circle)
			)
			(primitives
				(gr_poly
					(pts
						(arc
							(start 0.1524 0.127)
							(mid 0.137521 0.162921)
							(end 0.1016 0.1778)
						)
						(arc
							(start -0.1016 0.1778)
							(mid -0.137521 0.162921)
							(end -0.1524 0.127)
						)
						(arc
							(start -0.1524 -0.127)
							(mid -0.137521 -0.162921)
							(end -0.1016 -0.1778)
						)
						(arc
							(start 0.1016 -0.1778)
							(mid 0.137521 -0.162921)
							(end 0.1524 -0.127)
						)
					)
					(width 0)
					(fill yes)
				)
			)
		)
	)
	(footprint ""
		(layer "B.Cu")
		(at 114.1476 -84.455)
		(property "Reference" "R140"
			(at 0 0 0)
			(layer "B.SilkS")
			(hide yes)
			(effects
				(font
					(size 1.27 1.27)
				)
				(justify mirror)
			)
		)
		(property "Value" "34KR2F-GP"
			(at -0.064008 -3.993896 0)
			(unlocked yes)
			(layer "B.Fab")
			(hide yes)
			(effects
				(font
					(size 1.016 1.016)
					(thickness 0.1524)
				)
				(justify mirror)
			)
		)
		(property "Device Type" "R402H16"
			(at -0.064008 -5.517896 0)
			(unlocked yes)
			(layer "B.Fab")
			(hide yes)
			(effects
				(font
					(size 1.016 1.016)
					(thickness 0.1524)
				)
				(justify mirror)
			)
		)
		(duplicate_pad_numbers_are_jumpers no)
		(fp_line
			(start -0.508 -0.9398)
			(end 0.508 -0.9398)
			(stroke
				(width 0.1524)
				(type default)
			)
			(layer "B.SilkS")
		)
		(fp_line
			(start 0.508 -0.9398)
			(end 0.508 0.9398)
			(stroke
				(width 0.1524)
				(type default)
			)
			(layer "B.SilkS")
		)
		(fp_rect
			(start 0.508 0.9398)
			(end -0.508 -0.9398)
			(stroke
				(width 0)
				(type default)
			)
			(fill no)
			(layer "B.CrtYd")
		)
		(fp_rect
			(start 0.508 0.9398)
			(end -0.508 -0.9398)
			(stroke
				(width 0)
				(type default)
			)
			(fill no)
			(layer "B.Fab")
		)
		(pad "1" smd custom
			(at 0 -0.4445 180)
			(size 0.1397 0.1397)
			(layers "B.Cu" "B.Mask" "B.Paste")
			(net "P1V8_E")
			(options
				(clearance outline)
				(anchor circle)
			)
			(primitives
				(gr_poly
					(pts
						(arc
							(start -0.1778 0.2794)
							(mid -0.249642 0.249642)
							(end -0.2794 0.1778)
						)
						(arc
							(start -0.2794 -0.1778)
							(mid -0.249642 -0.249642)
							(end -0.1778 -0.2794)
						)
						(arc
							(start 0.1778 -0.2794)
							(mid 0.249642 -0.249642)
							(end 0.2794 -0.1778)
						)
						(arc
							(start 0.2794 0.1778)
							(mid 0.249642 0.249642)
							(end 0.1778 0.2794)
						)
					)
					(width 0)
					(fill yes)
				)
			)
		)
		(pad "2" smd custom
			(at 0 0.4445 180)
			(size 0.1397 0.1397)
			(layers "B.Cu" "B.Mask" "B.Paste")
			(net "EXP_XM_BUSY_N")
			(options
				(clearance outline)
				(anchor circle)
			)
			(primitives
				(gr_poly
					(pts
						(arc
							(start -0.1778 0.2794)
							(mid -0.249642 0.249642)
							(end -0.2794 0.1778)
						)
						(arc
							(start -0.2794 -0.1778)
							(mid -0.249642 -0.249642)
							(end -0.1778 -0.2794)
						)
						(arc
							(start 0.1778 -0.2794)
							(mid 0.249642 -0.249642)
							(end 0.2794 -0.1778)
						)
						(arc
							(start 0.2794 0.1778)
							(mid 0.249642 0.249642)
							(end 0.1778 0.2794)
						)
					)
					(width 0)
					(fill yes)
				)
			)
		)
	)
	(footprint ""
		(layer "B.Cu")
		(at 166.624 -59.6138 90)
		(property "Reference" "C353"
			(at 0 0 90)
			(layer "B.SilkS")
			(hide yes)
			(effects
				(font
					(size 1.27 1.27)
				)
				(justify mirror)
			)
		)
		(property "Value" "SC1U16V2KX-7-GP"
			(at -1.7526 -1.6002 90)
			(unlocked yes)
			(layer "B.Fab")
			(hide yes)
			(effects
				(font
					(size 1.016 1.016)
					(thickness 0.1524)
				)
				(justify mirror)
			)
		)
		(property "Device Type" "C402-TO0D2H24"
			(at -1.7526 -3.1242 90)
			(unlocked yes)
			(layer "B.Fab")
			(hide yes)
			(effects
				(font
					(size 1.016 1.016)
					(thickness 0.1524)
				)
				(justify mirror)
			)
		)
		(duplicate_pad_numbers_are_jumpers no)
		(fp_rect
			(start 0.4826 0.889)
			(end -0.4826 -0.889)
			(stroke
				(width 0)
				(type default)
			)
			(fill no)
			(layer "B.CrtYd")
		)
		(fp_rect
			(start 0.4826 0.889)
			(end -0.4826 -0.889)
			(stroke
				(width 0)
				(type default)
			)
			(fill no)
			(layer "B.Fab")
		)
		(pad "1" smd custom
			(at 0 -0.4572 270)
			(size 0.1524 0.1524)
			(layers "B.Cu" "B.Mask" "B.Paste")
			(net "HM40ADC_VDDA")
			(options
				(clearance outline)
				(anchor circle)
			)
			(primitives
				(gr_poly
					(pts
						(arc
							(start -0.254 -0.3048)
							(mid -0.325842 -0.275042)
							(end -0.3556 -0.2032)
						)
						(arc
							(start -0.3556 0.2032)
							(mid -0.325842 0.275042)
							(end -0.254 0.3048)
						)
						(arc
							(start 0.254 0.3048)
							(mid 0.325842 0.275042)
							(end 0.3556 0.2032)
						)
						(arc
							(start 0.3556 -0.2032)
							(mid 0.325842 -0.275042)
							(end 0.254 -0.3048)
						)
					)
					(width 0)
					(fill yes)
				)
			)
		)
		(pad "2" smd custom
			(at 0 0.4572 270)
			(size 0.1524 0.1524)
			(layers "B.Cu" "B.Mask" "B.Paste")
			(net "GND")
			(options
				(clearance outline)
				(anchor circle)
			)
			(primitives
				(gr_poly
					(pts
						(arc
							(start -0.254 -0.3048)
							(mid -0.325842 -0.275042)
							(end -0.3556 -0.2032)
						)
						(arc
							(start -0.3556 0.2032)
							(mid -0.325842 0.275042)
							(end -0.254 0.3048)
						)
						(arc
							(start 0.254 0.3048)
							(mid 0.325842 0.275042)
							(end 0.3556 0.2032)
						)
						(arc
							(start 0.3556 -0.2032)
							(mid 0.325842 -0.275042)
							(end 0.254 -0.3048)
						)
					)
					(width 0)
					(fill yes)
				)
			)
		)
	)
	(footprint ""
		(layer "B.Cu")
		(at 89.472516 -67.472814 180)
		(property "Reference" "L3"
			(at 0 0 0)
			(layer "B.SilkS")
			(hide yes)
			(effects
				(font
					(size 1.27 1.27)
				)
				(justify mirror)
			)
		)
		(property "Value" "MPZ2012S601AT-GP"
			(at 0 -4.2418 180)
			(unlocked yes)
			(layer "B.Fab")
			(hide yes)
			(effects
				(font
					(size 1.016 1.016)
					(thickness 0.1524)
				)
				(justify mirror)
			)
		)
		(property "Device Type" "L805H42"
			(at 0 -5.7912 180)
			(unlocked yes)
			(layer "B.Fab")
			(hide yes)
			(effects
				(font
					(size 1.016 1.016)
					(thickness 0.1524)
				)
				(justify mirror)
			)
		)
		(duplicate_pad_numbers_are_jumpers no)
		(fp_line
			(start 0.889 1.7018)
			(end 0.889 -1.7018)
			(stroke
				(width 0.1524)
				(type default)
			)
			(layer "B.SilkS")
		)
		(fp_line
			(start 0.889 -1.7018)
			(end -0.889 -1.7018)
			(stroke
				(width 0.1524)
				(type default)
			)
			(layer "B.SilkS")
		)
		(fp_line
			(start -0.889 1.7018)
			(end 0.889 1.7018)
			(stroke
				(width 0.1524)
				(type default)
			)
			(layer "B.SilkS")
		)
		(fp_line
			(start -0.889 -1.7018)
			(end -0.889 1.7018)
			(stroke
				(width 0.1524)
				(type default)
			)
			(layer "B.SilkS")
		)
		(fp_rect
			(start 0.9652 1.778)
			(end -0.9652 -1.778)
			(stroke
				(width 0)
				(type default)
			)
			(fill no)
			(layer "B.CrtYd")
		)
		(fp_rect
			(start 0.9652 1.778)
			(end -0.9652 -1.778)
			(stroke
				(width 0)
				(type default)
			)
			(fill no)
			(layer "B.Fab")
		)
		(pad "1" smd rect
			(at 0 -0.9652)
			(size 1.397 1.143)
			(layers "B.Cu" "B.Mask" "B.Paste")
			(net "PLLDDR_VDDA18")
		)
		(pad "2" smd rect
			(at 0 0.9652)
			(size 1.397 1.143)
			(layers "B.Cu" "B.Mask" "B.Paste")
			(net "P1V8_E")
		)
	)
	(footprint ""
		(layer "B.Cu")
		(at 130.433318 -87.260684 180)
		(property "Reference" "R43"
			(at 0 0 0)
			(layer "B.SilkS")
			(hide yes)
			(effects
				(font
					(size 1.27 1.27)
				)
				(justify mirror)
			)
		)
		(property "Value" "4K7R2F-GP"
			(at -0.064008 -3.993896 180)
			(unlocked yes)
			(layer "B.Fab")
			(hide yes)
			(effects
				(font
					(size 1.016 1.016)
					(thickness 0.1524)
				)
				(justify mirror)
			)
		)
		(property "Device Type" "R402H16"
			(at -0.064008 -5.517896 180)
			(unlocked yes)
			(layer "B.Fab")
			(hide yes)
			(effects
				(font
					(size 1.016 1.016)
					(thickness 0.1524)
				)
				(justify mirror)
			)
		)
		(duplicate_pad_numbers_are_jumpers no)
		(fp_line
			(start 0.508 -0.9398)
			(end 0.508 0.9398)
			(stroke
				(width 0.1524)
				(type default)
			)
			(layer "B.SilkS")
		)
		(fp_line
			(start -0.508 -0.9398)
			(end 0.508 -0.9398)
			(stroke
				(width 0.1524)
				(type default)
			)
			(layer "B.SilkS")
		)
		(fp_rect
			(start 0.508 0.9398)
			(end -0.508 -0.9398)
			(stroke
				(width 0)
				(type default)
			)
			(fill no)
			(layer "B.CrtYd")
		)
		(fp_rect
			(start 0.508 0.9398)
			(end -0.508 -0.9398)
			(stroke
				(width 0)
				(type default)
			)
			(fill no)
			(layer "B.Fab")
		)
		(pad "1" smd custom
			(at 0 -0.4445)
			(size 0.1397 0.1397)
			(layers "B.Cu" "B.Mask" "B.Paste")
			(net "EXP_SIO_D_OUT")
			(options
				(clearance outline)
				(anchor circle)
			)
			(primitives
				(gr_poly
					(pts
						(arc
							(start -0.1778 0.2794)
							(mid -0.249642 0.249642)
							(end -0.2794 0.1778)
						)
						(arc
							(start -0.2794 -0.1778)
							(mid -0.249642 -0.249642)
							(end -0.1778 -0.2794)
						)
						(arc
							(start 0.1778 -0.2794)
							(mid 0.249642 -0.249642)
							(end 0.2794 -0.1778)
						)
						(arc
							(start 0.2794 0.1778)
							(mid 0.249642 0.249642)
							(end 0.1778 0.2794)
						)
					)
					(width 0)
					(fill yes)
				)
			)
		)
		(pad "2" smd custom
			(at 0 0.4445)
			(size 0.1397 0.1397)
			(layers "B.Cu" "B.Mask" "B.Paste")
			(net "P1V8_E")
			(options
				(clearance outline)
				(anchor circle)
			)
			(primitives
				(gr_poly
					(pts
						(arc
							(start -0.1778 0.2794)
							(mid -0.249642 0.249642)
							(end -0.2794 0.1778)
						)
						(arc
							(start -0.2794 -0.1778)
							(mid -0.249642 -0.249642)
							(end -0.1778 -0.2794)
						)
						(arc
							(start 0.1778 -0.2794)
							(mid 0.249642 -0.249642)
							(end 0.2794 -0.1778)
						)
						(arc
							(start 0.2794 0.1778)
							(mid 0.249642 0.249642)
							(end 0.1778 0.2794)
						)
					)
					(width 0)
					(fill yes)
				)
			)
		)
	)
	(footprint ""
		(layer "B.Cu")
		(at 171.437808 -39.22141 -90)
		(property "Reference" "C447"
			(at 0 0 90)
			(layer "B.SilkS")
			(hide yes)
			(effects
				(font
					(size 1.27 1.27)
				)
				(justify mirror)
			)
		)
		(property "Value" "SC1KP50V2KX-1GP"
			(at -1.1811 -2.7051 270)
			(unlocked yes)
			(layer "B.Fab")
			(hide yes)
			(effects
				(font
					(size 1.016 1.016)
					(thickness 0.1524)
				)
				(justify mirror)
			)
		)
		(property "Device Type" "C402H22"
			(at -1.1811 -4.2291 270)
			(unlocked yes)
			(layer "B.Fab")
			(hide yes)
			(effects
				(font
					(size 1.016 1.016)
					(thickness 0.1524)
				)
				(justify mirror)
			)
		)
		(duplicate_pad_numbers_are_jumpers no)
		(fp_rect
			(start 0.4318 0.9525)
			(end -0.4318 -0.9525)
			(stroke
				(width 0)
				(type default)
			)
			(fill no)
			(layer "B.CrtYd")
		)
		(fp_rect
			(start 0.4318 0.9525)
			(end -0.4318 -0.9525)
			(stroke
				(width 0)
				(type default)
			)
			(fill no)
			(layer "B.Fab")
		)
		(pad "1" smd custom
			(at 0 -0.4445 90)
			(size 0.1524 0.1524)
			(layers "B.Cu" "B.Mask" "B.Paste")
			(net "P0V975")
			(options
				(clearance outline)
				(anchor circle)
			)
			(primitives
				(gr_poly
					(pts
						(arc
							(start 0.3048 0.2032)
							(mid 0.275042 0.275042)
							(end 0.2032 0.3048)
						)
						(arc
							(start -0.2032 0.3048)
							(mid -0.275042 0.275042)
							(end -0.3048 0.2032)
						)
						(arc
							(start -0.3048 -0.2032)
							(mid -0.275042 -0.275042)
							(end -0.2032 -0.3048)
						)
						(arc
							(start 0.2032 -0.3048)
							(mid 0.275042 -0.275042)
							(end 0.3048 -0.2032)
						)
					)
					(width 0)
					(fill yes)
				)
			)
		)
		(pad "2" smd custom
			(at 0 0.4445 90)
			(size 0.1524 0.1524)
			(layers "B.Cu" "B.Mask" "B.Paste")
			(net "GND")
			(options
				(clearance outline)
				(anchor circle)
			)
			(primitives
				(gr_poly
					(pts
						(arc
							(start 0.3048 0.2032)
							(mid 0.275042 0.275042)
							(end 0.2032 0.3048)
						)
						(arc
							(start -0.2032 0.3048)
							(mid -0.275042 0.275042)
							(end -0.3048 0.2032)
						)
						(arc
							(start -0.3048 -0.2032)
							(mid -0.275042 -0.275042)
							(end -0.2032 -0.3048)
						)
						(arc
							(start 0.2032 -0.3048)
							(mid 0.275042 -0.275042)
							(end 0.3048 -0.2032)
						)
					)
					(width 0)
					(fill yes)
				)
			)
		)
	)
	(footprint ""
		(layer "B.Cu")
		(at 162.814762 -16.258286)
		(property "Reference" "R312"
			(at 0 0 0)
			(layer "B.SilkS")
			(hide yes)
			(effects
				(font
					(size 1.27 1.27)
				)
				(justify mirror)
			)
		)
		(property "Value" "10KR2F-2-GP"
			(at -0.064008 -3.993896 0)
			(unlocked yes)
			(layer "B.Fab")
			(hide yes)
			(effects
				(font
					(size 1.016 1.016)
					(thickness 0.1524)
				)
				(justify mirror)
			)
		)
		(property "Device Type" "R402H16"
			(at -0.064008 -5.517896 0)
			(unlocked yes)
			(layer "B.Fab")
			(hide yes)
			(effects
				(font
					(size 1.016 1.016)
					(thickness 0.1524)
				)
				(justify mirror)
			)
		)
		(duplicate_pad_numbers_are_jumpers no)
		(fp_line
			(start -0.508 -0.9398)
			(end 0.508 -0.9398)
			(stroke
				(width 0.1524)
				(type default)
			)
			(layer "B.SilkS")
		)
		(fp_line
			(start 0.508 -0.9398)
			(end 0.508 0.9398)
			(stroke
				(width 0.1524)
				(type default)
			)
			(layer "B.SilkS")
		)
		(fp_rect
			(start 0.508 0.9398)
			(end -0.508 -0.9398)
			(stroke
				(width 0)
				(type default)
			)
			(fill no)
			(layer "B.CrtYd")
		)
		(fp_rect
			(start 0.508 0.9398)
			(end -0.508 -0.9398)
			(stroke
				(width 0)
				(type default)
			)
			(fill no)
			(layer "B.Fab")
		)
		(pad "1" smd custom
			(at 0 -0.4445 180)
			(size 0.1397 0.1397)
			(layers "B.Cu" "B.Mask" "B.Paste")
			(net "P3V3")
			(options
				(clearance outline)
				(anchor circle)
			)
			(primitives
				(gr_poly
					(pts
						(arc
							(start -0.1778 0.2794)
							(mid -0.249642 0.249642)
							(end -0.2794 0.1778)
						)
						(arc
							(start -0.2794 -0.1778)
							(mid -0.249642 -0.249642)
							(end -0.1778 -0.2794)
						)
						(arc
							(start 0.1778 -0.2794)
							(mid 0.249642 -0.249642)
							(end 0.2794 -0.1778)
						)
						(arc
							(start 0.2794 0.1778)
							(mid 0.249642 0.249642)
							(end 0.1778 0.2794)
						)
					)
					(width 0)
					(fill yes)
				)
			)
		)
		(pad "2" smd custom
			(at 0 0.4445 180)
			(size 0.1397 0.1397)
			(layers "B.Cu" "B.Mask" "B.Paste")
			(net "LS_EN_N")
			(options
				(clearance outline)
				(anchor circle)
			)
			(primitives
				(gr_poly
					(pts
						(arc
							(start -0.1778 0.2794)
							(mid -0.249642 0.249642)
							(end -0.2794 0.1778)
						)
						(arc
							(start -0.2794 -0.1778)
							(mid -0.249642 -0.249642)
							(end -0.1778 -0.2794)
						)
						(arc
							(start 0.1778 -0.2794)
							(mid 0.249642 -0.249642)
							(end 0.2794 -0.1778)
						)
						(arc
							(start 0.2794 0.1778)
							(mid 0.249642 0.249642)
							(end 0.1778 0.2794)
						)
					)
					(width 0)
					(fill yes)
				)
			)
		)
	)
	(footprint ""
		(layer "B.Cu")
		(at 70.485 -39.751 90)
		(property "Reference" "L17"
			(at 0 0 90)
			(layer "B.SilkS")
			(hide yes)
			(effects
				(font
					(size 1.27 1.27)
				)
				(justify mirror)
			)
		)
		(property "Value" "MPZ2012S300AT-GP"
			(at 0 -4.2418 90)
			(unlocked yes)
			(layer "B.Fab")
			(hide yes)
			(effects
				(font
					(size 1.016 1.016)
					(thickness 0.1524)
				)
				(justify mirror)
			)
		)
		(property "Device Type" "L805H42"
			(at 0 -5.7912 90)
			(unlocked yes)
			(layer "B.Fab")
			(hide yes)
			(effects
				(font
					(size 1.016 1.016)
					(thickness 0.1524)
				)
				(justify mirror)
			)
		)
		(duplicate_pad_numbers_are_jumpers no)
		(fp_line
			(start 0.889 -1.7018)
			(end -0.889 -1.7018)
			(stroke
				(width 0.1524)
				(type default)
			)
			(layer "B.SilkS")
		)
		(fp_line
			(start -0.889 -1.7018)
			(end -0.889 1.7018)
			(stroke
				(width 0.1524)
				(type default)
			)
			(layer "B.SilkS")
		)
		(fp_line
			(start 0.889 1.7018)
			(end 0.889 -1.7018)
			(stroke
				(width 0.1524)
				(type default)
			)
			(layer "B.SilkS")
		)
		(fp_line
			(start -0.889 1.7018)
			(end 0.889 1.7018)
			(stroke
				(width 0.1524)
				(type default)
			)
			(layer "B.SilkS")
		)
		(fp_rect
			(start 0.9652 1.778)
			(end -0.9652 -1.778)
			(stroke
				(width 0)
				(type default)
			)
			(fill no)
			(layer "B.CrtYd")
		)
		(fp_rect
			(start 0.9652 1.778)
			(end -0.9652 -1.778)
			(stroke
				(width 0)
				(type default)
			)
			(fill no)
			(layer "B.Fab")
		)
		(pad "1" smd rect
			(at 0 -0.9652 270)
			(size 1.397 1.143)
			(layers "B.Cu" "B.Mask" "B.Paste")
			(net "P0V9")
		)
		(pad "2" smd rect
			(at 0 0.9652 270)
			(size 1.397 1.143)
			(layers "B.Cu" "B.Mask" "B.Paste")
			(net "GB_VDDA")
		)
	)
	(footprint ""
		(layer "B.Cu")
		(at 134.493254 -64.507618 -90)
		(property "Reference" "C22"
			(at 0 0 90)
			(layer "B.SilkS")
			(hide yes)
			(effects
				(font
					(size 1.27 1.27)
				)
				(justify mirror)
			)
		)
		(property "Value" "SCD01U16V1KX-GP"
			(at 2.8321 -1.7399 270)
			(unlocked yes)
			(layer "B.Fab")
			(hide yes)
			(effects
				(font
					(size 1.016 1.016)
					(thickness 0.1524)
				)
				(justify mirror)
			)
		)
		(property "Device Type" "C0201H13"
			(at 2.8321 -3.2639 270)
			(unlocked yes)
			(layer "B.Fab")
			(hide yes)
			(effects
				(font
					(size 1.016 1.016)
					(thickness 0.1524)
				)
				(justify mirror)
			)
		)
		(duplicate_pad_numbers_are_jumpers no)
		(fp_rect
			(start 0.2794 0.6477)
			(end -0.2794 -0.6477)
			(stroke
				(width 0)
				(type default)
			)
			(fill no)
			(layer "B.CrtYd")
		)
		(fp_rect
			(start 0.2794 0.6477)
			(end -0.2794 -0.6477)
			(stroke
				(width 0)
				(type default)
			)
			(fill no)
			(layer "B.Fab")
		)
		(pad "1" smd custom
			(at 0 -0.2794 90)
			(size 0.0762 0.0762)
			(layers "B.Cu" "B.Mask" "B.Paste")
			(net "PHY_DPB_TO_SCC_1_DN")
			(options
				(clearance outline)
				(anchor circle)
			)
			(primitives
				(gr_poly
					(pts
						(arc
							(start 0.1524 0.127)
							(mid 0.137521 0.162921)
							(end 0.1016 0.1778)
						)
						(arc
							(start -0.1016 0.1778)
							(mid -0.137521 0.162921)
							(end -0.1524 0.127)
						)
						(arc
							(start -0.1524 -0.127)
							(mid -0.137521 -0.162921)
							(end -0.1016 -0.1778)
						)
						(arc
							(start 0.1016 -0.1778)
							(mid 0.137521 -0.162921)
							(end 0.1524 -0.127)
						)
					)
					(width 0)
					(fill yes)
				)
			)
		)
		(pad "2" smd custom
			(at 0 0.2794 90)
			(size 0.0762 0.0762)
			(layers "B.Cu" "B.Mask" "B.Paste")
			(net "PHY_DPB_TO_SCC_C_1_DN")
			(options
				(clearance outline)
				(anchor circle)
			)
			(primitives
				(gr_poly
					(pts
						(arc
							(start 0.1524 0.127)
							(mid 0.137521 0.162921)
							(end 0.1016 0.1778)
						)
						(arc
							(start -0.1016 0.1778)
							(mid -0.137521 0.162921)
							(end -0.1524 0.127)
						)
						(arc
							(start -0.1524 -0.127)
							(mid -0.137521 -0.162921)
							(end -0.1016 -0.1778)
						)
						(arc
							(start 0.1016 -0.1778)
							(mid 0.137521 -0.162921)
							(end 0.1524 -0.127)
						)
					)
					(width 0)
					(fill yes)
				)
			)
		)
	)
	(footprint ""
		(layer "B.Cu")
		(at 80.518 -85.217 180)
		(property "Reference" "U13"
			(at 0 0 0)
			(layer "B.SilkS")
			(hide yes)
			(effects
				(font
					(size 1.27 1.27)
				)
				(justify mirror)
			)
		)
		(property "Value" "S29GL128S10TFIV20-GP"
			(at 0.1778 -20.32 180)
			(unlocked yes)
			(layer "B.Fab")
			(hide yes)
			(effects
				(font
					(size 1.016 1.016)
					(thickness 0.1524)
				)
				(justify mirror)
			)
		)
		(property "Device Type" "TSOP56-1H48"
			(at 0.1778 -22.225 180)
			(unlocked yes)
			(layer "B.Fab")
			(hide yes)
			(effects
				(font
					(size 1.016 1.016)
					(thickness 0.1524)
				)
				(justify mirror)
			)
		)
		(duplicate_pad_numbers_are_jumpers no)
		(fp_line
			(start 7.5438 8.5598)
			(end -6.8326 8.5598)
			(stroke
				(width 0.1524)
				(type default)
			)
			(layer "B.SilkS")
		)
		(fp_line
			(start 7.5438 -0.4318)
			(end 7.112 0)
			(stroke
				(width 0.1524)
				(type default)
			)
			(layer "B.SilkS")
		)
		(fp_line
			(start 7.5438 -8.5598)
			(end 7.5438 8.5598)
			(stroke
				(width 0.1524)
				(type default)
			)
			(layer "B.SilkS")
		)
		(fp_line
			(start 7.366 8.5598)
			(end 7.366 10.795)
			(stroke
				(width 0.508)
				(type default)
			)
			(layer "B.SilkS")
		)
		(fp_line
			(start 7.112 0)
			(end 7.5438 0.4318)
			(stroke
				(width 0.1524)
				(type default)
			)
			(layer "B.SilkS")
		)
		(fp_line
			(start -6.8326 8.5598)
			(end -6.8326 -8.5598)
			(stroke
				(width 0.1524)
				(type default)
			)
			(layer "B.SilkS")
		)
		(fp_line
			(start -6.8326 -8.5598)
			(end 7.5438 -8.5598)
			(stroke
				(width 0.1524)
				(type default)
			)
			(layer "B.SilkS")
		)
		(fp_poly
			(pts
				(xy 7.62 11.049) (xy -7.62 11.049) (xy -7.62 -11.049) (xy 7.62 -11.049)
			)
			(stroke
				(width 0)
				(type default)
			)
			(fill no)
			(layer "B.CrtYd")
		)
		(fp_poly
			(pts
				(xy 7.62 -11.049) (xy -7.62 -11.049) (xy -7.62 11.049) (xy 7.62 11.049)
			)
			(stroke
				(width 0)
				(type default)
			)
			(fill no)
			(layer "B.Fab")
		)
		(pad "1" smd rect
			(at 6.75005 9.6139)
			(size 0.3048 1.524)
			(layers "B.Cu" "B.Mask" "B.Paste")
			(net "Net_772")
		)
		(pad "2" smd rect
			(at 6.24967 9.6139)
			(size 0.3048 1.524)
			(layers "B.Cu" "B.Mask" "B.Paste")
			(net "EXP_XM_ADDR_23")
		)
		(pad "3" smd rect
			(at 5.75056 9.6139)
			(size 0.3048 1.524)
			(layers "B.Cu" "B.Mask" "B.Paste")
			(net "EXP_XM_ADDR_16")
		)
		(pad "4" smd rect
			(at 5.25018 9.6139)
			(size 0.3048 1.524)
			(layers "B.Cu" "B.Mask" "B.Paste")
			(net "EXP_XM_ADDR_15")
		)
		(pad "5" smd rect
			(at 4.7498 9.6139)
			(size 0.3048 1.524)
			(layers "B.Cu" "B.Mask" "B.Paste")
			(net "EXP_XM_ADDR_14")
		)
		(pad "6" smd rect
			(at 4.24942 9.6139)
			(size 0.3048 1.524)
			(layers "B.Cu" "B.Mask" "B.Paste")
			(net "EXP_XM_ADDR_13")
		)
		(pad "7" smd rect
			(at 3.75031 9.6139)
			(size 0.3048 1.524)
			(layers "B.Cu" "B.Mask" "B.Paste")
			(net "EXP_XM_ADDR_12")
		)
		(pad "8" smd rect
			(at 3.24993 9.6139)
			(size 0.3048 1.524)
			(layers "B.Cu" "B.Mask" "B.Paste")
			(net "EXP_XM_ADDR_11")
		)
		(pad "9" smd rect
			(at 2.74955 9.6139)
			(size 0.3048 1.524)
			(layers "B.Cu" "B.Mask" "B.Paste")
			(net "EXP_XM_ADDR_10")
		)
		(pad "10" smd rect
			(at 2.25044 9.6139)
			(size 0.3048 1.524)
			(layers "B.Cu" "B.Mask" "B.Paste")
			(net "EXP_XM_ADDR_9")
		)
		(pad "11" smd rect
			(at 1.75006 9.6139)
			(size 0.3048 1.524)
			(layers "B.Cu" "B.Mask" "B.Paste")
			(net "EXP_XM_ADDR_20")
		)
		(pad "12" smd rect
			(at 1.24968 9.6139)
			(size 0.3048 1.524)
			(layers "B.Cu" "B.Mask" "B.Paste")
			(net "EXP_XM_ADDR_21")
		)
		(pad "13" smd rect
			(at 0.75057 9.6139)
			(size 0.3048 1.524)
			(layers "B.Cu" "B.Mask" "B.Paste")
			(net "EXP_XM_WE_N")
		)
		(pad "14" smd rect
			(at 0.25019 9.6139)
			(size 0.3048 1.524)
			(layers "B.Cu" "B.Mask" "B.Paste")
			(net "FW_RESET_N")
		)
		(pad "15" smd rect
			(at -0.25019 9.6139)
			(size 0.3048 1.524)
			(layers "B.Cu" "B.Mask" "B.Paste")
			(net "EXP_XM_ADDR_22")
		)
		(pad "16" smd rect
			(at -0.75057 9.6139)
			(size 0.3048 1.524)
			(layers "B.Cu" "B.Mask" "B.Paste")
			(net "EXP_WP_N")
		)
		(pad "17" smd rect
			(at -1.24968 9.6139)
			(size 0.3048 1.524)
			(layers "B.Cu" "B.Mask" "B.Paste")
			(net "EXP_XM_BUSY_N")
		)
		(pad "18" smd rect
			(at -1.75006 9.6139)
			(size 0.3048 1.524)
			(layers "B.Cu" "B.Mask" "B.Paste")
			(net "EXP_XM_ADDR_19")
		)
		(pad "19" smd rect
			(at -2.25044 9.6139)
			(size 0.3048 1.524)
			(layers "B.Cu" "B.Mask" "B.Paste")
			(net "EXP_XM_ADDR_18")
		)
		(pad "20" smd rect
			(at -2.74955 9.6139)
			(size 0.3048 1.524)
			(layers "B.Cu" "B.Mask" "B.Paste")
			(net "EXP_XM_ADDR_8")
		)
		(pad "21" smd rect
			(at -3.24993 9.6139)
			(size 0.3048 1.524)
			(layers "B.Cu" "B.Mask" "B.Paste")
			(net "EXP_XM_ADDR_7")
		)
		(pad "22" smd rect
			(at -3.75031 9.6139)
			(size 0.3048 1.524)
			(layers "B.Cu" "B.Mask" "B.Paste")
			(net "EXP_XM_ADDR_6")
		)
		(pad "23" smd rect
			(at -4.24942 9.6139)
			(size 0.3048 1.524)
			(layers "B.Cu" "B.Mask" "B.Paste")
			(net "EXP_XM_ADDR_5")
		)
		(pad "24" smd rect
			(at -4.7498 9.6139)
			(size 0.3048 1.524)
			(layers "B.Cu" "B.Mask" "B.Paste")
			(net "EXP_XM_ADDR_4")
		)
		(pad "25" smd rect
			(at -5.25018 9.6139)
			(size 0.3048 1.524)
			(layers "B.Cu" "B.Mask" "B.Paste")
			(net "EXP_XM_ADDR_3")
		)
		(pad "26" smd rect
			(at -5.75056 9.6139)
			(size 0.3048 1.524)
			(layers "B.Cu" "B.Mask" "B.Paste")
			(net "EXP_XM_ADDR_2")
		)
		(pad "27" smd rect
			(at -6.24967 9.6139)
			(size 0.3048 1.524)
			(layers "B.Cu" "B.Mask" "B.Paste")
			(net "Net_768")
		)
		(pad "28" smd rect
			(at -6.75005 9.6139)
			(size 0.3048 1.524)
			(layers "B.Cu" "B.Mask" "B.Paste")
			(net "Net_769")
		)
		(pad "29" smd rect
			(at -6.75005 -9.6139)
			(size 0.3048 1.524)
			(layers "B.Cu" "B.Mask" "B.Paste")
			(net "P1V8_E")
		)
		(pad "30" smd rect
			(at -6.24967 -9.6139)
			(size 0.3048 1.524)
			(layers "B.Cu" "B.Mask" "B.Paste")
			(net "Net_767")
		)
		(pad "31" smd rect
			(at -5.75056 -9.6139)
			(size 0.3048 1.524)
			(layers "B.Cu" "B.Mask" "B.Paste")
			(net "EXP_XM_ADDR_1")
		)
		(pad "32" smd rect
			(at -5.25018 -9.6139)
			(size 0.3048 1.524)
			(layers "B.Cu" "B.Mask" "B.Paste")
			(net "EXP_XM_NOR_CS_N")
		)
		(pad "33" smd rect
			(at -4.7498 -9.6139)
			(size 0.3048 1.524)
			(layers "B.Cu" "B.Mask" "B.Paste")
			(net "GND")
		)
		(pad "34" smd rect
			(at -4.24942 -9.6139)
			(size 0.3048 1.524)
			(layers "B.Cu" "B.Mask" "B.Paste")
			(net "EXP_XM_OE_N")
		)
		(pad "35" smd rect
			(at -3.75031 -9.6139)
			(size 0.3048 1.524)
			(layers "B.Cu" "B.Mask" "B.Paste")
			(net "XM_DATA0")
		)
		(pad "36" smd rect
			(at -3.24993 -9.6139)
			(size 0.3048 1.524)
			(layers "B.Cu" "B.Mask" "B.Paste")
			(net "XM_DATA8")
		)
		(pad "37" smd rect
			(at -2.74955 -9.6139)
			(size 0.3048 1.524)
			(layers "B.Cu" "B.Mask" "B.Paste")
			(net "XM_DATA1")
		)
		(pad "38" smd rect
			(at -2.25044 -9.6139)
			(size 0.3048 1.524)
			(layers "B.Cu" "B.Mask" "B.Paste")
			(net "XM_DATA9")
		)
		(pad "39" smd rect
			(at -1.75006 -9.6139)
			(size 0.3048 1.524)
			(layers "B.Cu" "B.Mask" "B.Paste")
			(net "XM_DATA2")
		)
		(pad "40" smd rect
			(at -1.24968 -9.6139)
			(size 0.3048 1.524)
			(layers "B.Cu" "B.Mask" "B.Paste")
			(net "XM_DATA10")
		)
		(pad "41" smd rect
			(at -0.75057 -9.6139)
			(size 0.3048 1.524)
			(layers "B.Cu" "B.Mask" "B.Paste")
			(net "XM_DATA3")
		)
		(pad "42" smd rect
			(at -0.25019 -9.6139)
			(size 0.3048 1.524)
			(layers "B.Cu" "B.Mask" "B.Paste")
			(net "XM_DATA11")
		)
		(pad "43" smd rect
			(at 0.25019 -9.6139)
			(size 0.3048 1.524)
			(layers "B.Cu" "B.Mask" "B.Paste")
			(net "P3V3")
		)
		(pad "44" smd rect
			(at 0.75057 -9.6139)
			(size 0.3048 1.524)
			(layers "B.Cu" "B.Mask" "B.Paste")
			(net "XM_DATA4")
		)
		(pad "45" smd rect
			(at 1.24968 -9.6139)
			(size 0.3048 1.524)
			(layers "B.Cu" "B.Mask" "B.Paste")
			(net "XM_DATA12")
		)
		(pad "46" smd rect
			(at 1.75006 -9.6139)
			(size 0.3048 1.524)
			(layers "B.Cu" "B.Mask" "B.Paste")
			(net "XM_DATA5")
		)
		(pad "47" smd rect
			(at 2.25044 -9.6139)
			(size 0.3048 1.524)
			(layers "B.Cu" "B.Mask" "B.Paste")
			(net "XM_DATA13")
		)
		(pad "48" smd rect
			(at 2.74955 -9.6139)
			(size 0.3048 1.524)
			(layers "B.Cu" "B.Mask" "B.Paste")
			(net "XM_DATA6")
		)
		(pad "49" smd rect
			(at 3.24993 -9.6139)
			(size 0.3048 1.524)
			(layers "B.Cu" "B.Mask" "B.Paste")
			(net "XM_DATA14")
		)
		(pad "50" smd rect
			(at 3.75031 -9.6139)
			(size 0.3048 1.524)
			(layers "B.Cu" "B.Mask" "B.Paste")
			(net "XM_DATA7")
		)
		(pad "51" smd rect
			(at 4.24942 -9.6139)
			(size 0.3048 1.524)
			(layers "B.Cu" "B.Mask" "B.Paste")
			(net "XM_DATA15")
		)
		(pad "52" smd rect
			(at 4.7498 -9.6139)
			(size 0.3048 1.524)
			(layers "B.Cu" "B.Mask" "B.Paste")
			(net "GND")
		)
		(pad "53" smd rect
			(at 5.25018 -9.6139)
			(size 0.3048 1.524)
			(layers "B.Cu" "B.Mask" "B.Paste")
			(net "EXP_BYTE_N")
		)
		(pad "54" smd rect
			(at 5.75056 -9.6139)
			(size 0.3048 1.524)
			(layers "B.Cu" "B.Mask" "B.Paste")
			(net "EXP_XM_ADDR_17")
		)
		(pad "55" smd rect
			(at 6.24967 -9.6139)
			(size 0.3048 1.524)
			(layers "B.Cu" "B.Mask" "B.Paste")
			(net "Net_770")
		)
		(pad "56" smd rect
			(at 6.75005 -9.6139)
			(size 0.3048 1.524)
			(layers "B.Cu" "B.Mask" "B.Paste")
			(net "Net_771")
		)
	)
	(footprint ""
		(layer "B.Cu")
		(at 140.2334 -87.1982)
		(property "Reference" "TP169"
			(at 0 0 0)
			(layer "B.SilkS")
			(hide yes)
			(effects
				(font
					(size 1.27 1.27)
				)
				(justify mirror)
			)
		)
		(property "Value" "TPAD28-2-GP"
			(at 0.0127 -1.6637 0)
			(unlocked yes)
			(layer "B.Fab")
			(hide yes)
			(effects
				(font
					(size 1.016 1.016)
					(thickness 0.1524)
				)
				(justify mirror)
			)
		)
		(property "Device Type" "TPAD28"
			(at 0.0127 -3.1877 0)
			(unlocked yes)
			(layer "B.Fab")
			(hide yes)
			(effects
				(font
					(size 1.016 1.016)
					(thickness 0.1524)
				)
				(justify mirror)
			)
		)
		(duplicate_pad_numbers_are_jumpers no)
		(fp_poly
			(pts
				(arc
					(start 0.3556 0)
					(mid -0.3556 0)
					(end 0.3556 0)
				)
			)
			(stroke
				(width 0)
				(type default)
			)
			(fill no)
			(layer "B.CrtYd")
		)
		(fp_poly
			(pts
				(arc
					(start 0.6096 0)
					(mid -0.6096 0)
					(end 0.6096 0)
				)
			)
			(stroke
				(width 0)
				(type default)
			)
			(fill no)
			(layer "B.Fab")
		)
		(pad "1" smd circle
			(at 0 0 180)
			(size 0.7112 0.7112)
			(layers "B.Cu" "B.Mask" "B.Paste")
			(net "EXP_I2C_SCL9")
		)
	)
	(footprint ""
		(layer "B.Cu")
		(at 183.822848 -117.696234 90)
		(property "Reference" "Q35"
			(at 0 0 90)
			(layer "B.SilkS")
			(hide yes)
			(effects
				(font
					(size 1.27 1.27)
				)
				(justify mirror)
			)
		)
		(property "Value" "FDS8878-G-GP"
			(at 3.707384 -1.5367 90)
			(unlocked yes)
			(layer "B.Fab")
			(hide yes)
			(effects
				(font
					(size 1.016 1.016)
					(thickness 0.1524)
				)
				(justify mirror)
			)
		)
		(property "Device Type" "SOIC8H69"
			(at 3.707384 -3.0607 90)
			(unlocked yes)
			(layer "B.Fab")
			(hide yes)
			(effects
				(font
					(size 1.016 1.016)
					(thickness 0.1524)
				)
				(justify mirror)
			)
		)
		(duplicate_pad_numbers_are_jumpers no)
		(fp_line
			(start 2.7432 -1.4224)
			(end 2.7432 1.4224)
			(stroke
				(width 0.1524)
				(type default)
			)
			(layer "B.SilkS")
		)
		(fp_line
			(start -2.1336 -1.4224)
			(end 2.7432 -1.4224)
			(stroke
				(width 0.1524)
				(type default)
			)
			(layer "B.SilkS")
		)
		(fp_line
			(start 2.7178 -0.508)
			(end 2.1844 -0.0508)
			(stroke
				(width 0.1524)
				(type default)
			)
			(layer "B.SilkS")
		)
		(fp_line
			(start 2.1844 -0.0508)
			(end 2.7178 0.508)
			(stroke
				(width 0.1524)
				(type default)
			)
			(layer "B.SilkS")
		)
		(fp_line
			(start 2.7432 1.4224)
			(end 2.6416 1.4224)
			(stroke
				(width 0.1524)
				(type default)
			)
			(layer "B.SilkS")
		)
		(fp_line
			(start 2.7432 1.4224)
			(end -2.1336 1.4224)
			(stroke
				(width 0.1524)
				(type default)
			)
			(layer "B.SilkS")
		)
		(fp_line
			(start -2.1336 1.4224)
			(end -2.1336 -1.4224)
			(stroke
				(width 0.1524)
				(type default)
			)
			(layer "B.SilkS")
		)
		(fp_line
			(start 2.6289 3.4417)
			(end 2.6289 1.4732)
			(stroke
				(width 0.381)
				(type default)
			)
			(layer "B.SilkS")
		)
		(fp_poly
			(pts
				(xy 2.2098 -1.4224) (xy 2.2098 1.4224) (xy -2.2098 1.4224) (xy -2.2098 -1.4224)
			)
			(stroke
				(width 0)
				(type default)
			)
			(fill yes)
			(layer "B.SilkS")
		)
		(fp_rect
			(start 2.450084 2.999994)
			(end -2.450084 -2.999994)
			(stroke
				(width 0)
				(type default)
			)
			(fill no)
			(layer "B.CrtYd")
		)
		(fp_poly
			(pts
				(xy 2.8194 3.6322) (xy 2.8194 -3.6322) (xy -2.8194 -3.6322) (xy -2.8194 1.18364) (xy -2.450084 1.18364)
				(xy -2.450084 -2.999994) (xy 2.450084 -2.999994) (xy 2.450084 2.999994) (xy -2.450084 2.999994)
				(xy -2.450084 1.18618) (xy -2.8194 1.18618) (xy -2.8194 3.6322)
			)
			(stroke
				(width 0)
				(type default)
			)
			(fill no)
			(layer "B.CrtYd")
		)
		(fp_rect
			(start 2.8194 3.6322)
			(end -2.8194 -3.6322)
			(stroke
				(width 0)
				(type default)
			)
			(fill no)
			(layer "B.Fab")
		)
		(pad "1" smd rect
			(at 1.905 2.54 270)
			(size 0.635 1.651)
			(layers "B.Cu" "B.Mask" "B.Paste")
			(net "P1V8_C")
		)
		(pad "2" smd rect
			(at 0.635 2.54 270)
			(size 0.635 1.651)
			(layers "B.Cu" "B.Mask" "B.Paste")
			(net "P1V8_C")
		)
		(pad "3" smd rect
			(at -0.635 2.54 270)
			(size 0.635 1.651)
			(layers "B.Cu" "B.Mask" "B.Paste")
			(net "P1V8_C")
		)
		(pad "4" smd rect
			(at -1.905 2.54 270)
			(size 0.635 1.651)
			(layers "B.Cu" "B.Mask" "B.Paste")
			(net "P1V8_C_G_PG")
		)
		(pad "5" smd rect
			(at -1.905 -2.54 270)
			(size 0.635 1.651)
			(layers "B.Cu" "B.Mask" "B.Paste")
			(net "P1V8_E_OUT")
		)
		(pad "6" smd rect
			(at -0.635 -2.54 270)
			(size 0.635 1.651)
			(layers "B.Cu" "B.Mask" "B.Paste")
			(net "P1V8_E_OUT")
		)
		(pad "7" smd rect
			(at 0.635 -2.54 270)
			(size 0.635 1.651)
			(layers "B.Cu" "B.Mask" "B.Paste")
			(net "P1V8_E_OUT")
		)
		(pad "8" smd rect
			(at 1.905 -2.54 270)
			(size 0.635 1.651)
			(layers "B.Cu" "B.Mask" "B.Paste")
			(net "P1V8_E_OUT")
		)
	)
	(footprint ""
		(layer "B.Cu")
		(at 113.284 -64.4779)
		(property "Reference" "C159"
			(at 0 0 0)
			(layer "B.SilkS")
			(hide yes)
			(effects
				(font
					(size 1.27 1.27)
				)
				(justify mirror)
			)
		)
		(property "Value" "SCD1U6D3V1KX-GP"
			(at 2.8321 -1.7399 0)
			(unlocked yes)
			(layer "B.Fab")
			(hide yes)
			(effects
				(font
					(size 1.016 1.016)
					(thickness 0.1524)
				)
				(justify mirror)
			)
		)
		(property "Device Type" "C0201H13"
			(at 2.8321 -3.2639 0)
			(unlocked yes)
			(layer "B.Fab")
			(hide yes)
			(effects
				(font
					(size 1.016 1.016)
					(thickness 0.1524)
				)
				(justify mirror)
			)
		)
		(duplicate_pad_numbers_are_jumpers no)
		(fp_rect
			(start 0.2794 0.6477)
			(end -0.2794 -0.6477)
			(stroke
				(width 0)
				(type default)
			)
			(fill no)
			(layer "B.CrtYd")
		)
		(fp_rect
			(start 0.2794 0.6477)
			(end -0.2794 -0.6477)
			(stroke
				(width 0)
				(type default)
			)
			(fill no)
			(layer "B.Fab")
		)
		(pad "1" smd custom
			(at 0 -0.2794 180)
			(size 0.0762 0.0762)
			(layers "B.Cu" "B.Mask" "B.Paste")
			(net "P0V9")
			(options
				(clearance outline)
				(anchor circle)
			)
			(primitives
				(gr_poly
					(pts
						(arc
							(start 0.1524 0.127)
							(mid 0.137521 0.162921)
							(end 0.1016 0.1778)
						)
						(arc
							(start -0.1016 0.1778)
							(mid -0.137521 0.162921)
							(end -0.1524 0.127)
						)
						(arc
							(start -0.1524 -0.127)
							(mid -0.137521 -0.162921)
							(end -0.1016 -0.1778)
						)
						(arc
							(start 0.1016 -0.1778)
							(mid 0.137521 -0.162921)
							(end 0.1524 -0.127)
						)
					)
					(width 0)
					(fill yes)
				)
			)
		)
		(pad "2" smd custom
			(at 0 0.2794 180)
			(size 0.0762 0.0762)
			(layers "B.Cu" "B.Mask" "B.Paste")
			(net "GND")
			(options
				(clearance outline)
				(anchor circle)
			)
			(primitives
				(gr_poly
					(pts
						(arc
							(start 0.1524 0.127)
							(mid 0.137521 0.162921)
							(end 0.1016 0.1778)
						)
						(arc
							(start -0.1016 0.1778)
							(mid -0.137521 0.162921)
							(end -0.1524 0.127)
						)
						(arc
							(start -0.1524 -0.127)
							(mid -0.137521 -0.162921)
							(end -0.1016 -0.1778)
						)
						(arc
							(start 0.1016 -0.1778)
							(mid 0.137521 -0.162921)
							(end 0.1524 -0.127)
						)
					)
					(width 0)
					(fill yes)
				)
			)
		)
	)
	(footprint ""
		(layer "B.Cu")
		(at 127.970788 -57.4929 -90)
		(property "Reference" "C257"
			(at 0 0 90)
			(layer "B.SilkS")
			(hide yes)
			(effects
				(font
					(size 1.27 1.27)
				)
				(justify mirror)
			)
		)
		(property "Value" "SC1U6D3V1MX-GP"
			(at -1.9177 2.0193 270)
			(unlocked yes)
			(layer "B.Fab")
			(hide yes)
			(effects
				(font
					(size 1.016 1.016)
					(thickness 0.1524)
				)
				(justify mirror)
			)
		)
		(property "Device Type" "C0201H14"
			(at -1.9177 0.4953 270)
			(unlocked yes)
			(layer "B.Fab")
			(hide yes)
			(effects
				(font
					(size 1.016 1.016)
					(thickness 0.1524)
				)
				(justify mirror)
			)
		)
		(duplicate_pad_numbers_are_jumpers no)
		(fp_rect
			(start 0.1524 0.3048)
			(end -0.1524 -0.3048)
			(stroke
				(width 0)
				(type default)
			)
			(fill no)
			(layer "B.CrtYd")
		)
		(fp_poly
			(pts
				(xy 0.2794 0.6477) (xy 0.2794 -0.6477) (xy -0.2794 -0.6477) (xy -0.2794 -0.1905) (xy -0.1524 -0.1905)
				(xy -0.1524 -0.3048) (xy 0.1524 -0.3048) (xy 0.1524 0.3048) (xy -0.1524 0.3048) (xy -0.1524 -0.1778)
				(xy -0.2794 -0.1778) (xy -0.2794 0.6477)
			)
			(stroke
				(width 0)
				(type default)
			)
			(fill no)
			(layer "B.CrtYd")
		)
		(fp_rect
			(start 0.2794 0.6477)
			(end -0.2794 -0.6477)
			(stroke
				(width 0)
				(type default)
			)
			(fill no)
			(layer "B.Fab")
		)
		(pad "1" smd custom
			(at 0 -0.2794 90)
			(size 0.0762 0.0762)
			(layers "B.Cu" "B.Mask" "B.Paste")
			(net "GB_VDDA")
			(options
				(clearance outline)
				(anchor circle)
			)
			(primitives
				(gr_poly
					(pts
						(arc
							(start 0.1524 0.127)
							(mid 0.137521 0.162921)
							(end 0.1016 0.1778)
						)
						(arc
							(start -0.1016 0.1778)
							(mid -0.137521 0.162921)
							(end -0.1524 0.127)
						)
						(arc
							(start -0.1524 -0.127)
							(mid -0.137521 -0.162921)
							(end -0.1016 -0.1778)
						)
						(arc
							(start 0.1016 -0.1778)
							(mid 0.137521 -0.162921)
							(end 0.1524 -0.127)
						)
					)
					(width 0)
					(fill yes)
				)
			)
		)
		(pad "2" smd custom
			(at 0 0.2794 90)
			(size 0.0762 0.0762)
			(layers "B.Cu" "B.Mask" "B.Paste")
			(net "GND")
			(options
				(clearance outline)
				(anchor circle)
			)
			(primitives
				(gr_poly
					(pts
						(arc
							(start 0.1524 0.127)
							(mid 0.137521 0.162921)
							(end 0.1016 0.1778)
						)
						(arc
							(start -0.1016 0.1778)
							(mid -0.137521 0.162921)
							(end -0.1524 0.127)
						)
						(arc
							(start -0.1524 -0.127)
							(mid -0.137521 -0.162921)
							(end -0.1016 -0.1778)
						)
						(arc
							(start 0.1016 -0.1778)
							(mid 0.137521 -0.162921)
							(end 0.1524 -0.127)
						)
					)
					(width 0)
					(fill yes)
				)
			)
		)
	)
	(footprint ""
		(layer "B.Cu")
		(at 62.1792 -60.579 -90)
		(property "Reference" "C614"
			(at 0 0 90)
			(layer "B.SilkS")
			(hide yes)
			(effects
				(font
					(size 1.27 1.27)
				)
				(justify mirror)
			)
		)
		(property "Value" "SC10U6D3V5KX-4GP"
			(at 0.0762 -6.1214 270)
			(unlocked yes)
			(layer "B.Fab")
			(hide yes)
			(effects
				(font
					(size 1.016 1.016)
					(thickness 0.1524)
				)
				(justify mirror)
			)
		)
		(property "Device Type" "C805H58"
			(at 0.0762 -8.1534 270)
			(unlocked yes)
			(layer "B.Fab")
			(hide yes)
			(effects
				(font
					(size 1.016 1.016)
					(thickness 0.1524)
				)
				(justify mirror)
			)
		)
		(duplicate_pad_numbers_are_jumpers no)
		(fp_line
			(start -0.635 0)
			(end 0.635 0)
			(stroke
				(width 0.508)
				(type default)
			)
			(layer "B.SilkS")
		)
		(fp_rect
			(start 0.9652 1.778)
			(end -0.9652 -1.778)
			(stroke
				(width 0)
				(type default)
			)
			(fill no)
			(layer "B.CrtYd")
		)
		(fp_poly
			(pts
				(xy 0.9652 -1.778) (xy -0.9652 -1.778) (xy -0.9652 1.778) (xy 0.9652 1.778)
			)
			(stroke
				(width 0)
				(type default)
			)
			(fill no)
			(layer "B.Fab")
		)
		(pad "1" smd rect
			(at 0 -0.9652 90)
			(size 1.397 1.143)
			(layers "B.Cu" "B.Mask" "B.Paste")
			(net "P0V9")
		)
		(pad "2" smd rect
			(at 0 0.9652 90)
			(size 1.397 1.143)
			(layers "B.Cu" "B.Mask" "B.Paste")
			(net "GND")
		)
	)
	(footprint ""
		(layer "B.Cu")
		(at 122.474228 -66.72453 -90)
		(property "Reference" "C230"
			(at 0 0 90)
			(layer "B.SilkS")
			(hide yes)
			(effects
				(font
					(size 1.27 1.27)
				)
				(justify mirror)
			)
		)
		(property "Value" "SCD1U6D3V1KX-GP"
			(at 2.8321 -1.7399 270)
			(unlocked yes)
			(layer "B.Fab")
			(hide yes)
			(effects
				(font
					(size 1.016 1.016)
					(thickness 0.1524)
				)
				(justify mirror)
			)
		)
		(property "Device Type" "C0201H13"
			(at 2.8321 -3.2639 270)
			(unlocked yes)
			(layer "B.Fab")
			(hide yes)
			(effects
				(font
					(size 1.016 1.016)
					(thickness 0.1524)
				)
				(justify mirror)
			)
		)
		(duplicate_pad_numbers_are_jumpers no)
		(fp_rect
			(start 0.2794 0.6477)
			(end -0.2794 -0.6477)
			(stroke
				(width 0)
				(type default)
			)
			(fill no)
			(layer "B.CrtYd")
		)
		(fp_rect
			(start 0.2794 0.6477)
			(end -0.2794 -0.6477)
			(stroke
				(width 0)
				(type default)
			)
			(fill no)
			(layer "B.Fab")
		)
		(pad "1" smd custom
			(at 0 -0.2794 90)
			(size 0.0762 0.0762)
			(layers "B.Cu" "B.Mask" "B.Paste")
			(net "GB_VDDA")
			(options
				(clearance outline)
				(anchor circle)
			)
			(primitives
				(gr_poly
					(pts
						(arc
							(start 0.1524 0.127)
							(mid 0.137521 0.162921)
							(end 0.1016 0.1778)
						)
						(arc
							(start -0.1016 0.1778)
							(mid -0.137521 0.162921)
							(end -0.1524 0.127)
						)
						(arc
							(start -0.1524 -0.127)
							(mid -0.137521 -0.162921)
							(end -0.1016 -0.1778)
						)
						(arc
							(start 0.1016 -0.1778)
							(mid 0.137521 -0.162921)
							(end 0.1524 -0.127)
						)
					)
					(width 0)
					(fill yes)
				)
			)
		)
		(pad "2" smd custom
			(at 0 0.2794 90)
			(size 0.0762 0.0762)
			(layers "B.Cu" "B.Mask" "B.Paste")
			(net "GND")
			(options
				(clearance outline)
				(anchor circle)
			)
			(primitives
				(gr_poly
					(pts
						(arc
							(start 0.1524 0.127)
							(mid 0.137521 0.162921)
							(end 0.1016 0.1778)
						)
						(arc
							(start -0.1016 0.1778)
							(mid -0.137521 0.162921)
							(end -0.1524 0.127)
						)
						(arc
							(start -0.1524 -0.127)
							(mid -0.137521 -0.162921)
							(end -0.1016 -0.1778)
						)
						(arc
							(start 0.1016 -0.1778)
							(mid 0.137521 -0.162921)
							(end 0.1524 -0.127)
						)
					)
					(width 0)
					(fill yes)
				)
			)
		)
	)
	(footprint ""
		(layer "B.Cu")
		(at 96.363282 -79.98333 90)
		(property "Reference" "R310"
			(at 0 0 90)
			(layer "B.SilkS")
			(hide yes)
			(effects
				(font
					(size 1.27 1.27)
				)
				(justify mirror)
			)
		)
		(property "Value" "10KR2F-2-GP"
			(at -0.064008 -3.993896 90)
			(unlocked yes)
			(layer "B.Fab")
			(hide yes)
			(effects
				(font
					(size 1.016 1.016)
					(thickness 0.1524)
				)
				(justify mirror)
			)
		)
		(property "Device Type" "R402H16"
			(at -0.064008 -5.517896 90)
			(unlocked yes)
			(layer "B.Fab")
			(hide yes)
			(effects
				(font
					(size 1.016 1.016)
					(thickness 0.1524)
				)
				(justify mirror)
			)
		)
		(duplicate_pad_numbers_are_jumpers no)
		(fp_line
			(start 0.508 -0.9398)
			(end 0.508 0.9398)
			(stroke
				(width 0.1524)
				(type default)
			)
			(layer "B.SilkS")
		)
		(fp_line
			(start -0.508 -0.9398)
			(end 0.508 -0.9398)
			(stroke
				(width 0.1524)
				(type default)
			)
			(layer "B.SilkS")
		)
		(fp_rect
			(start 0.508 0.9398)
			(end -0.508 -0.9398)
			(stroke
				(width 0)
				(type default)
			)
			(fill no)
			(layer "B.CrtYd")
		)
		(fp_rect
			(start 0.508 0.9398)
			(end -0.508 -0.9398)
			(stroke
				(width 0)
				(type default)
			)
			(fill no)
			(layer "B.Fab")
		)
		(pad "1" smd custom
			(at 0 -0.4445 270)
			(size 0.1397 0.1397)
			(layers "B.Cu" "B.Mask" "B.Paste")
			(net "P1V8_E")
			(options
				(clearance outline)
				(anchor circle)
			)
			(primitives
				(gr_poly
					(pts
						(arc
							(start -0.1778 0.2794)
							(mid -0.249642 0.249642)
							(end -0.2794 0.1778)
						)
						(arc
							(start -0.2794 -0.1778)
							(mid -0.249642 -0.249642)
							(end -0.1778 -0.2794)
						)
						(arc
							(start 0.1778 -0.2794)
							(mid 0.249642 -0.249642)
							(end 0.2794 -0.1778)
						)
						(arc
							(start 0.2794 0.1778)
							(mid 0.249642 0.249642)
							(end 0.1778 0.2794)
						)
					)
					(width 0)
					(fill yes)
				)
			)
		)
		(pad "2" smd custom
			(at 0 0.4445 270)
			(size 0.1397 0.1397)
			(layers "B.Cu" "B.Mask" "B.Paste")
			(net "FW_RESET_N")
			(options
				(clearance outline)
				(anchor circle)
			)
			(primitives
				(gr_poly
					(pts
						(arc
							(start -0.1778 0.2794)
							(mid -0.249642 0.249642)
							(end -0.2794 0.1778)
						)
						(arc
							(start -0.2794 -0.1778)
							(mid -0.249642 -0.249642)
							(end -0.1778 -0.2794)
						)
						(arc
							(start 0.1778 -0.2794)
							(mid 0.249642 -0.249642)
							(end 0.2794 -0.1778)
						)
						(arc
							(start 0.2794 0.1778)
							(mid 0.249642 0.249642)
							(end 0.1778 0.2794)
						)
					)
					(width 0)
					(fill yes)
				)
			)
		)
	)
	(footprint ""
		(layer "B.Cu")
		(at 170.636438 -45.197014 -90)
		(property "Reference" "C410"
			(at 0 0 90)
			(layer "B.SilkS")
			(hide yes)
			(effects
				(font
					(size 1.27 1.27)
				)
				(justify mirror)
			)
		)
		(property "Value" "SC10U6D3V5KX-4GP"
			(at 0.0762 -6.1214 270)
			(unlocked yes)
			(layer "B.Fab")
			(hide yes)
			(effects
				(font
					(size 1.016 1.016)
					(thickness 0.1524)
				)
				(justify mirror)
			)
		)
		(property "Device Type" "C805H58"
			(at 0.0762 -8.1534 270)
			(unlocked yes)
			(layer "B.Fab")
			(hide yes)
			(effects
				(font
					(size 1.016 1.016)
					(thickness 0.1524)
				)
				(justify mirror)
			)
		)
		(duplicate_pad_numbers_are_jumpers no)
		(fp_line
			(start -0.635 0)
			(end 0.635 0)
			(stroke
				(width 0.508)
				(type default)
			)
			(layer "B.SilkS")
		)
		(fp_rect
			(start 0.9652 1.778)
			(end -0.9652 -1.778)
			(stroke
				(width 0)
				(type default)
			)
			(fill no)
			(layer "B.CrtYd")
		)
		(fp_poly
			(pts
				(xy 0.9652 -1.778) (xy -0.9652 -1.778) (xy -0.9652 1.778) (xy 0.9652 1.778)
			)
			(stroke
				(width 0)
				(type default)
			)
			(fill no)
			(layer "B.Fab")
		)
		(pad "1" smd rect
			(at 0 -0.9652 90)
			(size 1.397 1.143)
			(layers "B.Cu" "B.Mask" "B.Paste")
			(net "P0V975")
		)
		(pad "2" smd rect
			(at 0 0.9652 90)
			(size 1.397 1.143)
			(layers "B.Cu" "B.Mask" "B.Paste")
			(net "GND")
		)
	)
	(footprint ""
		(layer "B.Cu")
		(at 121.5136 -72.263)
		(property "Reference" "C125"
			(at 0 0 0)
			(layer "B.SilkS")
			(hide yes)
			(effects
				(font
					(size 1.27 1.27)
				)
				(justify mirror)
			)
		)
		(property "Value" "SC1KP25V1KX-GP"
			(at 2.8321 -1.7399 0)
			(unlocked yes)
			(layer "B.Fab")
			(hide yes)
			(effects
				(font
					(size 1.016 1.016)
					(thickness 0.1524)
				)
				(justify mirror)
			)
		)
		(property "Device Type" "C0201H13"
			(at 2.8321 -3.2639 0)
			(unlocked yes)
			(layer "B.Fab")
			(hide yes)
			(effects
				(font
					(size 1.016 1.016)
					(thickness 0.1524)
				)
				(justify mirror)
			)
		)
		(duplicate_pad_numbers_are_jumpers no)
		(fp_rect
			(start 0.2794 0.6477)
			(end -0.2794 -0.6477)
			(stroke
				(width 0)
				(type default)
			)
			(fill no)
			(layer "B.CrtYd")
		)
		(fp_rect
			(start 0.2794 0.6477)
			(end -0.2794 -0.6477)
			(stroke
				(width 0)
				(type default)
			)
			(fill no)
			(layer "B.Fab")
		)
		(pad "1" smd custom
			(at 0 -0.2794 180)
			(size 0.0762 0.0762)
			(layers "B.Cu" "B.Mask" "B.Paste")
			(net "P1V8_E")
			(options
				(clearance outline)
				(anchor circle)
			)
			(primitives
				(gr_poly
					(pts
						(arc
							(start 0.1524 0.127)
							(mid 0.137521 0.162921)
							(end 0.1016 0.1778)
						)
						(arc
							(start -0.1016 0.1778)
							(mid -0.137521 0.162921)
							(end -0.1524 0.127)
						)
						(arc
							(start -0.1524 -0.127)
							(mid -0.137521 -0.162921)
							(end -0.1016 -0.1778)
						)
						(arc
							(start 0.1016 -0.1778)
							(mid 0.137521 -0.162921)
							(end 0.1524 -0.127)
						)
					)
					(width 0)
					(fill yes)
				)
			)
		)
		(pad "2" smd custom
			(at 0 0.2794 180)
			(size 0.0762 0.0762)
			(layers "B.Cu" "B.Mask" "B.Paste")
			(net "GND")
			(options
				(clearance outline)
				(anchor circle)
			)
			(primitives
				(gr_poly
					(pts
						(arc
							(start 0.1524 0.127)
							(mid 0.137521 0.162921)
							(end 0.1016 0.1778)
						)
						(arc
							(start -0.1016 0.1778)
							(mid -0.137521 0.162921)
							(end -0.1524 0.127)
						)
						(arc
							(start -0.1524 -0.127)
							(mid -0.137521 -0.162921)
							(end -0.1016 -0.1778)
						)
						(arc
							(start 0.1016 -0.1778)
							(mid 0.137521 -0.162921)
							(end 0.1524 -0.127)
						)
					)
					(width 0)
					(fill yes)
				)
			)
		)
	)
	(footprint ""
		(layer "B.Cu")
		(at 158.502604 -66.916808 180)
		(property "Reference" "L21"
			(at 0 0 0)
			(layer "B.SilkS")
			(hide yes)
			(effects
				(font
					(size 1.27 1.27)
				)
				(justify mirror)
			)
		)
		(property "Value" "MPZ2012S601AT-GP"
			(at 0 -4.2418 180)
			(unlocked yes)
			(layer "B.Fab")
			(hide yes)
			(effects
				(font
					(size 1.016 1.016)
					(thickness 0.1524)
				)
				(justify mirror)
			)
		)
		(property "Device Type" "L805H42"
			(at 0 -5.7912 180)
			(unlocked yes)
			(layer "B.Fab")
			(hide yes)
			(effects
				(font
					(size 1.016 1.016)
					(thickness 0.1524)
				)
				(justify mirror)
			)
		)
		(duplicate_pad_numbers_are_jumpers no)
		(fp_line
			(start 0.889 1.7018)
			(end 0.889 -1.7018)
			(stroke
				(width 0.1524)
				(type default)
			)
			(layer "B.SilkS")
		)
		(fp_line
			(start 0.889 -1.7018)
			(end -0.889 -1.7018)
			(stroke
				(width 0.1524)
				(type default)
			)
			(layer "B.SilkS")
		)
		(fp_line
			(start -0.889 1.7018)
			(end 0.889 1.7018)
			(stroke
				(width 0.1524)
				(type default)
			)
			(layer "B.SilkS")
		)
		(fp_line
			(start -0.889 -1.7018)
			(end -0.889 1.7018)
			(stroke
				(width 0.1524)
				(type default)
			)
			(layer "B.SilkS")
		)
		(fp_rect
			(start 0.9652 1.778)
			(end -0.9652 -1.778)
			(stroke
				(width 0)
				(type default)
			)
			(fill no)
			(layer "B.CrtYd")
		)
		(fp_rect
			(start 0.9652 1.778)
			(end -0.9652 -1.778)
			(stroke
				(width 0)
				(type default)
			)
			(fill no)
			(layer "B.Fab")
		)
		(pad "1" smd rect
			(at 0 -0.9652)
			(size 1.397 1.143)
			(layers "B.Cu" "B.Mask" "B.Paste")
			(net "SHELL_PLL_VDD")
		)
		(pad "2" smd rect
			(at 0 0.9652)
			(size 1.397 1.143)
			(layers "B.Cu" "B.Mask" "B.Paste")
			(net "P1V8_C")
		)
	)
	(footprint ""
		(layer "B.Cu")
		(at 121.92 -94.4372 -90)
		(property "Reference" "R557"
			(at 0 0 90)
			(layer "B.SilkS")
			(hide yes)
			(effects
				(font
					(size 1.27 1.27)
				)
				(justify mirror)
			)
		)
		(property "Value" "10KR2F-2-GP"
			(at -0.064008 -3.993896 270)
			(unlocked yes)
			(layer "B.Fab")
			(hide yes)
			(effects
				(font
					(size 1.016 1.016)
					(thickness 0.1524)
				)
				(justify mirror)
			)
		)
		(property "Device Type" "R402H16"
			(at -0.064008 -5.517896 270)
			(unlocked yes)
			(layer "B.Fab")
			(hide yes)
			(effects
				(font
					(size 1.016 1.016)
					(thickness 0.1524)
				)
				(justify mirror)
			)
		)
		(duplicate_pad_numbers_are_jumpers no)
		(fp_line
			(start -0.508 -0.9398)
			(end 0.508 -0.9398)
			(stroke
				(width 0.1524)
				(type default)
			)
			(layer "B.SilkS")
		)
		(fp_line
			(start 0.508 -0.9398)
			(end 0.508 0.9398)
			(stroke
				(width 0.1524)
				(type default)
			)
			(layer "B.SilkS")
		)
		(fp_rect
			(start 0.508 0.9398)
			(end -0.508 -0.9398)
			(stroke
				(width 0)
				(type default)
			)
			(fill no)
			(layer "B.CrtYd")
		)
		(fp_rect
			(start 0.508 0.9398)
			(end -0.508 -0.9398)
			(stroke
				(width 0)
				(type default)
			)
			(fill no)
			(layer "B.Fab")
		)
		(pad "1" smd custom
			(at 0 -0.4445 90)
			(size 0.1397 0.1397)
			(layers "B.Cu" "B.Mask" "B.Paste")
			(net "DRIVE_INSERT_ALERT_LS_N")
			(options
				(clearance outline)
				(anchor circle)
			)
			(primitives
				(gr_poly
					(pts
						(arc
							(start -0.1778 0.2794)
							(mid -0.249642 0.249642)
							(end -0.2794 0.1778)
						)
						(arc
							(start -0.2794 -0.1778)
							(mid -0.249642 -0.249642)
							(end -0.1778 -0.2794)
						)
						(arc
							(start 0.1778 -0.2794)
							(mid 0.249642 -0.249642)
							(end 0.2794 -0.1778)
						)
						(arc
							(start 0.2794 0.1778)
							(mid 0.249642 0.249642)
							(end 0.1778 0.2794)
						)
					)
					(width 0)
					(fill yes)
				)
			)
		)
		(pad "2" smd custom
			(at 0 0.4445 90)
			(size 0.1397 0.1397)
			(layers "B.Cu" "B.Mask" "B.Paste")
			(net "P1V8_E")
			(options
				(clearance outline)
				(anchor circle)
			)
			(primitives
				(gr_poly
					(pts
						(arc
							(start -0.1778 0.2794)
							(mid -0.249642 0.249642)
							(end -0.2794 0.1778)
						)
						(arc
							(start -0.2794 -0.1778)
							(mid -0.249642 -0.249642)
							(end -0.1778 -0.2794)
						)
						(arc
							(start 0.1778 -0.2794)
							(mid 0.249642 -0.249642)
							(end 0.2794 -0.1778)
						)
						(arc
							(start 0.2794 0.1778)
							(mid 0.249642 0.249642)
							(end 0.1778 0.2794)
						)
					)
					(width 0)
					(fill yes)
				)
			)
		)
	)
	(footprint ""
		(layer "B.Cu")
		(at 112.4458 -44.2214 180)
		(property "Reference" "C67"
			(at 0 0 0)
			(layer "B.SilkS")
			(hide yes)
			(effects
				(font
					(size 1.27 1.27)
				)
				(justify mirror)
			)
		)
		(property "Value" "SCD01U16V1KX-GP"
			(at 2.8321 -1.7399 180)
			(unlocked yes)
			(layer "B.Fab")
			(hide yes)
			(effects
				(font
					(size 1.016 1.016)
					(thickness 0.1524)
				)
				(justify mirror)
			)
		)
		(property "Device Type" "C0201H13"
			(at 2.8321 -3.2639 180)
			(unlocked yes)
			(layer "B.Fab")
			(hide yes)
			(effects
				(font
					(size 1.016 1.016)
					(thickness 0.1524)
				)
				(justify mirror)
			)
		)
		(duplicate_pad_numbers_are_jumpers no)
		(fp_rect
			(start 0.2794 0.6477)
			(end -0.2794 -0.6477)
			(stroke
				(width 0)
				(type default)
			)
			(fill no)
			(layer "B.CrtYd")
		)
		(fp_rect
			(start 0.2794 0.6477)
			(end -0.2794 -0.6477)
			(stroke
				(width 0)
				(type default)
			)
			(fill no)
			(layer "B.Fab")
		)
		(pad "1" smd custom
			(at 0 -0.2794)
			(size 0.0762 0.0762)
			(layers "B.Cu" "B.Mask" "B.Paste")
			(net "PHY_DPB_TO_SCC_26_DP")
			(options
				(clearance outline)
				(anchor circle)
			)
			(primitives
				(gr_poly
					(pts
						(arc
							(start 0.1524 0.127)
							(mid 0.137521 0.162921)
							(end 0.1016 0.1778)
						)
						(arc
							(start -0.1016 0.1778)
							(mid -0.137521 0.162921)
							(end -0.1524 0.127)
						)
						(arc
							(start -0.1524 -0.127)
							(mid -0.137521 -0.162921)
							(end -0.1016 -0.1778)
						)
						(arc
							(start 0.1016 -0.1778)
							(mid 0.137521 -0.162921)
							(end 0.1524 -0.127)
						)
					)
					(width 0)
					(fill yes)
				)
			)
		)
		(pad "2" smd custom
			(at 0 0.2794)
			(size 0.0762 0.0762)
			(layers "B.Cu" "B.Mask" "B.Paste")
			(net "PHY_DPB_TO_SCC_C_26_DP")
			(options
				(clearance outline)
				(anchor circle)
			)
			(primitives
				(gr_poly
					(pts
						(arc
							(start 0.1524 0.127)
							(mid 0.137521 0.162921)
							(end 0.1016 0.1778)
						)
						(arc
							(start -0.1016 0.1778)
							(mid -0.137521 0.162921)
							(end -0.1524 0.127)
						)
						(arc
							(start -0.1524 -0.127)
							(mid -0.137521 -0.162921)
							(end -0.1016 -0.1778)
						)
						(arc
							(start 0.1016 -0.1778)
							(mid 0.137521 -0.162921)
							(end 0.1524 -0.127)
						)
					)
					(width 0)
					(fill yes)
				)
			)
		)
	)
	(footprint ""
		(layer "B.Cu")
		(at 176.324768 -35.636962)
		(property "Reference" "C426"
			(at 0 0 0)
			(layer "B.SilkS")
			(hide yes)
			(effects
				(font
					(size 1.27 1.27)
				)
				(justify mirror)
			)
		)
		(property "Value" "SCD1U6D3V1KX-GP"
			(at 2.8321 -1.7399 0)
			(unlocked yes)
			(layer "B.Fab")
			(hide yes)
			(effects
				(font
					(size 1.016 1.016)
					(thickness 0.1524)
				)
				(justify mirror)
			)
		)
		(property "Device Type" "C0201H13"
			(at 2.8321 -3.2639 0)
			(unlocked yes)
			(layer "B.Fab")
			(hide yes)
			(effects
				(font
					(size 1.016 1.016)
					(thickness 0.1524)
				)
				(justify mirror)
			)
		)
		(duplicate_pad_numbers_are_jumpers no)
		(fp_rect
			(start 0.2794 0.6477)
			(end -0.2794 -0.6477)
			(stroke
				(width 0)
				(type default)
			)
			(fill no)
			(layer "B.CrtYd")
		)
		(fp_rect
			(start 0.2794 0.6477)
			(end -0.2794 -0.6477)
			(stroke
				(width 0)
				(type default)
			)
			(fill no)
			(layer "B.Fab")
		)
		(pad "1" smd custom
			(at 0 -0.2794 180)
			(size 0.0762 0.0762)
			(layers "B.Cu" "B.Mask" "B.Paste")
			(net "P0V975")
			(options
				(clearance outline)
				(anchor circle)
			)
			(primitives
				(gr_poly
					(pts
						(arc
							(start 0.1524 0.127)
							(mid 0.137521 0.162921)
							(end 0.1016 0.1778)
						)
						(arc
							(start -0.1016 0.1778)
							(mid -0.137521 0.162921)
							(end -0.1524 0.127)
						)
						(arc
							(start -0.1524 -0.127)
							(mid -0.137521 -0.162921)
							(end -0.1016 -0.1778)
						)
						(arc
							(start 0.1016 -0.1778)
							(mid 0.137521 -0.162921)
							(end 0.1524 -0.127)
						)
					)
					(width 0)
					(fill yes)
				)
			)
		)
		(pad "2" smd custom
			(at 0 0.2794 180)
			(size 0.0762 0.0762)
			(layers "B.Cu" "B.Mask" "B.Paste")
			(net "GND")
			(options
				(clearance outline)
				(anchor circle)
			)
			(primitives
				(gr_poly
					(pts
						(arc
							(start 0.1524 0.127)
							(mid 0.137521 0.162921)
							(end 0.1016 0.1778)
						)
						(arc
							(start -0.1016 0.1778)
							(mid -0.137521 0.162921)
							(end -0.1524 0.127)
						)
						(arc
							(start -0.1524 -0.127)
							(mid -0.137521 -0.162921)
							(end -0.1016 -0.1778)
						)
						(arc
							(start 0.1016 -0.1778)
							(mid 0.137521 -0.162921)
							(end 0.1524 -0.127)
						)
					)
					(width 0)
					(fill yes)
				)
			)
		)
	)
	(footprint ""
		(layer "B.Cu")
		(at 128.8034 -40.8686 180)
		(property "Reference" "C31"
			(at 0 0 0)
			(layer "B.SilkS")
			(hide yes)
			(effects
				(font
					(size 1.27 1.27)
				)
				(justify mirror)
			)
		)
		(property "Value" "SCD01U16V1KX-GP"
			(at 2.8321 -1.7399 180)
			(unlocked yes)
			(layer "B.Fab")
			(hide yes)
			(effects
				(font
					(size 1.016 1.016)
					(thickness 0.1524)
				)
				(justify mirror)
			)
		)
		(property "Device Type" "C0201H13"
			(at 2.8321 -3.2639 180)
			(unlocked yes)
			(layer "B.Fab")
			(hide yes)
			(effects
				(font
					(size 1.016 1.016)
					(thickness 0.1524)
				)
				(justify mirror)
			)
		)
		(duplicate_pad_numbers_are_jumpers no)
		(fp_rect
			(start 0.2794 0.6477)
			(end -0.2794 -0.6477)
			(stroke
				(width 0)
				(type default)
			)
			(fill no)
			(layer "B.CrtYd")
		)
		(fp_rect
			(start 0.2794 0.6477)
			(end -0.2794 -0.6477)
			(stroke
				(width 0)
				(type default)
			)
			(fill no)
			(layer "B.Fab")
		)
		(pad "1" smd custom
			(at 0 -0.2794)
			(size 0.0762 0.0762)
			(layers "B.Cu" "B.Mask" "B.Paste")
			(net "PHY_DPB_TO_SCC_28_DP")
			(options
				(clearance outline)
				(anchor circle)
			)
			(primitives
				(gr_poly
					(pts
						(arc
							(start 0.1524 0.127)
							(mid 0.137521 0.162921)
							(end 0.1016 0.1778)
						)
						(arc
							(start -0.1016 0.1778)
							(mid -0.137521 0.162921)
							(end -0.1524 0.127)
						)
						(arc
							(start -0.1524 -0.127)
							(mid -0.137521 -0.162921)
							(end -0.1016 -0.1778)
						)
						(arc
							(start 0.1016 -0.1778)
							(mid 0.137521 -0.162921)
							(end 0.1524 -0.127)
						)
					)
					(width 0)
					(fill yes)
				)
			)
		)
		(pad "2" smd custom
			(at 0 0.2794)
			(size 0.0762 0.0762)
			(layers "B.Cu" "B.Mask" "B.Paste")
			(net "PHY_DPB_TO_SCC_C_28_DP")
			(options
				(clearance outline)
				(anchor circle)
			)
			(primitives
				(gr_poly
					(pts
						(arc
							(start 0.1524 0.127)
							(mid 0.137521 0.162921)
							(end 0.1016 0.1778)
						)
						(arc
							(start -0.1016 0.1778)
							(mid -0.137521 0.162921)
							(end -0.1524 0.127)
						)
						(arc
							(start -0.1524 -0.127)
							(mid -0.137521 -0.162921)
							(end -0.1016 -0.1778)
						)
						(arc
							(start 0.1016 -0.1778)
							(mid 0.137521 -0.162921)
							(end 0.1524 -0.127)
						)
					)
					(width 0)
					(fill yes)
				)
			)
		)
	)
	(footprint ""
		(layer "B.Cu")
		(at 113.284 -68.6562)
		(property "Reference" "C165"
			(at 0 0 0)
			(layer "B.SilkS")
			(hide yes)
			(effects
				(font
					(size 1.27 1.27)
				)
				(justify mirror)
			)
		)
		(property "Value" "SCD1U6D3V1KX-GP"
			(at 2.8321 -1.7399 0)
			(unlocked yes)
			(layer "B.Fab")
			(hide yes)
			(effects
				(font
					(size 1.016 1.016)
					(thickness 0.1524)
				)
				(justify mirror)
			)
		)
		(property "Device Type" "C0201H13"
			(at 2.8321 -3.2639 0)
			(unlocked yes)
			(layer "B.Fab")
			(hide yes)
			(effects
				(font
					(size 1.016 1.016)
					(thickness 0.1524)
				)
				(justify mirror)
			)
		)
		(duplicate_pad_numbers_are_jumpers no)
		(fp_rect
			(start 0.2794 0.6477)
			(end -0.2794 -0.6477)
			(stroke
				(width 0)
				(type default)
			)
			(fill no)
			(layer "B.CrtYd")
		)
		(fp_rect
			(start 0.2794 0.6477)
			(end -0.2794 -0.6477)
			(stroke
				(width 0)
				(type default)
			)
			(fill no)
			(layer "B.Fab")
		)
		(pad "1" smd custom
			(at 0 -0.2794 180)
			(size 0.0762 0.0762)
			(layers "B.Cu" "B.Mask" "B.Paste")
			(net "P0V9")
			(options
				(clearance outline)
				(anchor circle)
			)
			(primitives
				(gr_poly
					(pts
						(arc
							(start 0.1524 0.127)
							(mid 0.137521 0.162921)
							(end 0.1016 0.1778)
						)
						(arc
							(start -0.1016 0.1778)
							(mid -0.137521 0.162921)
							(end -0.1524 0.127)
						)
						(arc
							(start -0.1524 -0.127)
							(mid -0.137521 -0.162921)
							(end -0.1016 -0.1778)
						)
						(arc
							(start 0.1016 -0.1778)
							(mid 0.137521 -0.162921)
							(end 0.1524 -0.127)
						)
					)
					(width 0)
					(fill yes)
				)
			)
		)
		(pad "2" smd custom
			(at 0 0.2794 180)
			(size 0.0762 0.0762)
			(layers "B.Cu" "B.Mask" "B.Paste")
			(net "GND")
			(options
				(clearance outline)
				(anchor circle)
			)
			(primitives
				(gr_poly
					(pts
						(arc
							(start 0.1524 0.127)
							(mid 0.137521 0.162921)
							(end 0.1016 0.1778)
						)
						(arc
							(start -0.1016 0.1778)
							(mid -0.137521 0.162921)
							(end -0.1524 0.127)
						)
						(arc
							(start -0.1524 -0.127)
							(mid -0.137521 -0.162921)
							(end -0.1016 -0.1778)
						)
						(arc
							(start 0.1016 -0.1778)
							(mid 0.137521 -0.162921)
							(end 0.1524 -0.127)
						)
					)
					(width 0)
					(fill yes)
				)
			)
		)
	)
	(footprint ""
		(layer "B.Cu")
		(at 120.4976 -66.675 -90)
		(property "Reference" "C216"
			(at 0 0 90)
			(layer "B.SilkS")
			(hide yes)
			(effects
				(font
					(size 1.27 1.27)
				)
				(justify mirror)
			)
		)
		(property "Value" "SCD1U16V2KX-3GP"
			(at -1.1811 -2.7051 270)
			(unlocked yes)
			(layer "B.Fab")
			(hide yes)
			(effects
				(font
					(size 1.016 1.016)
					(thickness 0.1524)
				)
				(justify mirror)
			)
		)
		(property "Device Type" "C402H22"
			(at -1.1811 -4.2291 270)
			(unlocked yes)
			(layer "B.Fab")
			(hide yes)
			(effects
				(font
					(size 1.016 1.016)
					(thickness 0.1524)
				)
				(justify mirror)
			)
		)
		(duplicate_pad_numbers_are_jumpers no)
		(fp_rect
			(start 0.4318 0.9525)
			(end -0.4318 -0.9525)
			(stroke
				(width 0)
				(type default)
			)
			(fill no)
			(layer "B.CrtYd")
		)
		(fp_rect
			(start 0.4318 0.9525)
			(end -0.4318 -0.9525)
			(stroke
				(width 0)
				(type default)
			)
			(fill no)
			(layer "B.Fab")
		)
		(pad "1" smd custom
			(at 0 -0.4445 90)
			(size 0.1524 0.1524)
			(layers "B.Cu" "B.Mask" "B.Paste")
			(net "GB_VDDH")
			(options
				(clearance outline)
				(anchor circle)
			)
			(primitives
				(gr_poly
					(pts
						(arc
							(start 0.3048 0.2032)
							(mid 0.275042 0.275042)
							(end 0.2032 0.3048)
						)
						(arc
							(start -0.2032 0.3048)
							(mid -0.275042 0.275042)
							(end -0.3048 0.2032)
						)
						(arc
							(start -0.3048 -0.2032)
							(mid -0.275042 -0.275042)
							(end -0.2032 -0.3048)
						)
						(arc
							(start 0.2032 -0.3048)
							(mid 0.275042 -0.275042)
							(end 0.3048 -0.2032)
						)
					)
					(width 0)
					(fill yes)
				)
			)
		)
		(pad "2" smd custom
			(at 0 0.4445 90)
			(size 0.1524 0.1524)
			(layers "B.Cu" "B.Mask" "B.Paste")
			(net "GND")
			(options
				(clearance outline)
				(anchor circle)
			)
			(primitives
				(gr_poly
					(pts
						(arc
							(start 0.3048 0.2032)
							(mid 0.275042 0.275042)
							(end 0.2032 0.3048)
						)
						(arc
							(start -0.2032 0.3048)
							(mid -0.275042 0.275042)
							(end -0.3048 0.2032)
						)
						(arc
							(start -0.3048 -0.2032)
							(mid -0.275042 -0.275042)
							(end -0.2032 -0.3048)
						)
						(arc
							(start 0.2032 -0.3048)
							(mid 0.275042 -0.275042)
							(end 0.3048 -0.2032)
						)
					)
					(width 0)
					(fill yes)
				)
			)
		)
	)
	(footprint ""
		(layer "B.Cu")
		(at 103.3018 -44.2214 180)
		(property "Reference" "C79"
			(at 0 0 0)
			(layer "B.SilkS")
			(hide yes)
			(effects
				(font
					(size 1.27 1.27)
				)
				(justify mirror)
			)
		)
		(property "Value" "SCD01U16V1KX-GP"
			(at 2.8321 -1.7399 180)
			(unlocked yes)
			(layer "B.Fab")
			(hide yes)
			(effects
				(font
					(size 1.016 1.016)
					(thickness 0.1524)
				)
				(justify mirror)
			)
		)
		(property "Device Type" "C0201H13"
			(at 2.8321 -3.2639 180)
			(unlocked yes)
			(layer "B.Fab")
			(hide yes)
			(effects
				(font
					(size 1.016 1.016)
					(thickness 0.1524)
				)
				(justify mirror)
			)
		)
		(duplicate_pad_numbers_are_jumpers no)
		(fp_rect
			(start 0.2794 0.6477)
			(end -0.2794 -0.6477)
			(stroke
				(width 0)
				(type default)
			)
			(fill no)
			(layer "B.CrtYd")
		)
		(fp_rect
			(start 0.2794 0.6477)
			(end -0.2794 -0.6477)
			(stroke
				(width 0)
				(type default)
			)
			(fill no)
			(layer "B.Fab")
		)
		(pad "1" smd custom
			(at 0 -0.2794)
			(size 0.0762 0.0762)
			(layers "B.Cu" "B.Mask" "B.Paste")
			(net "PHY_DPB_TO_SCC_20_DP")
			(options
				(clearance outline)
				(anchor circle)
			)
			(primitives
				(gr_poly
					(pts
						(arc
							(start 0.1524 0.127)
							(mid 0.137521 0.162921)
							(end 0.1016 0.1778)
						)
						(arc
							(start -0.1016 0.1778)
							(mid -0.137521 0.162921)
							(end -0.1524 0.127)
						)
						(arc
							(start -0.1524 -0.127)
							(mid -0.137521 -0.162921)
							(end -0.1016 -0.1778)
						)
						(arc
							(start 0.1016 -0.1778)
							(mid 0.137521 -0.162921)
							(end 0.1524 -0.127)
						)
					)
					(width 0)
					(fill yes)
				)
			)
		)
		(pad "2" smd custom
			(at 0 0.2794)
			(size 0.0762 0.0762)
			(layers "B.Cu" "B.Mask" "B.Paste")
			(net "PHY_DPB_TO_SCC_C_20_DP")
			(options
				(clearance outline)
				(anchor circle)
			)
			(primitives
				(gr_poly
					(pts
						(arc
							(start 0.1524 0.127)
							(mid 0.137521 0.162921)
							(end 0.1016 0.1778)
						)
						(arc
							(start -0.1016 0.1778)
							(mid -0.137521 0.162921)
							(end -0.1524 0.127)
						)
						(arc
							(start -0.1524 -0.127)
							(mid -0.137521 -0.162921)
							(end -0.1016 -0.1778)
						)
						(arc
							(start 0.1016 -0.1778)
							(mid 0.137521 -0.162921)
							(end 0.1524 -0.127)
						)
					)
					(width 0)
					(fill yes)
				)
			)
		)
	)
	(footprint ""
		(layer "B.Cu")
		(at 188.6458 -33.1724 90)
		(property "Reference" "TP84"
			(at 0 0 90)
			(layer "B.SilkS")
			(hide yes)
			(effects
				(font
					(size 1.27 1.27)
				)
				(justify mirror)
			)
		)
		(property "Value" "TPAD28-2-GP"
			(at 0.0127 -1.6637 90)
			(unlocked yes)
			(layer "B.Fab")
			(hide yes)
			(effects
				(font
					(size 1.016 1.016)
					(thickness 0.1524)
				)
				(justify mirror)
			)
		)
		(property "Device Type" "TPAD28"
			(at 0.0127 -3.1877 90)
			(unlocked yes)
			(layer "B.Fab")
			(hide yes)
			(effects
				(font
					(size 1.016 1.016)
					(thickness 0.1524)
				)
				(justify mirror)
			)
		)
		(duplicate_pad_numbers_are_jumpers no)
		(fp_poly
			(pts
				(arc
					(start 0 0.3556)
					(mid 0 -0.3556)
					(end 0 0.3556)
				)
			)
			(stroke
				(width 0)
				(type default)
			)
			(fill no)
			(layer "B.CrtYd")
		)
		(fp_poly
			(pts
				(arc
					(start 0 0.6096)
					(mid 0 -0.6096)
					(end 0 0.6096)
				)
			)
			(stroke
				(width 0)
				(type default)
			)
			(fill no)
			(layer "B.Fab")
		)
		(pad "1" smd circle
			(at 0 0 270)
			(size 0.7112 0.7112)
			(layers "B.Cu" "B.Mask" "B.Paste")
			(net "IOC_GPIO_28")
		)
	)
	(footprint ""
		(layer "B.Cu")
		(at 195.988178 -31.926022)
		(property "Reference" "C366"
			(at 0 0 0)
			(layer "B.SilkS")
			(hide yes)
			(effects
				(font
					(size 1.27 1.27)
				)
				(justify mirror)
			)
		)
		(property "Value" "SCD1U16V2KX-3GP"
			(at -1.1811 -2.7051 0)
			(unlocked yes)
			(layer "B.Fab")
			(hide yes)
			(effects
				(font
					(size 1.016 1.016)
					(thickness 0.1524)
				)
				(justify mirror)
			)
		)
		(property "Device Type" "C402H22"
			(at -1.1811 -4.2291 0)
			(unlocked yes)
			(layer "B.Fab")
			(hide yes)
			(effects
				(font
					(size 1.016 1.016)
					(thickness 0.1524)
				)
				(justify mirror)
			)
		)
		(duplicate_pad_numbers_are_jumpers no)
		(fp_rect
			(start 0.4318 0.9525)
			(end -0.4318 -0.9525)
			(stroke
				(width 0)
				(type default)
			)
			(fill no)
			(layer "B.CrtYd")
		)
		(fp_rect
			(start 0.4318 0.9525)
			(end -0.4318 -0.9525)
			(stroke
				(width 0)
				(type default)
			)
			(fill no)
			(layer "B.Fab")
		)
		(pad "1" smd custom
			(at 0 -0.4445 180)
			(size 0.1524 0.1524)
			(layers "B.Cu" "B.Mask" "B.Paste")
			(net "PLL_VDD")
			(options
				(clearance outline)
				(anchor circle)
			)
			(primitives
				(gr_poly
					(pts
						(arc
							(start 0.3048 0.2032)
							(mid 0.275042 0.275042)
							(end 0.2032 0.3048)
						)
						(arc
							(start -0.2032 0.3048)
							(mid -0.275042 0.275042)
							(end -0.3048 0.2032)
						)
						(arc
							(start -0.3048 -0.2032)
							(mid -0.275042 -0.275042)
							(end -0.2032 -0.3048)
						)
						(arc
							(start 0.2032 -0.3048)
							(mid 0.275042 -0.275042)
							(end 0.3048 -0.2032)
						)
					)
					(width 0)
					(fill yes)
				)
			)
		)
		(pad "2" smd custom
			(at 0 0.4445 180)
			(size 0.1524 0.1524)
			(layers "B.Cu" "B.Mask" "B.Paste")
			(net "GND")
			(options
				(clearance outline)
				(anchor circle)
			)
			(primitives
				(gr_poly
					(pts
						(arc
							(start 0.3048 0.2032)
							(mid 0.275042 0.275042)
							(end 0.2032 0.3048)
						)
						(arc
							(start -0.2032 0.3048)
							(mid -0.275042 0.275042)
							(end -0.3048 0.2032)
						)
						(arc
							(start -0.3048 -0.2032)
							(mid -0.275042 -0.275042)
							(end -0.2032 -0.3048)
						)
						(arc
							(start 0.2032 -0.3048)
							(mid 0.275042 -0.275042)
							(end 0.3048 -0.2032)
						)
					)
					(width 0)
					(fill yes)
				)
			)
		)
	)
	(footprint ""
		(layer "B.Cu")
		(at 128.524 -66.675 -90)
		(property "Reference" "C292"
			(at 0 0 90)
			(layer "B.SilkS")
			(hide yes)
			(effects
				(font
					(size 1.27 1.27)
				)
				(justify mirror)
			)
		)
		(property "Value" "SCD1U6D3V1KX-GP"
			(at 2.8321 -1.7399 270)
			(unlocked yes)
			(layer "B.Fab")
			(hide yes)
			(effects
				(font
					(size 1.016 1.016)
					(thickness 0.1524)
				)
				(justify mirror)
			)
		)
		(property "Device Type" "C0201H13"
			(at 2.8321 -3.2639 270)
			(unlocked yes)
			(layer "B.Fab")
			(hide yes)
			(effects
				(font
					(size 1.016 1.016)
					(thickness 0.1524)
				)
				(justify mirror)
			)
		)
		(duplicate_pad_numbers_are_jumpers no)
		(fp_rect
			(start 0.2794 0.6477)
			(end -0.2794 -0.6477)
			(stroke
				(width 0)
				(type default)
			)
			(fill no)
			(layer "B.CrtYd")
		)
		(fp_rect
			(start 0.2794 0.6477)
			(end -0.2794 -0.6477)
			(stroke
				(width 0)
				(type default)
			)
			(fill no)
			(layer "B.Fab")
		)
		(pad "1" smd custom
			(at 0 -0.2794 90)
			(size 0.0762 0.0762)
			(layers "B.Cu" "B.Mask" "B.Paste")
			(net "GB_VDDA")
			(options
				(clearance outline)
				(anchor circle)
			)
			(primitives
				(gr_poly
					(pts
						(arc
							(start 0.1524 0.127)
							(mid 0.137521 0.162921)
							(end 0.1016 0.1778)
						)
						(arc
							(start -0.1016 0.1778)
							(mid -0.137521 0.162921)
							(end -0.1524 0.127)
						)
						(arc
							(start -0.1524 -0.127)
							(mid -0.137521 -0.162921)
							(end -0.1016 -0.1778)
						)
						(arc
							(start 0.1016 -0.1778)
							(mid 0.137521 -0.162921)
							(end 0.1524 -0.127)
						)
					)
					(width 0)
					(fill yes)
				)
			)
		)
		(pad "2" smd custom
			(at 0 0.2794 90)
			(size 0.0762 0.0762)
			(layers "B.Cu" "B.Mask" "B.Paste")
			(net "GND")
			(options
				(clearance outline)
				(anchor circle)
			)
			(primitives
				(gr_poly
					(pts
						(arc
							(start 0.1524 0.127)
							(mid 0.137521 0.162921)
							(end 0.1016 0.1778)
						)
						(arc
							(start -0.1016 0.1778)
							(mid -0.137521 0.162921)
							(end -0.1524 0.127)
						)
						(arc
							(start -0.1524 -0.127)
							(mid -0.137521 -0.162921)
							(end -0.1016 -0.1778)
						)
						(arc
							(start 0.1016 -0.1778)
							(mid 0.137521 -0.162921)
							(end 0.1524 -0.127)
						)
					)
					(width 0)
					(fill yes)
				)
			)
		)
	)
	(footprint ""
		(layer "B.Cu")
		(at 166.84625 -43.802808)
		(property "Reference" "C453"
			(at 0 0 0)
			(layer "B.SilkS")
			(hide yes)
			(effects
				(font
					(size 1.27 1.27)
				)
				(justify mirror)
			)
		)
		(property "Value" "SCD1U6D3V1KX-GP"
			(at 2.8321 -1.7399 0)
			(unlocked yes)
			(layer "B.Fab")
			(hide yes)
			(effects
				(font
					(size 1.016 1.016)
					(thickness 0.1524)
				)
				(justify mirror)
			)
		)
		(property "Device Type" "C0201H13"
			(at 2.8321 -3.2639 0)
			(unlocked yes)
			(layer "B.Fab")
			(hide yes)
			(effects
				(font
					(size 1.016 1.016)
					(thickness 0.1524)
				)
				(justify mirror)
			)
		)
		(duplicate_pad_numbers_are_jumpers no)
		(fp_rect
			(start 0.2794 0.6477)
			(end -0.2794 -0.6477)
			(stroke
				(width 0)
				(type default)
			)
			(fill no)
			(layer "B.CrtYd")
		)
		(fp_rect
			(start 0.2794 0.6477)
			(end -0.2794 -0.6477)
			(stroke
				(width 0)
				(type default)
			)
			(fill no)
			(layer "B.Fab")
		)
		(pad "1" smd custom
			(at 0 -0.2794 180)
			(size 0.0762 0.0762)
			(layers "B.Cu" "B.Mask" "B.Paste")
			(net "P1V8_C")
			(options
				(clearance outline)
				(anchor circle)
			)
			(primitives
				(gr_poly
					(pts
						(arc
							(start 0.1524 0.127)
							(mid 0.137521 0.162921)
							(end 0.1016 0.1778)
						)
						(arc
							(start -0.1016 0.1778)
							(mid -0.137521 0.162921)
							(end -0.1524 0.127)
						)
						(arc
							(start -0.1524 -0.127)
							(mid -0.137521 -0.162921)
							(end -0.1016 -0.1778)
						)
						(arc
							(start 0.1016 -0.1778)
							(mid 0.137521 -0.162921)
							(end 0.1524 -0.127)
						)
					)
					(width 0)
					(fill yes)
				)
			)
		)
		(pad "2" smd custom
			(at 0 0.2794 180)
			(size 0.0762 0.0762)
			(layers "B.Cu" "B.Mask" "B.Paste")
			(net "GND")
			(options
				(clearance outline)
				(anchor circle)
			)
			(primitives
				(gr_poly
					(pts
						(arc
							(start 0.1524 0.127)
							(mid 0.137521 0.162921)
							(end 0.1016 0.1778)
						)
						(arc
							(start -0.1016 0.1778)
							(mid -0.137521 0.162921)
							(end -0.1524 0.127)
						)
						(arc
							(start -0.1524 -0.127)
							(mid -0.137521 -0.162921)
							(end -0.1016 -0.1778)
						)
						(arc
							(start 0.1016 -0.1778)
							(mid 0.137521 -0.162921)
							(end 0.1524 -0.127)
						)
					)
					(width 0)
					(fill yes)
				)
			)
		)
	)
	(footprint ""
		(layer "B.Cu")
		(at 189.659514 -48.146208 -90)
		(property "Reference" "TP107"
			(at 0 0 90)
			(layer "B.SilkS")
			(hide yes)
			(effects
				(font
					(size 1.27 1.27)
				)
				(justify mirror)
			)
		)
		(property "Value" "TPAD28-2-GP"
			(at 0.0127 -1.6637 270)
			(unlocked yes)
			(layer "B.Fab")
			(hide yes)
			(effects
				(font
					(size 1.016 1.016)
					(thickness 0.1524)
				)
				(justify mirror)
			)
		)
		(property "Device Type" "TPAD28"
			(at 0.0127 -3.1877 270)
			(unlocked yes)
			(layer "B.Fab")
			(hide yes)
			(effects
				(font
					(size 1.016 1.016)
					(thickness 0.1524)
				)
				(justify mirror)
			)
		)
		(duplicate_pad_numbers_are_jumpers no)
		(fp_poly
			(pts
				(arc
					(start 0 -0.3556)
					(mid 0 0.3556)
					(end 0 -0.3556)
				)
			)
			(stroke
				(width 0)
				(type default)
			)
			(fill no)
			(layer "B.CrtYd")
		)
		(fp_poly
			(pts
				(arc
					(start 0 -0.6096)
					(mid 0 0.6096)
					(end 0 -0.6096)
				)
			)
			(stroke
				(width 0)
				(type default)
			)
			(fill no)
			(layer "B.Fab")
		)
		(pad "1" smd circle
			(at 0 0 90)
			(size 0.7112 0.7112)
			(layers "B.Cu" "B.Mask" "B.Paste")
			(net "XM_ADDR_20")
		)
	)
	(footprint ""
		(layer "B.Cu")
		(at 105.0036 -86.9442)
		(property "Reference" "R85"
			(at 0 0 0)
			(layer "B.SilkS")
			(hide yes)
			(effects
				(font
					(size 1.27 1.27)
				)
				(justify mirror)
			)
		)
		(property "Value" "4K75R2F-1-GP"
			(at -0.064008 -3.993896 0)
			(unlocked yes)
			(layer "B.Fab")
			(hide yes)
			(effects
				(font
					(size 1.016 1.016)
					(thickness 0.1524)
				)
				(justify mirror)
			)
		)
		(property "Device Type" "R402H16"
			(at -0.064008 -5.517896 0)
			(unlocked yes)
			(layer "B.Fab")
			(hide yes)
			(effects
				(font
					(size 1.016 1.016)
					(thickness 0.1524)
				)
				(justify mirror)
			)
		)
		(duplicate_pad_numbers_are_jumpers no)
		(fp_line
			(start -0.508 -0.9398)
			(end 0.508 -0.9398)
			(stroke
				(width 0.1524)
				(type default)
			)
			(layer "B.SilkS")
		)
		(fp_line
			(start 0.508 -0.9398)
			(end 0.508 0.9398)
			(stroke
				(width 0.1524)
				(type default)
			)
			(layer "B.SilkS")
		)
		(fp_rect
			(start 0.508 0.9398)
			(end -0.508 -0.9398)
			(stroke
				(width 0)
				(type default)
			)
			(fill no)
			(layer "B.CrtYd")
		)
		(fp_rect
			(start 0.508 0.9398)
			(end -0.508 -0.9398)
			(stroke
				(width 0)
				(type default)
			)
			(fill no)
			(layer "B.Fab")
		)
		(pad "1" smd custom
			(at 0 -0.4445 180)
			(size 0.1397 0.1397)
			(layers "B.Cu" "B.Mask" "B.Paste")
			(net "P1V8_E")
			(options
				(clearance outline)
				(anchor circle)
			)
			(primitives
				(gr_poly
					(pts
						(arc
							(start -0.1778 0.2794)
							(mid -0.249642 0.249642)
							(end -0.2794 0.1778)
						)
						(arc
							(start -0.2794 -0.1778)
							(mid -0.249642 -0.249642)
							(end -0.1778 -0.2794)
						)
						(arc
							(start 0.1778 -0.2794)
							(mid 0.249642 -0.249642)
							(end 0.2794 -0.1778)
						)
						(arc
							(start 0.2794 0.1778)
							(mid 0.249642 0.249642)
							(end 0.1778 0.2794)
						)
					)
					(width 0)
					(fill yes)
				)
			)
		)
		(pad "2" smd custom
			(at 0 0.4445 180)
			(size 0.1397 0.1397)
			(layers "B.Cu" "B.Mask" "B.Paste")
			(net "SXP_ACTIVE_0")
			(options
				(clearance outline)
				(anchor circle)
			)
			(primitives
				(gr_poly
					(pts
						(arc
							(start -0.1778 0.2794)
							(mid -0.249642 0.249642)
							(end -0.2794 0.1778)
						)
						(arc
							(start -0.2794 -0.1778)
							(mid -0.249642 -0.249642)
							(end -0.1778 -0.2794)
						)
						(arc
							(start 0.1778 -0.2794)
							(mid 0.249642 -0.249642)
							(end 0.2794 -0.1778)
						)
						(arc
							(start 0.2794 0.1778)
							(mid 0.249642 0.249642)
							(end 0.1778 0.2794)
						)
					)
					(width 0)
					(fill yes)
				)
			)
		)
	)
	(footprint ""
		(layer "B.Cu")
		(at 165.337744 -40.861996)
		(property "Reference" "TP97"
			(at 0 0 0)
			(layer "B.SilkS")
			(hide yes)
			(effects
				(font
					(size 1.27 1.27)
				)
				(justify mirror)
			)
		)
		(property "Value" "TPAD28-2-GP"
			(at 0.0127 -1.6637 0)
			(unlocked yes)
			(layer "B.Fab")
			(hide yes)
			(effects
				(font
					(size 1.016 1.016)
					(thickness 0.1524)
				)
				(justify mirror)
			)
		)
		(property "Device Type" "TPAD28"
			(at 0.0127 -3.1877 0)
			(unlocked yes)
			(layer "B.Fab")
			(hide yes)
			(effects
				(font
					(size 1.016 1.016)
					(thickness 0.1524)
				)
				(justify mirror)
			)
		)
		(duplicate_pad_numbers_are_jumpers no)
		(fp_poly
			(pts
				(arc
					(start 0.3556 0)
					(mid -0.3556 0)
					(end 0.3556 0)
				)
			)
			(stroke
				(width 0)
				(type default)
			)
			(fill no)
			(layer "B.CrtYd")
		)
		(fp_poly
			(pts
				(arc
					(start 0.6096 0)
					(mid -0.6096 0)
					(end 0.6096 0)
				)
			)
			(stroke
				(width 0)
				(type default)
			)
			(fill no)
			(layer "B.Fab")
		)
		(pad "1" smd circle
			(at 0 0 180)
			(size 0.7112 0.7112)
			(layers "B.Cu" "B.Mask" "B.Paste")
			(net "IOC_SIO_BLINK")
		)
	)
	(footprint ""
		(layer "B.Cu")
		(at 161.544 -52.07)
		(property "Reference" "R203"
			(at 0 0 0)
			(layer "B.SilkS")
			(hide yes)
			(effects
				(font
					(size 1.27 1.27)
				)
				(justify mirror)
			)
		)
		(property "Value" "2K2R2F-GP"
			(at -0.064008 -3.993896 0)
			(unlocked yes)
			(layer "B.Fab")
			(hide yes)
			(effects
				(font
					(size 1.016 1.016)
					(thickness 0.1524)
				)
				(justify mirror)
			)
		)
		(property "Device Type" "R402H16"
			(at -0.064008 -5.517896 0)
			(unlocked yes)
			(layer "B.Fab")
			(hide yes)
			(effects
				(font
					(size 1.016 1.016)
					(thickness 0.1524)
				)
				(justify mirror)
			)
		)
		(duplicate_pad_numbers_are_jumpers no)
		(fp_line
			(start -0.508 -0.9398)
			(end 0.508 -0.9398)
			(stroke
				(width 0.1524)
				(type default)
			)
			(layer "B.SilkS")
		)
		(fp_line
			(start 0.508 -0.9398)
			(end 0.508 0.9398)
			(stroke
				(width 0.1524)
				(type default)
			)
			(layer "B.SilkS")
		)
		(fp_rect
			(start 0.508 0.9398)
			(end -0.508 -0.9398)
			(stroke
				(width 0)
				(type default)
			)
			(fill no)
			(layer "B.CrtYd")
		)
		(fp_rect
			(start 0.508 0.9398)
			(end -0.508 -0.9398)
			(stroke
				(width 0)
				(type default)
			)
			(fill no)
			(layer "B.Fab")
		)
		(pad "1" smd custom
			(at 0 -0.4445 180)
			(size 0.1397 0.1397)
			(layers "B.Cu" "B.Mask" "B.Paste")
			(net "P1V8_C")
			(options
				(clearance outline)
				(anchor circle)
			)
			(primitives
				(gr_poly
					(pts
						(arc
							(start -0.1778 0.2794)
							(mid -0.249642 0.249642)
							(end -0.2794 0.1778)
						)
						(arc
							(start -0.2794 -0.1778)
							(mid -0.249642 -0.249642)
							(end -0.1778 -0.2794)
						)
						(arc
							(start 0.1778 -0.2794)
							(mid 0.249642 -0.249642)
							(end 0.2794 -0.1778)
						)
						(arc
							(start 0.2794 0.1778)
							(mid 0.249642 0.249642)
							(end 0.1778 0.2794)
						)
					)
					(width 0)
					(fill yes)
				)
			)
		)
		(pad "2" smd custom
			(at 0 0.4445 180)
			(size 0.1397 0.1397)
			(layers "B.Cu" "B.Mask" "B.Paste")
			(net "SIO_DOUT_1")
			(options
				(clearance outline)
				(anchor circle)
			)
			(primitives
				(gr_poly
					(pts
						(arc
							(start -0.1778 0.2794)
							(mid -0.249642 0.249642)
							(end -0.2794 0.1778)
						)
						(arc
							(start -0.2794 -0.1778)
							(mid -0.249642 -0.249642)
							(end -0.1778 -0.2794)
						)
						(arc
							(start 0.1778 -0.2794)
							(mid 0.249642 -0.249642)
							(end 0.2794 -0.1778)
						)
						(arc
							(start 0.2794 0.1778)
							(mid 0.249642 0.249642)
							(end 0.1778 0.2794)
						)
					)
					(width 0)
					(fill yes)
				)
			)
		)
	)
	(footprint ""
		(layer "B.Cu")
		(at 187.1472 -31.8008 90)
		(property "Reference" "TP82"
			(at 0 0 90)
			(layer "B.SilkS")
			(hide yes)
			(effects
				(font
					(size 1.27 1.27)
				)
				(justify mirror)
			)
		)
		(property "Value" "TPAD28-2-GP"
			(at 0.0127 -1.6637 90)
			(unlocked yes)
			(layer "B.Fab")
			(hide yes)
			(effects
				(font
					(size 1.016 1.016)
					(thickness 0.1524)
				)
				(justify mirror)
			)
		)
		(property "Device Type" "TPAD28"
			(at 0.0127 -3.1877 90)
			(unlocked yes)
			(layer "B.Fab")
			(hide yes)
			(effects
				(font
					(size 1.016 1.016)
					(thickness 0.1524)
				)
				(justify mirror)
			)
		)
		(duplicate_pad_numbers_are_jumpers no)
		(fp_poly
			(pts
				(arc
					(start 0 0.3556)
					(mid 0 -0.3556)
					(end 0 0.3556)
				)
			)
			(stroke
				(width 0)
				(type default)
			)
			(fill no)
			(layer "B.CrtYd")
		)
		(fp_poly
			(pts
				(arc
					(start 0 0.6096)
					(mid 0 -0.6096)
					(end 0 0.6096)
				)
			)
			(stroke
				(width 0)
				(type default)
			)
			(fill no)
			(layer "B.Fab")
		)
		(pad "1" smd circle
			(at 0 0 270)
			(size 0.7112 0.7112)
			(layers "B.Cu" "B.Mask" "B.Paste")
			(net "IOC_GPIO_27")
		)
	)
	(footprint ""
		(layer "B.Cu")
		(at 183.144668 -38.39845 -90)
		(property "Reference" "C475"
			(at 0 0 90)
			(layer "B.SilkS")
			(hide yes)
			(effects
				(font
					(size 1.27 1.27)
				)
				(justify mirror)
			)
		)
		(property "Value" "SCD1U6D3V1KX-GP"
			(at 2.8321 -1.7399 270)
			(unlocked yes)
			(layer "B.Fab")
			(hide yes)
			(effects
				(font
					(size 1.016 1.016)
					(thickness 0.1524)
				)
				(justify mirror)
			)
		)
		(property "Device Type" "C0201H13"
			(at 2.8321 -3.2639 270)
			(unlocked yes)
			(layer "B.Fab")
			(hide yes)
			(effects
				(font
					(size 1.016 1.016)
					(thickness 0.1524)
				)
				(justify mirror)
			)
		)
		(duplicate_pad_numbers_are_jumpers no)
		(fp_rect
			(start 0.2794 0.6477)
			(end -0.2794 -0.6477)
			(stroke
				(width 0)
				(type default)
			)
			(fill no)
			(layer "B.CrtYd")
		)
		(fp_rect
			(start 0.2794 0.6477)
			(end -0.2794 -0.6477)
			(stroke
				(width 0)
				(type default)
			)
			(fill no)
			(layer "B.Fab")
		)
		(pad "1" smd custom
			(at 0 -0.2794 90)
			(size 0.0762 0.0762)
			(layers "B.Cu" "B.Mask" "B.Paste")
			(net "P1V8_C")
			(options
				(clearance outline)
				(anchor circle)
			)
			(primitives
				(gr_poly
					(pts
						(arc
							(start 0.1524 0.127)
							(mid 0.137521 0.162921)
							(end 0.1016 0.1778)
						)
						(arc
							(start -0.1016 0.1778)
							(mid -0.137521 0.162921)
							(end -0.1524 0.127)
						)
						(arc
							(start -0.1524 -0.127)
							(mid -0.137521 -0.162921)
							(end -0.1016 -0.1778)
						)
						(arc
							(start 0.1016 -0.1778)
							(mid 0.137521 -0.162921)
							(end 0.1524 -0.127)
						)
					)
					(width 0)
					(fill yes)
				)
			)
		)
		(pad "2" smd custom
			(at 0 0.2794 90)
			(size 0.0762 0.0762)
			(layers "B.Cu" "B.Mask" "B.Paste")
			(net "GND")
			(options
				(clearance outline)
				(anchor circle)
			)
			(primitives
				(gr_poly
					(pts
						(arc
							(start 0.1524 0.127)
							(mid 0.137521 0.162921)
							(end 0.1016 0.1778)
						)
						(arc
							(start -0.1016 0.1778)
							(mid -0.137521 0.162921)
							(end -0.1524 0.127)
						)
						(arc
							(start -0.1524 -0.127)
							(mid -0.137521 -0.162921)
							(end -0.1016 -0.1778)
						)
						(arc
							(start 0.1016 -0.1778)
							(mid 0.137521 -0.162921)
							(end 0.1524 -0.127)
						)
					)
					(width 0)
					(fill yes)
				)
			)
		)
	)
	(footprint ""
		(layer "B.Cu")
		(at 167.344598 -49.481232 90)
		(property "Reference" "C463"
			(at 0 0 90)
			(layer "B.SilkS")
			(hide yes)
			(effects
				(font
					(size 1.27 1.27)
				)
				(justify mirror)
			)
		)
		(property "Value" "SCD1U6D3V1KX-GP"
			(at 2.8321 -1.7399 90)
			(unlocked yes)
			(layer "B.Fab")
			(hide yes)
			(effects
				(font
					(size 1.016 1.016)
					(thickness 0.1524)
				)
				(justify mirror)
			)
		)
		(property "Device Type" "C0201H13"
			(at 2.8321 -3.2639 90)
			(unlocked yes)
			(layer "B.Fab")
			(hide yes)
			(effects
				(font
					(size 1.016 1.016)
					(thickness 0.1524)
				)
				(justify mirror)
			)
		)
		(duplicate_pad_numbers_are_jumpers no)
		(fp_rect
			(start 0.2794 0.6477)
			(end -0.2794 -0.6477)
			(stroke
				(width 0)
				(type default)
			)
			(fill no)
			(layer "B.CrtYd")
		)
		(fp_rect
			(start 0.2794 0.6477)
			(end -0.2794 -0.6477)
			(stroke
				(width 0)
				(type default)
			)
			(fill no)
			(layer "B.Fab")
		)
		(pad "1" smd custom
			(at 0 -0.2794 270)
			(size 0.0762 0.0762)
			(layers "B.Cu" "B.Mask" "B.Paste")
			(net "P1V8_C")
			(options
				(clearance outline)
				(anchor circle)
			)
			(primitives
				(gr_poly
					(pts
						(arc
							(start 0.1524 0.127)
							(mid 0.137521 0.162921)
							(end 0.1016 0.1778)
						)
						(arc
							(start -0.1016 0.1778)
							(mid -0.137521 0.162921)
							(end -0.1524 0.127)
						)
						(arc
							(start -0.1524 -0.127)
							(mid -0.137521 -0.162921)
							(end -0.1016 -0.1778)
						)
						(arc
							(start 0.1016 -0.1778)
							(mid 0.137521 -0.162921)
							(end 0.1524 -0.127)
						)
					)
					(width 0)
					(fill yes)
				)
			)
		)
		(pad "2" smd custom
			(at 0 0.2794 270)
			(size 0.0762 0.0762)
			(layers "B.Cu" "B.Mask" "B.Paste")
			(net "GND")
			(options
				(clearance outline)
				(anchor circle)
			)
			(primitives
				(gr_poly
					(pts
						(arc
							(start 0.1524 0.127)
							(mid 0.137521 0.162921)
							(end 0.1016 0.1778)
						)
						(arc
							(start -0.1016 0.1778)
							(mid -0.137521 0.162921)
							(end -0.1524 0.127)
						)
						(arc
							(start -0.1524 -0.127)
							(mid -0.137521 -0.162921)
							(end -0.1016 -0.1778)
						)
						(arc
							(start 0.1016 -0.1778)
							(mid 0.137521 -0.162921)
							(end 0.1524 -0.127)
						)
					)
					(width 0)
					(fill yes)
				)
			)
		)
	)
	(footprint ""
		(layer "B.Cu")
		(at 124.5108 -57.7596 90)
		(property "Reference" "C278"
			(at 0 0 90)
			(layer "B.SilkS")
			(hide yes)
			(effects
				(font
					(size 1.27 1.27)
				)
				(justify mirror)
			)
		)
		(property "Value" "SCD1U6D3V1KX-GP"
			(at 2.8321 -1.7399 90)
			(unlocked yes)
			(layer "B.Fab")
			(hide yes)
			(effects
				(font
					(size 1.016 1.016)
					(thickness 0.1524)
				)
				(justify mirror)
			)
		)
		(property "Device Type" "C0201H13"
			(at 2.8321 -3.2639 90)
			(unlocked yes)
			(layer "B.Fab")
			(hide yes)
			(effects
				(font
					(size 1.016 1.016)
					(thickness 0.1524)
				)
				(justify mirror)
			)
		)
		(duplicate_pad_numbers_are_jumpers no)
		(fp_rect
			(start 0.2794 0.6477)
			(end -0.2794 -0.6477)
			(stroke
				(width 0)
				(type default)
			)
			(fill no)
			(layer "B.CrtYd")
		)
		(fp_rect
			(start 0.2794 0.6477)
			(end -0.2794 -0.6477)
			(stroke
				(width 0)
				(type default)
			)
			(fill no)
			(layer "B.Fab")
		)
		(pad "1" smd custom
			(at 0 -0.2794 270)
			(size 0.0762 0.0762)
			(layers "B.Cu" "B.Mask" "B.Paste")
			(net "GB_VDDA")
			(options
				(clearance outline)
				(anchor circle)
			)
			(primitives
				(gr_poly
					(pts
						(arc
							(start 0.1524 0.127)
							(mid 0.137521 0.162921)
							(end 0.1016 0.1778)
						)
						(arc
							(start -0.1016 0.1778)
							(mid -0.137521 0.162921)
							(end -0.1524 0.127)
						)
						(arc
							(start -0.1524 -0.127)
							(mid -0.137521 -0.162921)
							(end -0.1016 -0.1778)
						)
						(arc
							(start 0.1016 -0.1778)
							(mid 0.137521 -0.162921)
							(end 0.1524 -0.127)
						)
					)
					(width 0)
					(fill yes)
				)
			)
		)
		(pad "2" smd custom
			(at 0 0.2794 270)
			(size 0.0762 0.0762)
			(layers "B.Cu" "B.Mask" "B.Paste")
			(net "GND")
			(options
				(clearance outline)
				(anchor circle)
			)
			(primitives
				(gr_poly
					(pts
						(arc
							(start 0.1524 0.127)
							(mid 0.137521 0.162921)
							(end 0.1016 0.1778)
						)
						(arc
							(start -0.1016 0.1778)
							(mid -0.137521 0.162921)
							(end -0.1524 0.127)
						)
						(arc
							(start -0.1524 -0.127)
							(mid -0.137521 -0.162921)
							(end -0.1016 -0.1778)
						)
						(arc
							(start 0.1016 -0.1778)
							(mid 0.137521 -0.162921)
							(end 0.1524 -0.127)
						)
					)
					(width 0)
					(fill yes)
				)
			)
		)
	)
	(footprint ""
		(layer "B.Cu")
		(at 176.1998 -38.6715 90)
		(property "Reference" "C417"
			(at 0 0 90)
			(layer "B.SilkS")
			(hide yes)
			(effects
				(font
					(size 1.27 1.27)
				)
				(justify mirror)
			)
		)
		(property "Value" "SCD1U6D3V1KX-GP"
			(at 2.8321 -1.7399 90)
			(unlocked yes)
			(layer "B.Fab")
			(hide yes)
			(effects
				(font
					(size 1.016 1.016)
					(thickness 0.1524)
				)
				(justify mirror)
			)
		)
		(property "Device Type" "C0201H13"
			(at 2.8321 -3.2639 90)
			(unlocked yes)
			(layer "B.Fab")
			(hide yes)
			(effects
				(font
					(size 1.016 1.016)
					(thickness 0.1524)
				)
				(justify mirror)
			)
		)
		(duplicate_pad_numbers_are_jumpers no)
		(fp_rect
			(start 0.2794 0.6477)
			(end -0.2794 -0.6477)
			(stroke
				(width 0)
				(type default)
			)
			(fill no)
			(layer "B.CrtYd")
		)
		(fp_rect
			(start 0.2794 0.6477)
			(end -0.2794 -0.6477)
			(stroke
				(width 0)
				(type default)
			)
			(fill no)
			(layer "B.Fab")
		)
		(pad "1" smd custom
			(at 0 -0.2794 270)
			(size 0.0762 0.0762)
			(layers "B.Cu" "B.Mask" "B.Paste")
			(net "P0V975")
			(options
				(clearance outline)
				(anchor circle)
			)
			(primitives
				(gr_poly
					(pts
						(arc
							(start 0.1524 0.127)
							(mid 0.137521 0.162921)
							(end 0.1016 0.1778)
						)
						(arc
							(start -0.1016 0.1778)
							(mid -0.137521 0.162921)
							(end -0.1524 0.127)
						)
						(arc
							(start -0.1524 -0.127)
							(mid -0.137521 -0.162921)
							(end -0.1016 -0.1778)
						)
						(arc
							(start 0.1016 -0.1778)
							(mid 0.137521 -0.162921)
							(end 0.1524 -0.127)
						)
					)
					(width 0)
					(fill yes)
				)
			)
		)
		(pad "2" smd custom
			(at 0 0.2794 270)
			(size 0.0762 0.0762)
			(layers "B.Cu" "B.Mask" "B.Paste")
			(net "GND")
			(options
				(clearance outline)
				(anchor circle)
			)
			(primitives
				(gr_poly
					(pts
						(arc
							(start 0.1524 0.127)
							(mid 0.137521 0.162921)
							(end 0.1016 0.1778)
						)
						(arc
							(start -0.1016 0.1778)
							(mid -0.137521 0.162921)
							(end -0.1524 0.127)
						)
						(arc
							(start -0.1524 -0.127)
							(mid -0.137521 -0.162921)
							(end -0.1016 -0.1778)
						)
						(arc
							(start 0.1016 -0.1778)
							(mid 0.137521 -0.162921)
							(end 0.1524 -0.127)
						)
					)
					(width 0)
					(fill yes)
				)
			)
		)
	)
	(footprint ""
		(layer "B.Cu")
		(at 114.6683 -64.4779)
		(property "Reference" "C175"
			(at 0 0 0)
			(layer "B.SilkS")
			(hide yes)
			(effects
				(font
					(size 1.27 1.27)
				)
				(justify mirror)
			)
		)
		(property "Value" "SCD1U6D3V1KX-GP"
			(at 2.8321 -1.7399 0)
			(unlocked yes)
			(layer "B.Fab")
			(hide yes)
			(effects
				(font
					(size 1.016 1.016)
					(thickness 0.1524)
				)
				(justify mirror)
			)
		)
		(property "Device Type" "C0201H13"
			(at 2.8321 -3.2639 0)
			(unlocked yes)
			(layer "B.Fab")
			(hide yes)
			(effects
				(font
					(size 1.016 1.016)
					(thickness 0.1524)
				)
				(justify mirror)
			)
		)
		(duplicate_pad_numbers_are_jumpers no)
		(fp_rect
			(start 0.2794 0.6477)
			(end -0.2794 -0.6477)
			(stroke
				(width 0)
				(type default)
			)
			(fill no)
			(layer "B.CrtYd")
		)
		(fp_rect
			(start 0.2794 0.6477)
			(end -0.2794 -0.6477)
			(stroke
				(width 0)
				(type default)
			)
			(fill no)
			(layer "B.Fab")
		)
		(pad "1" smd custom
			(at 0 -0.2794 180)
			(size 0.0762 0.0762)
			(layers "B.Cu" "B.Mask" "B.Paste")
			(net "P0V9")
			(options
				(clearance outline)
				(anchor circle)
			)
			(primitives
				(gr_poly
					(pts
						(arc
							(start 0.1524 0.127)
							(mid 0.137521 0.162921)
							(end 0.1016 0.1778)
						)
						(arc
							(start -0.1016 0.1778)
							(mid -0.137521 0.162921)
							(end -0.1524 0.127)
						)
						(arc
							(start -0.1524 -0.127)
							(mid -0.137521 -0.162921)
							(end -0.1016 -0.1778)
						)
						(arc
							(start 0.1016 -0.1778)
							(mid 0.137521 -0.162921)
							(end 0.1524 -0.127)
						)
					)
					(width 0)
					(fill yes)
				)
			)
		)
		(pad "2" smd custom
			(at 0 0.2794 180)
			(size 0.0762 0.0762)
			(layers "B.Cu" "B.Mask" "B.Paste")
			(net "GND")
			(options
				(clearance outline)
				(anchor circle)
			)
			(primitives
				(gr_poly
					(pts
						(arc
							(start 0.1524 0.127)
							(mid 0.137521 0.162921)
							(end 0.1016 0.1778)
						)
						(arc
							(start -0.1016 0.1778)
							(mid -0.137521 0.162921)
							(end -0.1524 0.127)
						)
						(arc
							(start -0.1524 -0.127)
							(mid -0.137521 -0.162921)
							(end -0.1016 -0.1778)
						)
						(arc
							(start 0.1016 -0.1778)
							(mid 0.137521 -0.162921)
							(end 0.1524 -0.127)
						)
					)
					(width 0)
					(fill yes)
				)
			)
		)
	)
	(footprint ""
		(layer "B.Cu")
		(at 114.6048 -71.882)
		(property "Reference" "C127"
			(at 0 0 0)
			(layer "B.SilkS")
			(hide yes)
			(effects
				(font
					(size 1.27 1.27)
				)
				(justify mirror)
			)
		)
		(property "Value" "SC1KP25V1KX-GP"
			(at 2.8321 -1.7399 0)
			(unlocked yes)
			(layer "B.Fab")
			(hide yes)
			(effects
				(font
					(size 1.016 1.016)
					(thickness 0.1524)
				)
				(justify mirror)
			)
		)
		(property "Device Type" "C0201H13"
			(at 2.8321 -3.2639 0)
			(unlocked yes)
			(layer "B.Fab")
			(hide yes)
			(effects
				(font
					(size 1.016 1.016)
					(thickness 0.1524)
				)
				(justify mirror)
			)
		)
		(duplicate_pad_numbers_are_jumpers no)
		(fp_rect
			(start 0.2794 0.6477)
			(end -0.2794 -0.6477)
			(stroke
				(width 0)
				(type default)
			)
			(fill no)
			(layer "B.CrtYd")
		)
		(fp_rect
			(start 0.2794 0.6477)
			(end -0.2794 -0.6477)
			(stroke
				(width 0)
				(type default)
			)
			(fill no)
			(layer "B.Fab")
		)
		(pad "1" smd custom
			(at 0 -0.2794 180)
			(size 0.0762 0.0762)
			(layers "B.Cu" "B.Mask" "B.Paste")
			(net "P1V8_E")
			(options
				(clearance outline)
				(anchor circle)
			)
			(primitives
				(gr_poly
					(pts
						(arc
							(start 0.1524 0.127)
							(mid 0.137521 0.162921)
							(end 0.1016 0.1778)
						)
						(arc
							(start -0.1016 0.1778)
							(mid -0.137521 0.162921)
							(end -0.1524 0.127)
						)
						(arc
							(start -0.1524 -0.127)
							(mid -0.137521 -0.162921)
							(end -0.1016 -0.1778)
						)
						(arc
							(start 0.1016 -0.1778)
							(mid 0.137521 -0.162921)
							(end 0.1524 -0.127)
						)
					)
					(width 0)
					(fill yes)
				)
			)
		)
		(pad "2" smd custom
			(at 0 0.2794 180)
			(size 0.0762 0.0762)
			(layers "B.Cu" "B.Mask" "B.Paste")
			(net "GND")
			(options
				(clearance outline)
				(anchor circle)
			)
			(primitives
				(gr_poly
					(pts
						(arc
							(start 0.1524 0.127)
							(mid 0.137521 0.162921)
							(end 0.1016 0.1778)
						)
						(arc
							(start -0.1016 0.1778)
							(mid -0.137521 0.162921)
							(end -0.1524 0.127)
						)
						(arc
							(start -0.1524 -0.127)
							(mid -0.137521 -0.162921)
							(end -0.1016 -0.1778)
						)
						(arc
							(start 0.1016 -0.1778)
							(mid 0.137521 -0.162921)
							(end 0.1524 -0.127)
						)
					)
					(width 0)
					(fill yes)
				)
			)
		)
	)
	(footprint ""
		(layer "B.Cu")
		(at 137.4648 -67.7926 -90)
		(property "Reference" "C18"
			(at 0 0 90)
			(layer "B.SilkS")
			(hide yes)
			(effects
				(font
					(size 1.27 1.27)
				)
				(justify mirror)
			)
		)
		(property "Value" "SCD01U16V1KX-GP"
			(at 2.8321 -1.7399 270)
			(unlocked yes)
			(layer "B.Fab")
			(hide yes)
			(effects
				(font
					(size 1.016 1.016)
					(thickness 0.1524)
				)
				(justify mirror)
			)
		)
		(property "Device Type" "C0201H13"
			(at 2.8321 -3.2639 270)
			(unlocked yes)
			(layer "B.Fab")
			(hide yes)
			(effects
				(font
					(size 1.016 1.016)
					(thickness 0.1524)
				)
				(justify mirror)
			)
		)
		(duplicate_pad_numbers_are_jumpers no)
		(fp_rect
			(start 0.2794 0.6477)
			(end -0.2794 -0.6477)
			(stroke
				(width 0)
				(type default)
			)
			(fill no)
			(layer "B.CrtYd")
		)
		(fp_rect
			(start 0.2794 0.6477)
			(end -0.2794 -0.6477)
			(stroke
				(width 0)
				(type default)
			)
			(fill no)
			(layer "B.Fab")
		)
		(pad "1" smd custom
			(at 0 -0.2794 90)
			(size 0.0762 0.0762)
			(layers "B.Cu" "B.Mask" "B.Paste")
			(net "PHY_DPB_TO_SCC_3_DN")
			(options
				(clearance outline)
				(anchor circle)
			)
			(primitives
				(gr_poly
					(pts
						(arc
							(start 0.1524 0.127)
							(mid 0.137521 0.162921)
							(end 0.1016 0.1778)
						)
						(arc
							(start -0.1016 0.1778)
							(mid -0.137521 0.162921)
							(end -0.1524 0.127)
						)
						(arc
							(start -0.1524 -0.127)
							(mid -0.137521 -0.162921)
							(end -0.1016 -0.1778)
						)
						(arc
							(start 0.1016 -0.1778)
							(mid 0.137521 -0.162921)
							(end 0.1524 -0.127)
						)
					)
					(width 0)
					(fill yes)
				)
			)
		)
		(pad "2" smd custom
			(at 0 0.2794 90)
			(size 0.0762 0.0762)
			(layers "B.Cu" "B.Mask" "B.Paste")
			(net "PHY_DPB_TO_SCC_C_3_DN")
			(options
				(clearance outline)
				(anchor circle)
			)
			(primitives
				(gr_poly
					(pts
						(arc
							(start 0.1524 0.127)
							(mid 0.137521 0.162921)
							(end 0.1016 0.1778)
						)
						(arc
							(start -0.1016 0.1778)
							(mid -0.137521 0.162921)
							(end -0.1524 0.127)
						)
						(arc
							(start -0.1524 -0.127)
							(mid -0.137521 -0.162921)
							(end -0.1016 -0.1778)
						)
						(arc
							(start 0.1016 -0.1778)
							(mid 0.137521 -0.162921)
							(end 0.1524 -0.127)
						)
					)
					(width 0)
					(fill yes)
				)
			)
		)
	)
	(footprint ""
		(layer "B.Cu")
		(at 135.10768 -61.304678 180)
		(property "Reference" "C24"
			(at 0 0 0)
			(layer "B.SilkS")
			(hide yes)
			(effects
				(font
					(size 1.27 1.27)
				)
				(justify mirror)
			)
		)
		(property "Value" "SCD01U16V1KX-GP"
			(at 2.8321 -1.7399 180)
			(unlocked yes)
			(layer "B.Fab")
			(hide yes)
			(effects
				(font
					(size 1.016 1.016)
					(thickness 0.1524)
				)
				(justify mirror)
			)
		)
		(property "Device Type" "C0201H13"
			(at 2.8321 -3.2639 180)
			(unlocked yes)
			(layer "B.Fab")
			(hide yes)
			(effects
				(font
					(size 1.016 1.016)
					(thickness 0.1524)
				)
				(justify mirror)
			)
		)
		(duplicate_pad_numbers_are_jumpers no)
		(fp_rect
			(start 0.2794 0.6477)
			(end -0.2794 -0.6477)
			(stroke
				(width 0)
				(type default)
			)
			(fill no)
			(layer "B.CrtYd")
		)
		(fp_rect
			(start 0.2794 0.6477)
			(end -0.2794 -0.6477)
			(stroke
				(width 0)
				(type default)
			)
			(fill no)
			(layer "B.Fab")
		)
		(pad "1" smd custom
			(at 0 -0.2794)
			(size 0.0762 0.0762)
			(layers "B.Cu" "B.Mask" "B.Paste")
			(net "PHY_DPB_TO_SCC_0_DN")
			(options
				(clearance outline)
				(anchor circle)
			)
			(primitives
				(gr_poly
					(pts
						(arc
							(start 0.1524 0.127)
							(mid 0.137521 0.162921)
							(end 0.1016 0.1778)
						)
						(arc
							(start -0.1016 0.1778)
							(mid -0.137521 0.162921)
							(end -0.1524 0.127)
						)
						(arc
							(start -0.1524 -0.127)
							(mid -0.137521 -0.162921)
							(end -0.1016 -0.1778)
						)
						(arc
							(start 0.1016 -0.1778)
							(mid 0.137521 -0.162921)
							(end 0.1524 -0.127)
						)
					)
					(width 0)
					(fill yes)
				)
			)
		)
		(pad "2" smd custom
			(at 0 0.2794)
			(size 0.0762 0.0762)
			(layers "B.Cu" "B.Mask" "B.Paste")
			(net "PHY_DPB_TO_SCC_C_0_DN")
			(options
				(clearance outline)
				(anchor circle)
			)
			(primitives
				(gr_poly
					(pts
						(arc
							(start 0.1524 0.127)
							(mid 0.137521 0.162921)
							(end 0.1016 0.1778)
						)
						(arc
							(start -0.1016 0.1778)
							(mid -0.137521 0.162921)
							(end -0.1524 0.127)
						)
						(arc
							(start -0.1524 -0.127)
							(mid -0.137521 -0.162921)
							(end -0.1016 -0.1778)
						)
						(arc
							(start 0.1016 -0.1778)
							(mid 0.137521 -0.162921)
							(end 0.1524 -0.127)
						)
					)
					(width 0)
					(fill yes)
				)
			)
		)
	)
	(footprint ""
		(layer "B.Cu")
		(at 41.157652 -112.556544)
		(property "Reference" "U7"
			(at 0 0 0)
			(layer "B.SilkS")
			(hide yes)
			(effects
				(font
					(size 1.27 1.27)
				)
				(justify mirror)
			)
		)
		(property "Value" "UA78M05CDCYRG3-GP"
			(at 0 -16.2052 0)
			(unlocked yes)
			(layer "B.Fab")
			(hide yes)
			(effects
				(font
					(size 1.016 1.016)
					(thickness 0.1524)
				)
				(justify mirror)
			)
		)
		(property "Device Type" "SOT-223H67"
			(at 0 -17.7292 0)
			(unlocked yes)
			(layer "B.Fab")
			(hide yes)
			(effects
				(font
					(size 1.016 1.016)
					(thickness 0.1524)
				)
				(justify mirror)
			)
		)
		(duplicate_pad_numbers_are_jumpers no)
		(fp_line
			(start -3.683 -7.366)
			(end 3.683 -7.366)
			(stroke
				(width 0.1524)
				(type default)
			)
			(layer "B.SilkS")
		)
		(fp_line
			(start -3.683 1.524)
			(end -3.683 -7.366)
			(stroke
				(width 0.1524)
				(type default)
			)
			(layer "B.SilkS")
		)
		(fp_line
			(start 3.683 -7.366)
			(end 3.683 1.524)
			(stroke
				(width 0.1524)
				(type default)
			)
			(layer "B.SilkS")
		)
		(fp_line
			(start 3.683 1.524)
			(end -3.683 1.524)
			(stroke
				(width 0.1524)
				(type default)
			)
			(layer "B.SilkS")
		)
		(fp_line
			(start 3.7592 0.3556)
			(end 3.7592 1.6256)
			(stroke
				(width 0.3302)
				(type default)
			)
			(layer "B.SilkS")
		)
		(fp_line
			(start 3.7592 1.6256)
			(end 2.4892 1.6256)
			(stroke
				(width 0.3302)
				(type default)
			)
			(layer "B.SilkS")
		)
		(fp_poly
			(pts
				(xy 0.635 -1.016) (xy -0.635 -1.016) (xy -0.635 1.016) (xy 0.635 1.016)
			)
			(stroke
				(width 0)
				(type default)
			)
			(fill yes)
			(layer "B.Paste")
		)
		(fp_poly
			(pts
				(xy 1.778 -6.731) (xy -1.778 -6.731) (xy -1.778 -4.699) (xy 1.778 -4.699)
			)
			(stroke
				(width 0)
				(type default)
			)
			(fill yes)
			(layer "B.Paste")
		)
		(fp_poly
			(pts
				(xy 3.683 1.524) (xy -3.683 1.524) (xy -3.683 -7.366) (xy 3.683 -7.366)
			)
			(stroke
				(width 0)
				(type default)
			)
			(fill no)
			(layer "B.CrtYd")
		)
		(fp_poly
			(pts
				(xy 3.683 -7.366) (xy -3.683 -7.366) (xy -3.683 1.524) (xy 3.683 1.524)
			)
			(stroke
				(width 0)
				(type default)
			)
			(fill no)
			(layer "B.Fab")
		)
		(pad "1" smd rect
			(at 2.286 0 180)
			(size 1.27 2.032)
			(layers "B.Cu" "B.Mask" "B.Paste")
			(net "P12V_STBY_SCC")
		)
		(pad "2" smd custom
			(at 0 0 180)
			(size 0.889 0.889)
			(layers "B.Cu" "B.Mask" "B.Paste")
			(net "GND")
			(options
				(clearance outline)
				(anchor circle)
			)
			(primitives
				(gr_poly
					(pts
						(xy -1.778 3.8735) (xy 1.778 3.8735) (xy 1.778 1.8415) (xy 0.381 1.8415) (xy 0.381 -1.8415) (xy 0.635 -1.8415)
						(xy 0.635 -3.8735) (xy -0.635 -3.8735) (xy -0.635 -1.8415) (xy -0.381 -1.8415) (xy -0.381 1.8415)
						(xy -1.778 1.8415)
					)
					(width 0)
					(fill yes)
				)
			)
		)
		(pad "3" smd rect
			(at -2.286 0 180)
			(size 1.27 2.032)
			(layers "B.Cu" "B.Mask" "B.Paste")
			(net "P5V")
		)
	)
	(footprint ""
		(layer "B.Cu")
		(at 157.740604 -59.677808 90)
		(property "Reference" "C362"
			(at 0 0 90)
			(layer "B.SilkS")
			(hide yes)
			(effects
				(font
					(size 1.27 1.27)
				)
				(justify mirror)
			)
		)
		(property "Value" "SCD1U16V2KX-3GP"
			(at -1.1811 -2.7051 90)
			(unlocked yes)
			(layer "B.Fab")
			(hide yes)
			(effects
				(font
					(size 1.016 1.016)
					(thickness 0.1524)
				)
				(justify mirror)
			)
		)
		(property "Device Type" "C402H22"
			(at -1.1811 -4.2291 90)
			(unlocked yes)
			(layer "B.Fab")
			(hide yes)
			(effects
				(font
					(size 1.016 1.016)
					(thickness 0.1524)
				)
				(justify mirror)
			)
		)
		(duplicate_pad_numbers_are_jumpers no)
		(fp_rect
			(start 0.4318 0.9525)
			(end -0.4318 -0.9525)
			(stroke
				(width 0)
				(type default)
			)
			(fill no)
			(layer "B.CrtYd")
		)
		(fp_rect
			(start 0.4318 0.9525)
			(end -0.4318 -0.9525)
			(stroke
				(width 0)
				(type default)
			)
			(fill no)
			(layer "B.Fab")
		)
		(pad "1" smd custom
			(at 0 -0.4445 270)
			(size 0.1524 0.1524)
			(layers "B.Cu" "B.Mask" "B.Paste")
			(net "SHELL_PLL_VDD")
			(options
				(clearance outline)
				(anchor circle)
			)
			(primitives
				(gr_poly
					(pts
						(arc
							(start 0.3048 0.2032)
							(mid 0.275042 0.275042)
							(end 0.2032 0.3048)
						)
						(arc
							(start -0.2032 0.3048)
							(mid -0.275042 0.275042)
							(end -0.3048 0.2032)
						)
						(arc
							(start -0.3048 -0.2032)
							(mid -0.275042 -0.275042)
							(end -0.2032 -0.3048)
						)
						(arc
							(start 0.2032 -0.3048)
							(mid 0.275042 -0.275042)
							(end 0.3048 -0.2032)
						)
					)
					(width 0)
					(fill yes)
				)
			)
		)
		(pad "2" smd custom
			(at 0 0.4445 270)
			(size 0.1524 0.1524)
			(layers "B.Cu" "B.Mask" "B.Paste")
			(net "GND")
			(options
				(clearance outline)
				(anchor circle)
			)
			(primitives
				(gr_poly
					(pts
						(arc
							(start 0.3048 0.2032)
							(mid 0.275042 0.275042)
							(end 0.2032 0.3048)
						)
						(arc
							(start -0.2032 0.3048)
							(mid -0.275042 0.275042)
							(end -0.3048 0.2032)
						)
						(arc
							(start -0.3048 -0.2032)
							(mid -0.275042 -0.275042)
							(end -0.2032 -0.3048)
						)
						(arc
							(start 0.2032 -0.3048)
							(mid 0.275042 -0.275042)
							(end 0.3048 -0.2032)
						)
					)
					(width 0)
					(fill yes)
				)
			)
		)
	)
	(footprint ""
		(layer "B.Cu")
		(at 177.673 -30.353 -90)
		(property "Reference" "C485"
			(at 0 0 90)
			(layer "B.SilkS")
			(hide yes)
			(effects
				(font
					(size 1.27 1.27)
				)
				(justify mirror)
			)
		)
		(property "Value" "SC1U16V2KX-7-GP"
			(at -1.7526 -1.6002 270)
			(unlocked yes)
			(layer "B.Fab")
			(hide yes)
			(effects
				(font
					(size 1.016 1.016)
					(thickness 0.1524)
				)
				(justify mirror)
			)
		)
		(property "Device Type" "C402-TO0D2H24"
			(at -1.7526 -3.1242 270)
			(unlocked yes)
			(layer "B.Fab")
			(hide yes)
			(effects
				(font
					(size 1.016 1.016)
					(thickness 0.1524)
				)
				(justify mirror)
			)
		)
		(duplicate_pad_numbers_are_jumpers no)
		(fp_rect
			(start 0.4826 0.889)
			(end -0.4826 -0.889)
			(stroke
				(width 0)
				(type default)
			)
			(fill no)
			(layer "B.CrtYd")
		)
		(fp_rect
			(start 0.4826 0.889)
			(end -0.4826 -0.889)
			(stroke
				(width 0)
				(type default)
			)
			(fill no)
			(layer "B.Fab")
		)
		(pad "1" smd custom
			(at 0 -0.4572 90)
			(size 0.1524 0.1524)
			(layers "B.Cu" "B.Mask" "B.Paste")
			(net "P1V8_C")
			(options
				(clearance outline)
				(anchor circle)
			)
			(primitives
				(gr_poly
					(pts
						(arc
							(start -0.254 -0.3048)
							(mid -0.325842 -0.275042)
							(end -0.3556 -0.2032)
						)
						(arc
							(start -0.3556 0.2032)
							(mid -0.325842 0.275042)
							(end -0.254 0.3048)
						)
						(arc
							(start 0.254 0.3048)
							(mid 0.325842 0.275042)
							(end 0.3556 0.2032)
						)
						(arc
							(start 0.3556 -0.2032)
							(mid 0.325842 -0.275042)
							(end 0.254 -0.3048)
						)
					)
					(width 0)
					(fill yes)
				)
			)
		)
		(pad "2" smd custom
			(at 0 0.4572 90)
			(size 0.1524 0.1524)
			(layers "B.Cu" "B.Mask" "B.Paste")
			(net "GND")
			(options
				(clearance outline)
				(anchor circle)
			)
			(primitives
				(gr_poly
					(pts
						(arc
							(start -0.254 -0.3048)
							(mid -0.325842 -0.275042)
							(end -0.3556 -0.2032)
						)
						(arc
							(start -0.3556 0.2032)
							(mid -0.325842 0.275042)
							(end -0.254 0.3048)
						)
						(arc
							(start 0.254 0.3048)
							(mid 0.325842 0.275042)
							(end 0.3556 0.2032)
						)
						(arc
							(start 0.3556 -0.2032)
							(mid 0.325842 -0.275042)
							(end 0.254 -0.3048)
						)
					)
					(width 0)
					(fill yes)
				)
			)
		)
	)
	(footprint ""
		(layer "B.Cu")
		(at 183.2356 -30.353 90)
		(property "Reference" "C483"
			(at 0 0 90)
			(layer "B.SilkS")
			(hide yes)
			(effects
				(font
					(size 1.27 1.27)
				)
				(justify mirror)
			)
		)
		(property "Value" "SC1U16V2KX-7-GP"
			(at -1.7526 -1.6002 90)
			(unlocked yes)
			(layer "B.Fab")
			(hide yes)
			(effects
				(font
					(size 1.016 1.016)
					(thickness 0.1524)
				)
				(justify mirror)
			)
		)
		(property "Device Type" "C402-TO0D2H24"
			(at -1.7526 -3.1242 90)
			(unlocked yes)
			(layer "B.Fab")
			(hide yes)
			(effects
				(font
					(size 1.016 1.016)
					(thickness 0.1524)
				)
				(justify mirror)
			)
		)
		(duplicate_pad_numbers_are_jumpers no)
		(fp_rect
			(start 0.4826 0.889)
			(end -0.4826 -0.889)
			(stroke
				(width 0)
				(type default)
			)
			(fill no)
			(layer "B.CrtYd")
		)
		(fp_rect
			(start 0.4826 0.889)
			(end -0.4826 -0.889)
			(stroke
				(width 0)
				(type default)
			)
			(fill no)
			(layer "B.Fab")
		)
		(pad "1" smd custom
			(at 0 -0.4572 270)
			(size 0.1524 0.1524)
			(layers "B.Cu" "B.Mask" "B.Paste")
			(net "P1V8_C")
			(options
				(clearance outline)
				(anchor circle)
			)
			(primitives
				(gr_poly
					(pts
						(arc
							(start -0.254 -0.3048)
							(mid -0.325842 -0.275042)
							(end -0.3556 -0.2032)
						)
						(arc
							(start -0.3556 0.2032)
							(mid -0.325842 0.275042)
							(end -0.254 0.3048)
						)
						(arc
							(start 0.254 0.3048)
							(mid 0.325842 0.275042)
							(end 0.3556 0.2032)
						)
						(arc
							(start 0.3556 -0.2032)
							(mid 0.325842 -0.275042)
							(end 0.254 -0.3048)
						)
					)
					(width 0)
					(fill yes)
				)
			)
		)
		(pad "2" smd custom
			(at 0 0.4572 270)
			(size 0.1524 0.1524)
			(layers "B.Cu" "B.Mask" "B.Paste")
			(net "GND")
			(options
				(clearance outline)
				(anchor circle)
			)
			(primitives
				(gr_poly
					(pts
						(arc
							(start -0.254 -0.3048)
							(mid -0.325842 -0.275042)
							(end -0.3556 -0.2032)
						)
						(arc
							(start -0.3556 0.2032)
							(mid -0.325842 0.275042)
							(end -0.254 0.3048)
						)
						(arc
							(start 0.254 0.3048)
							(mid 0.325842 0.275042)
							(end 0.3556 0.2032)
						)
						(arc
							(start 0.3556 -0.2032)
							(mid 0.325842 -0.275042)
							(end 0.254 -0.3048)
						)
					)
					(width 0)
					(fill yes)
				)
			)
		)
	)
	(footprint ""
		(layer "B.Cu")
		(at 163.1696 -60.5536 -90)
		(property "Reference" "C370"
			(at 0 0 90)
			(layer "B.SilkS")
			(hide yes)
			(effects
				(font
					(size 1.27 1.27)
				)
				(justify mirror)
			)
		)
		(property "Value" "SCD1U16V2KX-3GP"
			(at -1.1811 -2.7051 270)
			(unlocked yes)
			(layer "B.Fab")
			(hide yes)
			(effects
				(font
					(size 1.016 1.016)
					(thickness 0.1524)
				)
				(justify mirror)
			)
		)
		(property "Device Type" "C402H22"
			(at -1.1811 -4.2291 270)
			(unlocked yes)
			(layer "B.Fab")
			(hide yes)
			(effects
				(font
					(size 1.016 1.016)
					(thickness 0.1524)
				)
				(justify mirror)
			)
		)
		(duplicate_pad_numbers_are_jumpers no)
		(fp_rect
			(start 0.4318 0.9525)
			(end -0.4318 -0.9525)
			(stroke
				(width 0)
				(type default)
			)
			(fill no)
			(layer "B.CrtYd")
		)
		(fp_rect
			(start 0.4318 0.9525)
			(end -0.4318 -0.9525)
			(stroke
				(width 0)
				(type default)
			)
			(fill no)
			(layer "B.Fab")
		)
		(pad "1" smd custom
			(at 0 -0.4445 90)
			(size 0.1524 0.1524)
			(layers "B.Cu" "B.Mask" "B.Paste")
			(net "VDDA_SAS_REF_CLK")
			(options
				(clearance outline)
				(anchor circle)
			)
			(primitives
				(gr_poly
					(pts
						(arc
							(start 0.3048 0.2032)
							(mid 0.275042 0.275042)
							(end 0.2032 0.3048)
						)
						(arc
							(start -0.2032 0.3048)
							(mid -0.275042 0.275042)
							(end -0.3048 0.2032)
						)
						(arc
							(start -0.3048 -0.2032)
							(mid -0.275042 -0.275042)
							(end -0.2032 -0.3048)
						)
						(arc
							(start 0.2032 -0.3048)
							(mid 0.275042 -0.275042)
							(end 0.3048 -0.2032)
						)
					)
					(width 0)
					(fill yes)
				)
			)
		)
		(pad "2" smd custom
			(at 0 0.4445 90)
			(size 0.1524 0.1524)
			(layers "B.Cu" "B.Mask" "B.Paste")
			(net "GND")
			(options
				(clearance outline)
				(anchor circle)
			)
			(primitives
				(gr_poly
					(pts
						(arc
							(start 0.3048 0.2032)
							(mid 0.275042 0.275042)
							(end 0.2032 0.3048)
						)
						(arc
							(start -0.2032 0.3048)
							(mid -0.275042 0.275042)
							(end -0.3048 0.2032)
						)
						(arc
							(start -0.3048 -0.2032)
							(mid -0.275042 -0.275042)
							(end -0.2032 -0.3048)
						)
						(arc
							(start 0.2032 -0.3048)
							(mid 0.275042 -0.275042)
							(end 0.3048 -0.2032)
						)
					)
					(width 0)
					(fill yes)
				)
			)
		)
	)
	(footprint ""
		(layer "B.Cu")
		(at 108.8517 -59.4487)
		(property "Reference" "C239"
			(at 0 0 0)
			(layer "B.SilkS")
			(hide yes)
			(effects
				(font
					(size 1.27 1.27)
				)
				(justify mirror)
			)
		)
		(property "Value" "SCD1U6D3V1KX-GP"
			(at 2.8321 -1.7399 0)
			(unlocked yes)
			(layer "B.Fab")
			(hide yes)
			(effects
				(font
					(size 1.016 1.016)
					(thickness 0.1524)
				)
				(justify mirror)
			)
		)
		(property "Device Type" "C0201H13"
			(at 2.8321 -3.2639 0)
			(unlocked yes)
			(layer "B.Fab")
			(hide yes)
			(effects
				(font
					(size 1.016 1.016)
					(thickness 0.1524)
				)
				(justify mirror)
			)
		)
		(duplicate_pad_numbers_are_jumpers no)
		(fp_rect
			(start 0.2794 0.6477)
			(end -0.2794 -0.6477)
			(stroke
				(width 0)
				(type default)
			)
			(fill no)
			(layer "B.CrtYd")
		)
		(fp_rect
			(start 0.2794 0.6477)
			(end -0.2794 -0.6477)
			(stroke
				(width 0)
				(type default)
			)
			(fill no)
			(layer "B.Fab")
		)
		(pad "1" smd custom
			(at 0 -0.2794 180)
			(size 0.0762 0.0762)
			(layers "B.Cu" "B.Mask" "B.Paste")
			(net "GB_VDDA")
			(options
				(clearance outline)
				(anchor circle)
			)
			(primitives
				(gr_poly
					(pts
						(arc
							(start 0.1524 0.127)
							(mid 0.137521 0.162921)
							(end 0.1016 0.1778)
						)
						(arc
							(start -0.1016 0.1778)
							(mid -0.137521 0.162921)
							(end -0.1524 0.127)
						)
						(arc
							(start -0.1524 -0.127)
							(mid -0.137521 -0.162921)
							(end -0.1016 -0.1778)
						)
						(arc
							(start 0.1016 -0.1778)
							(mid 0.137521 -0.162921)
							(end 0.1524 -0.127)
						)
					)
					(width 0)
					(fill yes)
				)
			)
		)
		(pad "2" smd custom
			(at 0 0.2794 180)
			(size 0.0762 0.0762)
			(layers "B.Cu" "B.Mask" "B.Paste")
			(net "GND")
			(options
				(clearance outline)
				(anchor circle)
			)
			(primitives
				(gr_poly
					(pts
						(arc
							(start 0.1524 0.127)
							(mid 0.137521 0.162921)
							(end 0.1016 0.1778)
						)
						(arc
							(start -0.1016 0.1778)
							(mid -0.137521 0.162921)
							(end -0.1524 0.127)
						)
						(arc
							(start -0.1524 -0.127)
							(mid -0.137521 -0.162921)
							(end -0.1016 -0.1778)
						)
						(arc
							(start 0.1016 -0.1778)
							(mid 0.137521 -0.162921)
							(end 0.1524 -0.127)
						)
					)
					(width 0)
					(fill yes)
				)
			)
		)
	)
	(footprint ""
		(layer "B.Cu")
		(at 132.466588 -87.260684 180)
		(property "Reference" "R42"
			(at 0 0 0)
			(layer "B.SilkS")
			(hide yes)
			(effects
				(font
					(size 1.27 1.27)
				)
				(justify mirror)
			)
		)
		(property "Value" "4K7R2F-GP"
			(at -0.064008 -3.993896 180)
			(unlocked yes)
			(layer "B.Fab")
			(hide yes)
			(effects
				(font
					(size 1.016 1.016)
					(thickness 0.1524)
				)
				(justify mirror)
			)
		)
		(property "Device Type" "R402H16"
			(at -0.064008 -5.517896 180)
			(unlocked yes)
			(layer "B.Fab")
			(hide yes)
			(effects
				(font
					(size 1.016 1.016)
					(thickness 0.1524)
				)
				(justify mirror)
			)
		)
		(duplicate_pad_numbers_are_jumpers no)
		(fp_line
			(start 0.508 -0.9398)
			(end 0.508 0.9398)
			(stroke
				(width 0.1524)
				(type default)
			)
			(layer "B.SilkS")
		)
		(fp_line
			(start -0.508 -0.9398)
			(end 0.508 -0.9398)
			(stroke
				(width 0.1524)
				(type default)
			)
			(layer "B.SilkS")
		)
		(fp_rect
			(start 0.508 0.9398)
			(end -0.508 -0.9398)
			(stroke
				(width 0)
				(type default)
			)
			(fill no)
			(layer "B.CrtYd")
		)
		(fp_rect
			(start 0.508 0.9398)
			(end -0.508 -0.9398)
			(stroke
				(width 0)
				(type default)
			)
			(fill no)
			(layer "B.Fab")
		)
		(pad "1" smd custom
			(at 0 -0.4445)
			(size 0.1397 0.1397)
			(layers "B.Cu" "B.Mask" "B.Paste")
			(net "EXP_SIO_CLK_OUT")
			(options
				(clearance outline)
				(anchor circle)
			)
			(primitives
				(gr_poly
					(pts
						(arc
							(start -0.1778 0.2794)
							(mid -0.249642 0.249642)
							(end -0.2794 0.1778)
						)
						(arc
							(start -0.2794 -0.1778)
							(mid -0.249642 -0.249642)
							(end -0.1778 -0.2794)
						)
						(arc
							(start 0.1778 -0.2794)
							(mid 0.249642 -0.249642)
							(end 0.2794 -0.1778)
						)
						(arc
							(start 0.2794 0.1778)
							(mid 0.249642 0.249642)
							(end 0.1778 0.2794)
						)
					)
					(width 0)
					(fill yes)
				)
			)
		)
		(pad "2" smd custom
			(at 0 0.4445)
			(size 0.1397 0.1397)
			(layers "B.Cu" "B.Mask" "B.Paste")
			(net "P1V8_E")
			(options
				(clearance outline)
				(anchor circle)
			)
			(primitives
				(gr_poly
					(pts
						(arc
							(start -0.1778 0.2794)
							(mid -0.249642 0.249642)
							(end -0.2794 0.1778)
						)
						(arc
							(start -0.2794 -0.1778)
							(mid -0.249642 -0.249642)
							(end -0.1778 -0.2794)
						)
						(arc
							(start 0.1778 -0.2794)
							(mid 0.249642 -0.249642)
							(end 0.2794 -0.1778)
						)
						(arc
							(start 0.2794 0.1778)
							(mid 0.249642 0.249642)
							(end 0.1778 0.2794)
						)
					)
					(width 0)
					(fill yes)
				)
			)
		)
	)
	(footprint ""
		(layer "B.Cu")
		(at 173.7868 -41.86682 -90)
		(property "Reference" "C425"
			(at 0 0 90)
			(layer "B.SilkS")
			(hide yes)
			(effects
				(font
					(size 1.27 1.27)
				)
				(justify mirror)
			)
		)
		(property "Value" "SCD1U6D3V1KX-GP"
			(at 2.8321 -1.7399 270)
			(unlocked yes)
			(layer "B.Fab")
			(hide yes)
			(effects
				(font
					(size 1.016 1.016)
					(thickness 0.1524)
				)
				(justify mirror)
			)
		)
		(property "Device Type" "C0201H13"
			(at 2.8321 -3.2639 270)
			(unlocked yes)
			(layer "B.Fab")
			(hide yes)
			(effects
				(font
					(size 1.016 1.016)
					(thickness 0.1524)
				)
				(justify mirror)
			)
		)
		(duplicate_pad_numbers_are_jumpers no)
		(fp_rect
			(start 0.2794 0.6477)
			(end -0.2794 -0.6477)
			(stroke
				(width 0)
				(type default)
			)
			(fill no)
			(layer "B.CrtYd")
		)
		(fp_rect
			(start 0.2794 0.6477)
			(end -0.2794 -0.6477)
			(stroke
				(width 0)
				(type default)
			)
			(fill no)
			(layer "B.Fab")
		)
		(pad "1" smd custom
			(at 0 -0.2794 90)
			(size 0.0762 0.0762)
			(layers "B.Cu" "B.Mask" "B.Paste")
			(net "P0V975")
			(options
				(clearance outline)
				(anchor circle)
			)
			(primitives
				(gr_poly
					(pts
						(arc
							(start 0.1524 0.127)
							(mid 0.137521 0.162921)
							(end 0.1016 0.1778)
						)
						(arc
							(start -0.1016 0.1778)
							(mid -0.137521 0.162921)
							(end -0.1524 0.127)
						)
						(arc
							(start -0.1524 -0.127)
							(mid -0.137521 -0.162921)
							(end -0.1016 -0.1778)
						)
						(arc
							(start 0.1016 -0.1778)
							(mid 0.137521 -0.162921)
							(end 0.1524 -0.127)
						)
					)
					(width 0)
					(fill yes)
				)
			)
		)
		(pad "2" smd custom
			(at 0 0.2794 90)
			(size 0.0762 0.0762)
			(layers "B.Cu" "B.Mask" "B.Paste")
			(net "GND")
			(options
				(clearance outline)
				(anchor circle)
			)
			(primitives
				(gr_poly
					(pts
						(arc
							(start 0.1524 0.127)
							(mid 0.137521 0.162921)
							(end 0.1016 0.1778)
						)
						(arc
							(start -0.1016 0.1778)
							(mid -0.137521 0.162921)
							(end -0.1524 0.127)
						)
						(arc
							(start -0.1524 -0.127)
							(mid -0.137521 -0.162921)
							(end -0.1016 -0.1778)
						)
						(arc
							(start 0.1016 -0.1778)
							(mid 0.137521 -0.162921)
							(end 0.1524 -0.127)
						)
					)
					(width 0)
					(fill yes)
				)
			)
		)
	)
	(footprint ""
		(layer "B.Cu")
		(at 65.786 -95.4405 90)
		(property "Reference" "C639"
			(at 0 0 90)
			(layer "B.SilkS")
			(hide yes)
			(effects
				(font
					(size 1.27 1.27)
				)
				(justify mirror)
			)
		)
		(property "Value" "SC4D7U25V5KX-1-GP"
			(at 0.0762 -6.1214 90)
			(unlocked yes)
			(layer "B.Fab")
			(hide yes)
			(effects
				(font
					(size 1.016 1.016)
					(thickness 0.1524)
				)
				(justify mirror)
			)
		)
		(property "Device Type" "C805H58"
			(at 0.0762 -8.1534 90)
			(unlocked yes)
			(layer "B.Fab")
			(hide yes)
			(effects
				(font
					(size 1.016 1.016)
					(thickness 0.1524)
				)
				(justify mirror)
			)
		)
		(duplicate_pad_numbers_are_jumpers no)
		(fp_line
			(start -0.635 0)
			(end 0.635 0)
			(stroke
				(width 0.508)
				(type default)
			)
			(layer "B.SilkS")
		)
		(fp_rect
			(start 0.9652 1.778)
			(end -0.9652 -1.778)
			(stroke
				(width 0)
				(type default)
			)
			(fill no)
			(layer "B.CrtYd")
		)
		(fp_poly
			(pts
				(xy 0.9652 -1.778) (xy -0.9652 -1.778) (xy -0.9652 1.778) (xy 0.9652 1.778)
			)
			(stroke
				(width 0)
				(type default)
			)
			(fill no)
			(layer "B.Fab")
		)
		(pad "1" smd rect
			(at 0 -0.9652 270)
			(size 1.397 1.143)
			(layers "B.Cu" "B.Mask" "B.Paste")
			(net "P12V_STBY_VDD_U10")
		)
		(pad "2" smd rect
			(at 0 0.9652 270)
			(size 1.397 1.143)
			(layers "B.Cu" "B.Mask" "B.Paste")
			(net "GND")
		)
	)
	(footprint ""
		(layer "B.Cu")
		(at 172.309028 -32.69869 90)
		(property "Reference" "C380"
			(at 0 0 90)
			(layer "B.SilkS")
			(hide yes)
			(effects
				(font
					(size 1.27 1.27)
				)
				(justify mirror)
			)
		)
		(property "Value" "SCD1U16V2KX-3GP"
			(at -1.1811 -2.7051 90)
			(unlocked yes)
			(layer "B.Fab")
			(hide yes)
			(effects
				(font
					(size 1.016 1.016)
					(thickness 0.1524)
				)
				(justify mirror)
			)
		)
		(property "Device Type" "C402H22"
			(at -1.1811 -4.2291 90)
			(unlocked yes)
			(layer "B.Fab")
			(hide yes)
			(effects
				(font
					(size 1.016 1.016)
					(thickness 0.1524)
				)
				(justify mirror)
			)
		)
		(duplicate_pad_numbers_are_jumpers no)
		(fp_rect
			(start 0.4318 0.9525)
			(end -0.4318 -0.9525)
			(stroke
				(width 0)
				(type default)
			)
			(fill no)
			(layer "B.CrtYd")
		)
		(fp_rect
			(start 0.4318 0.9525)
			(end -0.4318 -0.9525)
			(stroke
				(width 0)
				(type default)
			)
			(fill no)
			(layer "B.Fab")
		)
		(pad "1" smd custom
			(at 0 -0.4445 270)
			(size 0.1524 0.1524)
			(layers "B.Cu" "B.Mask" "B.Paste")
			(net "PCE_VDDH")
			(options
				(clearance outline)
				(anchor circle)
			)
			(primitives
				(gr_poly
					(pts
						(arc
							(start 0.3048 0.2032)
							(mid 0.275042 0.275042)
							(end 0.2032 0.3048)
						)
						(arc
							(start -0.2032 0.3048)
							(mid -0.275042 0.275042)
							(end -0.3048 0.2032)
						)
						(arc
							(start -0.3048 -0.2032)
							(mid -0.275042 -0.275042)
							(end -0.2032 -0.3048)
						)
						(arc
							(start 0.2032 -0.3048)
							(mid 0.275042 -0.275042)
							(end 0.3048 -0.2032)
						)
					)
					(width 0)
					(fill yes)
				)
			)
		)
		(pad "2" smd custom
			(at 0 0.4445 270)
			(size 0.1524 0.1524)
			(layers "B.Cu" "B.Mask" "B.Paste")
			(net "GND")
			(options
				(clearance outline)
				(anchor circle)
			)
			(primitives
				(gr_poly
					(pts
						(arc
							(start 0.3048 0.2032)
							(mid 0.275042 0.275042)
							(end 0.2032 0.3048)
						)
						(arc
							(start -0.2032 0.3048)
							(mid -0.275042 0.275042)
							(end -0.3048 0.2032)
						)
						(arc
							(start -0.3048 -0.2032)
							(mid -0.275042 -0.275042)
							(end -0.2032 -0.3048)
						)
						(arc
							(start 0.2032 -0.3048)
							(mid 0.275042 -0.275042)
							(end 0.3048 -0.2032)
						)
					)
					(width 0)
					(fill yes)
				)
			)
		)
	)
	(footprint ""
		(layer "B.Cu")
		(at 169.632122 -43.47464 180)
		(property "Reference" "C493"
			(at 0 0 0)
			(layer "B.SilkS")
			(hide yes)
			(effects
				(font
					(size 1.27 1.27)
				)
				(justify mirror)
			)
		)
		(property "Value" "SCD1U6D3V1KX-GP"
			(at 2.8321 -1.7399 180)
			(unlocked yes)
			(layer "B.Fab")
			(hide yes)
			(effects
				(font
					(size 1.016 1.016)
					(thickness 0.1524)
				)
				(justify mirror)
			)
		)
		(property "Device Type" "C0201H13"
			(at 2.8321 -3.2639 180)
			(unlocked yes)
			(layer "B.Fab")
			(hide yes)
			(effects
				(font
					(size 1.016 1.016)
					(thickness 0.1524)
				)
				(justify mirror)
			)
		)
		(duplicate_pad_numbers_are_jumpers no)
		(fp_rect
			(start 0.2794 0.6477)
			(end -0.2794 -0.6477)
			(stroke
				(width 0)
				(type default)
			)
			(fill no)
			(layer "B.CrtYd")
		)
		(fp_rect
			(start 0.2794 0.6477)
			(end -0.2794 -0.6477)
			(stroke
				(width 0)
				(type default)
			)
			(fill no)
			(layer "B.Fab")
		)
		(pad "1" smd custom
			(at 0 -0.2794)
			(size 0.0762 0.0762)
			(layers "B.Cu" "B.Mask" "B.Paste")
			(net "P1V8_C")
			(options
				(clearance outline)
				(anchor circle)
			)
			(primitives
				(gr_poly
					(pts
						(arc
							(start 0.1524 0.127)
							(mid 0.137521 0.162921)
							(end 0.1016 0.1778)
						)
						(arc
							(start -0.1016 0.1778)
							(mid -0.137521 0.162921)
							(end -0.1524 0.127)
						)
						(arc
							(start -0.1524 -0.127)
							(mid -0.137521 -0.162921)
							(end -0.1016 -0.1778)
						)
						(arc
							(start 0.1016 -0.1778)
							(mid 0.137521 -0.162921)
							(end 0.1524 -0.127)
						)
					)
					(width 0)
					(fill yes)
				)
			)
		)
		(pad "2" smd custom
			(at 0 0.2794)
			(size 0.0762 0.0762)
			(layers "B.Cu" "B.Mask" "B.Paste")
			(net "GND")
			(options
				(clearance outline)
				(anchor circle)
			)
			(primitives
				(gr_poly
					(pts
						(arc
							(start 0.1524 0.127)
							(mid 0.137521 0.162921)
							(end 0.1016 0.1778)
						)
						(arc
							(start -0.1016 0.1778)
							(mid -0.137521 0.162921)
							(end -0.1524 0.127)
						)
						(arc
							(start -0.1524 -0.127)
							(mid -0.137521 -0.162921)
							(end -0.1016 -0.1778)
						)
						(arc
							(start 0.1016 -0.1778)
							(mid 0.137521 -0.162921)
							(end 0.1524 -0.127)
						)
					)
					(width 0)
					(fill yes)
				)
			)
		)
	)
	(footprint ""
		(layer "B.Cu")
		(at 131.113276 -84.473288)
		(property "Reference" "TP15"
			(at 0 0 0)
			(layer "B.SilkS")
			(hide yes)
			(effects
				(font
					(size 1.27 1.27)
				)
				(justify mirror)
			)
		)
		(property "Value" "TPAD28-2-GP"
			(at 0.0127 -1.6637 0)
			(unlocked yes)
			(layer "B.Fab")
			(hide yes)
			(effects
				(font
					(size 1.016 1.016)
					(thickness 0.1524)
				)
				(justify mirror)
			)
		)
		(property "Device Type" "TPAD28"
			(at 0.0127 -3.1877 0)
			(unlocked yes)
			(layer "B.Fab")
			(hide yes)
			(effects
				(font
					(size 1.016 1.016)
					(thickness 0.1524)
				)
				(justify mirror)
			)
		)
		(duplicate_pad_numbers_are_jumpers no)
		(fp_poly
			(pts
				(arc
					(start 0.3556 0)
					(mid -0.3556 0)
					(end 0.3556 0)
				)
			)
			(stroke
				(width 0)
				(type default)
			)
			(fill no)
			(layer "B.CrtYd")
		)
		(fp_poly
			(pts
				(arc
					(start 0.6096 0)
					(mid -0.6096 0)
					(end 0.6096 0)
				)
			)
			(stroke
				(width 0)
				(type default)
			)
			(fill no)
			(layer "B.Fab")
		)
		(pad "1" smd circle
			(at 0 0 180)
			(size 0.7112 0.7112)
			(layers "B.Cu" "B.Mask" "B.Paste")
			(net "EXP_I2C_SDA11")
		)
	)
	(footprint ""
		(layer "B.Cu")
		(at 120.4976 -70.739 -90)
		(property "Reference" "C214"
			(at 0 0 90)
			(layer "B.SilkS")
			(hide yes)
			(effects
				(font
					(size 1.27 1.27)
				)
				(justify mirror)
			)
		)
		(property "Value" "SC1U16V2KX-7-GP"
			(at -1.7526 -1.6002 270)
			(unlocked yes)
			(layer "B.Fab")
			(hide yes)
			(effects
				(font
					(size 1.016 1.016)
					(thickness 0.1524)
				)
				(justify mirror)
			)
		)
		(property "Device Type" "C402-TO0D2H24"
			(at -1.7526 -3.1242 270)
			(unlocked yes)
			(layer "B.Fab")
			(hide yes)
			(effects
				(font
					(size 1.016 1.016)
					(thickness 0.1524)
				)
				(justify mirror)
			)
		)
		(duplicate_pad_numbers_are_jumpers no)
		(fp_rect
			(start 0.4826 0.889)
			(end -0.4826 -0.889)
			(stroke
				(width 0)
				(type default)
			)
			(fill no)
			(layer "B.CrtYd")
		)
		(fp_rect
			(start 0.4826 0.889)
			(end -0.4826 -0.889)
			(stroke
				(width 0)
				(type default)
			)
			(fill no)
			(layer "B.Fab")
		)
		(pad "1" smd custom
			(at 0 -0.4572 90)
			(size 0.1524 0.1524)
			(layers "B.Cu" "B.Mask" "B.Paste")
			(net "GB_VDDH")
			(options
				(clearance outline)
				(anchor circle)
			)
			(primitives
				(gr_poly
					(pts
						(arc
							(start -0.254 -0.3048)
							(mid -0.325842 -0.275042)
							(end -0.3556 -0.2032)
						)
						(arc
							(start -0.3556 0.2032)
							(mid -0.325842 0.275042)
							(end -0.254 0.3048)
						)
						(arc
							(start 0.254 0.3048)
							(mid 0.325842 0.275042)
							(end 0.3556 0.2032)
						)
						(arc
							(start 0.3556 -0.2032)
							(mid 0.325842 -0.275042)
							(end 0.254 -0.3048)
						)
					)
					(width 0)
					(fill yes)
				)
			)
		)
		(pad "2" smd custom
			(at 0 0.4572 90)
			(size 0.1524 0.1524)
			(layers "B.Cu" "B.Mask" "B.Paste")
			(net "GND")
			(options
				(clearance outline)
				(anchor circle)
			)
			(primitives
				(gr_poly
					(pts
						(arc
							(start -0.254 -0.3048)
							(mid -0.325842 -0.275042)
							(end -0.3556 -0.2032)
						)
						(arc
							(start -0.3556 0.2032)
							(mid -0.325842 0.275042)
							(end -0.254 0.3048)
						)
						(arc
							(start 0.254 0.3048)
							(mid 0.325842 0.275042)
							(end 0.3556 0.2032)
						)
						(arc
							(start 0.3556 -0.2032)
							(mid 0.325842 -0.275042)
							(end 0.254 -0.3048)
						)
					)
					(width 0)
					(fill yes)
				)
			)
		)
	)
	(footprint ""
		(layer "B.Cu")
		(at 184.465468 -38.39845 90)
		(property "Reference" "C490"
			(at 0 0 90)
			(layer "B.SilkS")
			(hide yes)
			(effects
				(font
					(size 1.27 1.27)
				)
				(justify mirror)
			)
		)
		(property "Value" "SCD1U6D3V1KX-GP"
			(at 2.8321 -1.7399 90)
			(unlocked yes)
			(layer "B.Fab")
			(hide yes)
			(effects
				(font
					(size 1.016 1.016)
					(thickness 0.1524)
				)
				(justify mirror)
			)
		)
		(property "Device Type" "C0201H13"
			(at 2.8321 -3.2639 90)
			(unlocked yes)
			(layer "B.Fab")
			(hide yes)
			(effects
				(font
					(size 1.016 1.016)
					(thickness 0.1524)
				)
				(justify mirror)
			)
		)
		(duplicate_pad_numbers_are_jumpers no)
		(fp_rect
			(start 0.2794 0.6477)
			(end -0.2794 -0.6477)
			(stroke
				(width 0)
				(type default)
			)
			(fill no)
			(layer "B.CrtYd")
		)
		(fp_rect
			(start 0.2794 0.6477)
			(end -0.2794 -0.6477)
			(stroke
				(width 0)
				(type default)
			)
			(fill no)
			(layer "B.Fab")
		)
		(pad "1" smd custom
			(at 0 -0.2794 270)
			(size 0.0762 0.0762)
			(layers "B.Cu" "B.Mask" "B.Paste")
			(net "P1V8_C")
			(options
				(clearance outline)
				(anchor circle)
			)
			(primitives
				(gr_poly
					(pts
						(arc
							(start 0.1524 0.127)
							(mid 0.137521 0.162921)
							(end 0.1016 0.1778)
						)
						(arc
							(start -0.1016 0.1778)
							(mid -0.137521 0.162921)
							(end -0.1524 0.127)
						)
						(arc
							(start -0.1524 -0.127)
							(mid -0.137521 -0.162921)
							(end -0.1016 -0.1778)
						)
						(arc
							(start 0.1016 -0.1778)
							(mid 0.137521 -0.162921)
							(end 0.1524 -0.127)
						)
					)
					(width 0)
					(fill yes)
				)
			)
		)
		(pad "2" smd custom
			(at 0 0.2794 270)
			(size 0.0762 0.0762)
			(layers "B.Cu" "B.Mask" "B.Paste")
			(net "GND")
			(options
				(clearance outline)
				(anchor circle)
			)
			(primitives
				(gr_poly
					(pts
						(arc
							(start 0.1524 0.127)
							(mid 0.137521 0.162921)
							(end 0.1016 0.1778)
						)
						(arc
							(start -0.1016 0.1778)
							(mid -0.137521 0.162921)
							(end -0.1524 0.127)
						)
						(arc
							(start -0.1524 -0.127)
							(mid -0.137521 -0.162921)
							(end -0.1016 -0.1778)
						)
						(arc
							(start 0.1016 -0.1778)
							(mid 0.137521 -0.162921)
							(end 0.1524 -0.127)
						)
					)
					(width 0)
					(fill yes)
				)
			)
		)
	)
	(footprint ""
		(layer "B.Cu")
		(at 140.716 -88.9)
		(property "Reference" "R66"
			(at 0 0 0)
			(layer "B.SilkS")
			(hide yes)
			(effects
				(font
					(size 1.27 1.27)
				)
				(justify mirror)
			)
		)
		(property "Value" "1KR2F-3-GP"
			(at -0.064008 -3.993896 0)
			(unlocked yes)
			(layer "B.Fab")
			(hide yes)
			(effects
				(font
					(size 1.016 1.016)
					(thickness 0.1524)
				)
				(justify mirror)
			)
		)
		(property "Device Type" "R402H16"
			(at -0.064008 -5.517896 0)
			(unlocked yes)
			(layer "B.Fab")
			(hide yes)
			(effects
				(font
					(size 1.016 1.016)
					(thickness 0.1524)
				)
				(justify mirror)
			)
		)
		(duplicate_pad_numbers_are_jumpers no)
		(fp_line
			(start -0.508 -0.9398)
			(end 0.508 -0.9398)
			(stroke
				(width 0.1524)
				(type default)
			)
			(layer "B.SilkS")
		)
		(fp_line
			(start 0.508 -0.9398)
			(end 0.508 0.9398)
			(stroke
				(width 0.1524)
				(type default)
			)
			(layer "B.SilkS")
		)
		(fp_rect
			(start 0.508 0.9398)
			(end -0.508 -0.9398)
			(stroke
				(width 0)
				(type default)
			)
			(fill no)
			(layer "B.CrtYd")
		)
		(fp_rect
			(start 0.508 0.9398)
			(end -0.508 -0.9398)
			(stroke
				(width 0)
				(type default)
			)
			(fill no)
			(layer "B.Fab")
		)
		(pad "1" smd custom
			(at 0 -0.4445 180)
			(size 0.1397 0.1397)
			(layers "B.Cu" "B.Mask" "B.Paste")
			(net "P1V8_E")
			(options
				(clearance outline)
				(anchor circle)
			)
			(primitives
				(gr_poly
					(pts
						(arc
							(start -0.1778 0.2794)
							(mid -0.249642 0.249642)
							(end -0.2794 0.1778)
						)
						(arc
							(start -0.2794 -0.1778)
							(mid -0.249642 -0.249642)
							(end -0.1778 -0.2794)
						)
						(arc
							(start 0.1778 -0.2794)
							(mid 0.249642 -0.249642)
							(end 0.2794 -0.1778)
						)
						(arc
							(start 0.2794 0.1778)
							(mid 0.249642 0.249642)
							(end 0.1778 0.2794)
						)
					)
					(width 0)
					(fill yes)
				)
			)
		)
		(pad "2" smd custom
			(at 0 0.4445 180)
			(size 0.1397 0.1397)
			(layers "B.Cu" "B.Mask" "B.Paste")
			(net "EXP_I2C_SCL9")
			(options
				(clearance outline)
				(anchor circle)
			)
			(primitives
				(gr_poly
					(pts
						(arc
							(start -0.1778 0.2794)
							(mid -0.249642 0.249642)
							(end -0.2794 0.1778)
						)
						(arc
							(start -0.2794 -0.1778)
							(mid -0.249642 -0.249642)
							(end -0.1778 -0.2794)
						)
						(arc
							(start 0.1778 -0.2794)
							(mid 0.249642 -0.249642)
							(end 0.2794 -0.1778)
						)
						(arc
							(start 0.2794 0.1778)
							(mid 0.249642 0.249642)
							(end 0.1778 0.2794)
						)
					)
					(width 0)
					(fill yes)
				)
			)
		)
	)
	(footprint ""
		(layer "B.Cu")
		(at 129.397252 -58.696606 90)
		(property "Reference" "C271"
			(at 0 0 90)
			(layer "B.SilkS")
			(hide yes)
			(effects
				(font
					(size 1.27 1.27)
				)
				(justify mirror)
			)
		)
		(property "Value" "SCD1U6D3V1KX-GP"
			(at 2.8321 -1.7399 90)
			(unlocked yes)
			(layer "B.Fab")
			(hide yes)
			(effects
				(font
					(size 1.016 1.016)
					(thickness 0.1524)
				)
				(justify mirror)
			)
		)
		(property "Device Type" "C0201H13"
			(at 2.8321 -3.2639 90)
			(unlocked yes)
			(layer "B.Fab")
			(hide yes)
			(effects
				(font
					(size 1.016 1.016)
					(thickness 0.1524)
				)
				(justify mirror)
			)
		)
		(duplicate_pad_numbers_are_jumpers no)
		(fp_rect
			(start 0.2794 0.6477)
			(end -0.2794 -0.6477)
			(stroke
				(width 0)
				(type default)
			)
			(fill no)
			(layer "B.CrtYd")
		)
		(fp_rect
			(start 0.2794 0.6477)
			(end -0.2794 -0.6477)
			(stroke
				(width 0)
				(type default)
			)
			(fill no)
			(layer "B.Fab")
		)
		(pad "1" smd custom
			(at 0 -0.2794 270)
			(size 0.0762 0.0762)
			(layers "B.Cu" "B.Mask" "B.Paste")
			(net "GB_VDDA")
			(options
				(clearance outline)
				(anchor circle)
			)
			(primitives
				(gr_poly
					(pts
						(arc
							(start 0.1524 0.127)
							(mid 0.137521 0.162921)
							(end 0.1016 0.1778)
						)
						(arc
							(start -0.1016 0.1778)
							(mid -0.137521 0.162921)
							(end -0.1524 0.127)
						)
						(arc
							(start -0.1524 -0.127)
							(mid -0.137521 -0.162921)
							(end -0.1016 -0.1778)
						)
						(arc
							(start 0.1016 -0.1778)
							(mid 0.137521 -0.162921)
							(end 0.1524 -0.127)
						)
					)
					(width 0)
					(fill yes)
				)
			)
		)
		(pad "2" smd custom
			(at 0 0.2794 270)
			(size 0.0762 0.0762)
			(layers "B.Cu" "B.Mask" "B.Paste")
			(net "GND")
			(options
				(clearance outline)
				(anchor circle)
			)
			(primitives
				(gr_poly
					(pts
						(arc
							(start 0.1524 0.127)
							(mid 0.137521 0.162921)
							(end 0.1016 0.1778)
						)
						(arc
							(start -0.1016 0.1778)
							(mid -0.137521 0.162921)
							(end -0.1524 0.127)
						)
						(arc
							(start -0.1524 -0.127)
							(mid -0.137521 -0.162921)
							(end -0.1016 -0.1778)
						)
						(arc
							(start 0.1016 -0.1778)
							(mid 0.137521 -0.162921)
							(end 0.1524 -0.127)
						)
					)
					(width 0)
					(fill yes)
				)
			)
		)
	)
	(footprint ""
		(layer "B.Cu")
		(at 96.497394 -50.950368 90)
		(property "Reference" "C90"
			(at 0 0 90)
			(layer "B.SilkS")
			(hide yes)
			(effects
				(font
					(size 1.27 1.27)
				)
				(justify mirror)
			)
		)
		(property "Value" "SCD01U16V1KX-GP"
			(at 2.8321 -1.7399 90)
			(unlocked yes)
			(layer "B.Fab")
			(hide yes)
			(effects
				(font
					(size 1.016 1.016)
					(thickness 0.1524)
				)
				(justify mirror)
			)
		)
		(property "Device Type" "C0201H13"
			(at 2.8321 -3.2639 90)
			(unlocked yes)
			(layer "B.Fab")
			(hide yes)
			(effects
				(font
					(size 1.016 1.016)
					(thickness 0.1524)
				)
				(justify mirror)
			)
		)
		(duplicate_pad_numbers_are_jumpers no)
		(fp_rect
			(start 0.2794 0.6477)
			(end -0.2794 -0.6477)
			(stroke
				(width 0)
				(type default)
			)
			(fill no)
			(layer "B.CrtYd")
		)
		(fp_rect
			(start 0.2794 0.6477)
			(end -0.2794 -0.6477)
			(stroke
				(width 0)
				(type default)
			)
			(fill no)
			(layer "B.Fab")
		)
		(pad "1" smd custom
			(at 0 -0.2794 270)
			(size 0.0762 0.0762)
			(layers "B.Cu" "B.Mask" "B.Paste")
			(net "PHY_DPB_TO_SCC_15_DN")
			(options
				(clearance outline)
				(anchor circle)
			)
			(primitives
				(gr_poly
					(pts
						(arc
							(start 0.1524 0.127)
							(mid 0.137521 0.162921)
							(end 0.1016 0.1778)
						)
						(arc
							(start -0.1016 0.1778)
							(mid -0.137521 0.162921)
							(end -0.1524 0.127)
						)
						(arc
							(start -0.1524 -0.127)
							(mid -0.137521 -0.162921)
							(end -0.1016 -0.1778)
						)
						(arc
							(start 0.1016 -0.1778)
							(mid 0.137521 -0.162921)
							(end 0.1524 -0.127)
						)
					)
					(width 0)
					(fill yes)
				)
			)
		)
		(pad "2" smd custom
			(at 0 0.2794 270)
			(size 0.0762 0.0762)
			(layers "B.Cu" "B.Mask" "B.Paste")
			(net "PHY_DPB_TO_SCC_C_15_DN")
			(options
				(clearance outline)
				(anchor circle)
			)
			(primitives
				(gr_poly
					(pts
						(arc
							(start 0.1524 0.127)
							(mid 0.137521 0.162921)
							(end 0.1016 0.1778)
						)
						(arc
							(start -0.1016 0.1778)
							(mid -0.137521 0.162921)
							(end -0.1524 0.127)
						)
						(arc
							(start -0.1524 -0.127)
							(mid -0.137521 -0.162921)
							(end -0.1016 -0.1778)
						)
						(arc
							(start 0.1016 -0.1778)
							(mid 0.137521 -0.162921)
							(end 0.1524 -0.127)
						)
					)
					(width 0)
					(fill yes)
				)
			)
		)
	)
	(footprint ""
		(layer "B.Cu")
		(at 128.2192 -40.8686 180)
		(property "Reference" "C32"
			(at 0 0 0)
			(layer "B.SilkS")
			(hide yes)
			(effects
				(font
					(size 1.27 1.27)
				)
				(justify mirror)
			)
		)
		(property "Value" "SCD01U16V1KX-GP"
			(at 2.8321 -1.7399 180)
			(unlocked yes)
			(layer "B.Fab")
			(hide yes)
			(effects
				(font
					(size 1.016 1.016)
					(thickness 0.1524)
				)
				(justify mirror)
			)
		)
		(property "Device Type" "C0201H13"
			(at 2.8321 -3.2639 180)
			(unlocked yes)
			(layer "B.Fab")
			(hide yes)
			(effects
				(font
					(size 1.016 1.016)
					(thickness 0.1524)
				)
				(justify mirror)
			)
		)
		(duplicate_pad_numbers_are_jumpers no)
		(fp_rect
			(start 0.2794 0.6477)
			(end -0.2794 -0.6477)
			(stroke
				(width 0)
				(type default)
			)
			(fill no)
			(layer "B.CrtYd")
		)
		(fp_rect
			(start 0.2794 0.6477)
			(end -0.2794 -0.6477)
			(stroke
				(width 0)
				(type default)
			)
			(fill no)
			(layer "B.Fab")
		)
		(pad "1" smd custom
			(at 0 -0.2794)
			(size 0.0762 0.0762)
			(layers "B.Cu" "B.Mask" "B.Paste")
			(net "PHY_DPB_TO_SCC_28_DN")
			(options
				(clearance outline)
				(anchor circle)
			)
			(primitives
				(gr_poly
					(pts
						(arc
							(start 0.1524 0.127)
							(mid 0.137521 0.162921)
							(end 0.1016 0.1778)
						)
						(arc
							(start -0.1016 0.1778)
							(mid -0.137521 0.162921)
							(end -0.1524 0.127)
						)
						(arc
							(start -0.1524 -0.127)
							(mid -0.137521 -0.162921)
							(end -0.1016 -0.1778)
						)
						(arc
							(start 0.1016 -0.1778)
							(mid 0.137521 -0.162921)
							(end 0.1524 -0.127)
						)
					)
					(width 0)
					(fill yes)
				)
			)
		)
		(pad "2" smd custom
			(at 0 0.2794)
			(size 0.0762 0.0762)
			(layers "B.Cu" "B.Mask" "B.Paste")
			(net "PHY_DPB_TO_SCC_C_28_DN")
			(options
				(clearance outline)
				(anchor circle)
			)
			(primitives
				(gr_poly
					(pts
						(arc
							(start 0.1524 0.127)
							(mid 0.137521 0.162921)
							(end 0.1016 0.1778)
						)
						(arc
							(start -0.1016 0.1778)
							(mid -0.137521 0.162921)
							(end -0.1524 0.127)
						)
						(arc
							(start -0.1524 -0.127)
							(mid -0.137521 -0.162921)
							(end -0.1016 -0.1778)
						)
						(arc
							(start 0.1016 -0.1778)
							(mid 0.137521 -0.162921)
							(end 0.1524 -0.127)
						)
					)
					(width 0)
					(fill yes)
				)
			)
		)
	)
	(footprint ""
		(layer "B.Cu")
		(at 93.311472 -71.192898)
		(property "Reference" "C197"
			(at 0 0 0)
			(layer "B.SilkS")
			(hide yes)
			(effects
				(font
					(size 1.27 1.27)
				)
				(justify mirror)
			)
		)
		(property "Value" "SC10U6D3V2MX-GP-U"
			(at 1.524 -1.905 0)
			(unlocked yes)
			(layer "B.Fab")
			(hide yes)
			(effects
				(font
					(size 1.016 1.016)
					(thickness 0.1524)
				)
				(justify mirror)
			)
		)
		(property "Device Type" "C402-TO0D2H28"
			(at 1.524 -3.429 0)
			(unlocked yes)
			(layer "B.Fab")
			(hide yes)
			(effects
				(font
					(size 1.016 1.016)
					(thickness 0.1524)
				)
				(justify mirror)
			)
		)
		(duplicate_pad_numbers_are_jumpers no)
		(fp_rect
			(start 0.4826 0.889)
			(end -0.4826 -0.889)
			(stroke
				(width 0)
				(type default)
			)
			(fill no)
			(layer "B.CrtYd")
		)
		(fp_rect
			(start 0.4826 0.889)
			(end -0.4826 -0.889)
			(stroke
				(width 0)
				(type default)
			)
			(fill no)
			(layer "B.Fab")
		)
		(pad "1" smd custom
			(at 0 -0.4572 180)
			(size 0.1524 0.1524)
			(layers "B.Cu" "B.Mask" "B.Paste")
			(net "SYSPLL_VDDA18")
			(options
				(clearance outline)
				(anchor circle)
			)
			(primitives
				(gr_poly
					(pts
						(arc
							(start -0.254 -0.3048)
							(mid -0.325842 -0.275042)
							(end -0.3556 -0.2032)
						)
						(arc
							(start -0.3556 0.2032)
							(mid -0.325842 0.275042)
							(end -0.254 0.3048)
						)
						(arc
							(start 0.254 0.3048)
							(mid 0.325842 0.275042)
							(end 0.3556 0.2032)
						)
						(arc
							(start 0.3556 -0.2032)
							(mid 0.325842 -0.275042)
							(end 0.254 -0.3048)
						)
					)
					(width 0)
					(fill yes)
				)
			)
		)
		(pad "2" smd custom
			(at 0 0.4572 180)
			(size 0.1524 0.1524)
			(layers "B.Cu" "B.Mask" "B.Paste")
			(net "GND")
			(options
				(clearance outline)
				(anchor circle)
			)
			(primitives
				(gr_poly
					(pts
						(arc
							(start -0.254 -0.3048)
							(mid -0.325842 -0.275042)
							(end -0.3556 -0.2032)
						)
						(arc
							(start -0.3556 0.2032)
							(mid -0.325842 0.275042)
							(end -0.254 0.3048)
						)
						(arc
							(start 0.254 0.3048)
							(mid 0.325842 0.275042)
							(end 0.3556 0.2032)
						)
						(arc
							(start 0.3556 -0.2032)
							(mid 0.325842 -0.275042)
							(end 0.254 -0.3048)
						)
					)
					(width 0)
					(fill yes)
				)
			)
		)
	)
	(footprint ""
		(layer "B.Cu")
		(at 159.40278 -116.00942 180)
		(property "Reference" "C607"
			(at 0 0 0)
			(layer "B.SilkS")
			(hide yes)
			(effects
				(font
					(size 1.27 1.27)
				)
				(justify mirror)
			)
		)
		(property "Value" "SC4D7U25V5KX-1-GP"
			(at 0.0762 -6.1214 180)
			(unlocked yes)
			(layer "B.Fab")
			(hide yes)
			(effects
				(font
					(size 1.016 1.016)
					(thickness 0.1524)
				)
				(justify mirror)
			)
		)
		(property "Device Type" "C805H58"
			(at 0.0762 -8.1534 180)
			(unlocked yes)
			(layer "B.Fab")
			(hide yes)
			(effects
				(font
					(size 1.016 1.016)
					(thickness 0.1524)
				)
				(justify mirror)
			)
		)
		(duplicate_pad_numbers_are_jumpers no)
		(fp_line
			(start -0.635 0)
			(end 0.635 0)
			(stroke
				(width 0.508)
				(type default)
			)
			(layer "B.SilkS")
		)
		(fp_rect
			(start 0.9652 1.778)
			(end -0.9652 -1.778)
			(stroke
				(width 0)
				(type default)
			)
			(fill no)
			(layer "B.CrtYd")
		)
		(fp_poly
			(pts
				(xy 0.9652 -1.778) (xy -0.9652 -1.778) (xy -0.9652 1.778) (xy 0.9652 1.778)
			)
			(stroke
				(width 0)
				(type default)
			)
			(fill no)
			(layer "B.Fab")
		)
		(pad "1" smd rect
			(at 0 -0.9652)
			(size 1.397 1.143)
			(layers "B.Cu" "B.Mask" "B.Paste")
			(net "P12V_STBY_VDD_U11")
		)
		(pad "2" smd rect
			(at 0 0.9652)
			(size 1.397 1.143)
			(layers "B.Cu" "B.Mask" "B.Paste")
			(net "GND")
		)
	)
	(footprint ""
		(layer "B.Cu")
		(at 137.4648 -69.9008 -90)
		(property "Reference" "C15"
			(at 0 0 90)
			(layer "B.SilkS")
			(hide yes)
			(effects
				(font
					(size 1.27 1.27)
				)
				(justify mirror)
			)
		)
		(property "Value" "SCD01U16V1KX-GP"
			(at 2.8321 -1.7399 270)
			(unlocked yes)
			(layer "B.Fab")
			(hide yes)
			(effects
				(font
					(size 1.016 1.016)
					(thickness 0.1524)
				)
				(justify mirror)
			)
		)
		(property "Device Type" "C0201H13"
			(at 2.8321 -3.2639 270)
			(unlocked yes)
			(layer "B.Fab")
			(hide yes)
			(effects
				(font
					(size 1.016 1.016)
					(thickness 0.1524)
				)
				(justify mirror)
			)
		)
		(duplicate_pad_numbers_are_jumpers no)
		(fp_rect
			(start 0.2794 0.6477)
			(end -0.2794 -0.6477)
			(stroke
				(width 0)
				(type default)
			)
			(fill no)
			(layer "B.CrtYd")
		)
		(fp_rect
			(start 0.2794 0.6477)
			(end -0.2794 -0.6477)
			(stroke
				(width 0)
				(type default)
			)
			(fill no)
			(layer "B.Fab")
		)
		(pad "1" smd custom
			(at 0 -0.2794 90)
			(size 0.0762 0.0762)
			(layers "B.Cu" "B.Mask" "B.Paste")
			(net "PHY_DPB_TO_SCC_4_DP")
			(options
				(clearance outline)
				(anchor circle)
			)
			(primitives
				(gr_poly
					(pts
						(arc
							(start 0.1524 0.127)
							(mid 0.137521 0.162921)
							(end 0.1016 0.1778)
						)
						(arc
							(start -0.1016 0.1778)
							(mid -0.137521 0.162921)
							(end -0.1524 0.127)
						)
						(arc
							(start -0.1524 -0.127)
							(mid -0.137521 -0.162921)
							(end -0.1016 -0.1778)
						)
						(arc
							(start 0.1016 -0.1778)
							(mid 0.137521 -0.162921)
							(end 0.1524 -0.127)
						)
					)
					(width 0)
					(fill yes)
				)
			)
		)
		(pad "2" smd custom
			(at 0 0.2794 90)
			(size 0.0762 0.0762)
			(layers "B.Cu" "B.Mask" "B.Paste")
			(net "PHY_DPB_TO_SCC_C_4_DP")
			(options
				(clearance outline)
				(anchor circle)
			)
			(primitives
				(gr_poly
					(pts
						(arc
							(start 0.1524 0.127)
							(mid 0.137521 0.162921)
							(end 0.1016 0.1778)
						)
						(arc
							(start -0.1016 0.1778)
							(mid -0.137521 0.162921)
							(end -0.1524 0.127)
						)
						(arc
							(start -0.1524 -0.127)
							(mid -0.137521 -0.162921)
							(end -0.1016 -0.1778)
						)
						(arc
							(start 0.1016 -0.1778)
							(mid 0.137521 -0.162921)
							(end 0.1524 -0.127)
						)
					)
					(width 0)
					(fill yes)
				)
			)
		)
	)
	(footprint ""
		(layer "B.Cu")
		(at 166.335964 -8.6614 -90)
		(property "Reference" "U50"
			(at 0 0 90)
			(layer "B.SilkS")
			(hide yes)
			(effects
				(font
					(size 1.27 1.27)
				)
				(justify mirror)
			)
		)
		(property "Value" "SNLVC1G126DCKR-GP"
			(at 2.3368 -8.6868 270)
			(unlocked yes)
			(layer "B.Fab")
			(hide yes)
			(effects
				(font
					(size 1.016 1.016)
					(thickness 0.1524)
				)
				(justify mirror)
			)
		)
		(property "Device Type" "SC70-5H44"
			(at 2.3114 -10.414 270)
			(unlocked yes)
			(layer "B.Fab")
			(hide yes)
			(effects
				(font
					(size 1.016 1.016)
					(thickness 0.1524)
				)
				(justify mirror)
			)
		)
		(duplicate_pad_numbers_are_jumpers no)
		(fp_line
			(start -1.27 1.7018)
			(end 1.27 1.7018)
			(stroke
				(width 0.1524)
				(type default)
			)
			(layer "B.SilkS")
		)
		(fp_line
			(start 1.27 1.7018)
			(end 1.27 -1.7018)
			(stroke
				(width 0.1524)
				(type default)
			)
			(layer "B.SilkS")
		)
		(fp_line
			(start -1.27 -1.7018)
			(end -1.27 1.7018)
			(stroke
				(width 0.1524)
				(type default)
			)
			(layer "B.SilkS")
		)
		(fp_line
			(start 1.27 -1.7018)
			(end -1.27 -1.7018)
			(stroke
				(width 0.1524)
				(type default)
			)
			(layer "B.SilkS")
		)
		(fp_line
			(start -1.3843 -1.8034)
			(end -1.3843 -1.1176)
			(stroke
				(width 0.3302)
				(type default)
			)
			(layer "B.SilkS")
		)
		(fp_line
			(start -0.6604 -1.8034)
			(end -1.3843 -1.8034)
			(stroke
				(width 0.3302)
				(type default)
			)
			(layer "B.SilkS")
		)
		(fp_rect
			(start 1.524 1.9558)
			(end -1.524 -1.9558)
			(stroke
				(width 0)
				(type default)
			)
			(fill no)
			(layer "B.CrtYd")
		)
		(fp_poly
			(pts
				(xy 1.524 -1.9558) (xy -1.524 -1.9558) (xy -1.524 1.9558) (xy 1.524 1.9558)
			)
			(stroke
				(width 0)
				(type default)
			)
			(fill no)
			(layer "B.Fab")
		)
		(pad "1" smd rect
			(at -0.65024 -0.8255 90)
			(size 0.4064 1.2192)
			(layers "B.Cu" "B.Mask" "B.Paste")
			(net "U50_OE")
		)
		(pad "2" smd rect
			(at 0 -0.8255 90)
			(size 0.4064 1.2192)
			(layers "B.Cu" "B.Mask" "B.Paste")
			(net "SCC_RESET_N")
		)
		(pad "3" smd rect
			(at 0.65024 -0.8255 90)
			(size 0.4064 1.2192)
			(layers "B.Cu" "B.Mask" "B.Paste")
			(net "GND")
		)
		(pad "4" smd rect
			(at 0.65024 0.8255 90)
			(size 0.4064 1.2192)
			(layers "B.Cu" "B.Mask" "B.Paste")
			(net "SCC_RESET_BUF_N")
		)
		(pad "5" smd rect
			(at -0.65024 0.8255 90)
			(size 0.4064 1.2192)
			(layers "B.Cu" "B.Mask" "B.Paste")
			(net "P3V3")
		)
	)
	(footprint ""
		(layer "B.Cu")
		(at 105.5116 -79.6036)
		(property "Reference" "C156"
			(at 0 0 0)
			(layer "B.SilkS")
			(hide yes)
			(effects
				(font
					(size 1.27 1.27)
				)
				(justify mirror)
			)
		)
		(property "Value" "SCD1U6D3V1KX-GP"
			(at 2.8321 -1.7399 0)
			(unlocked yes)
			(layer "B.Fab")
			(hide yes)
			(effects
				(font
					(size 1.016 1.016)
					(thickness 0.1524)
				)
				(justify mirror)
			)
		)
		(property "Device Type" "C0201H13"
			(at 2.8321 -3.2639 0)
			(unlocked yes)
			(layer "B.Fab")
			(hide yes)
			(effects
				(font
					(size 1.016 1.016)
					(thickness 0.1524)
				)
				(justify mirror)
			)
		)
		(duplicate_pad_numbers_are_jumpers no)
		(fp_rect
			(start 0.2794 0.6477)
			(end -0.2794 -0.6477)
			(stroke
				(width 0)
				(type default)
			)
			(fill no)
			(layer "B.CrtYd")
		)
		(fp_rect
			(start 0.2794 0.6477)
			(end -0.2794 -0.6477)
			(stroke
				(width 0)
				(type default)
			)
			(fill no)
			(layer "B.Fab")
		)
		(pad "1" smd custom
			(at 0 -0.2794 180)
			(size 0.0762 0.0762)
			(layers "B.Cu" "B.Mask" "B.Paste")
			(net "P1V8_E")
			(options
				(clearance outline)
				(anchor circle)
			)
			(primitives
				(gr_poly
					(pts
						(arc
							(start 0.1524 0.127)
							(mid 0.137521 0.162921)
							(end 0.1016 0.1778)
						)
						(arc
							(start -0.1016 0.1778)
							(mid -0.137521 0.162921)
							(end -0.1524 0.127)
						)
						(arc
							(start -0.1524 -0.127)
							(mid -0.137521 -0.162921)
							(end -0.1016 -0.1778)
						)
						(arc
							(start 0.1016 -0.1778)
							(mid 0.137521 -0.162921)
							(end 0.1524 -0.127)
						)
					)
					(width 0)
					(fill yes)
				)
			)
		)
		(pad "2" smd custom
			(at 0 0.2794 180)
			(size 0.0762 0.0762)
			(layers "B.Cu" "B.Mask" "B.Paste")
			(net "GND")
			(options
				(clearance outline)
				(anchor circle)
			)
			(primitives
				(gr_poly
					(pts
						(arc
							(start 0.1524 0.127)
							(mid 0.137521 0.162921)
							(end 0.1016 0.1778)
						)
						(arc
							(start -0.1016 0.1778)
							(mid -0.137521 0.162921)
							(end -0.1524 0.127)
						)
						(arc
							(start -0.1524 -0.127)
							(mid -0.137521 -0.162921)
							(end -0.1016 -0.1778)
						)
						(arc
							(start 0.1016 -0.1778)
							(mid 0.137521 -0.162921)
							(end 0.1524 -0.127)
						)
					)
					(width 0)
					(fill yes)
				)
			)
		)
	)
	(footprint ""
		(layer "B.Cu")
		(at 138.17473 -121.94286 90)
		(property "Reference" "R1"
			(at 0 0 90)
			(layer "B.SilkS")
			(hide yes)
			(effects
				(font
					(size 1.27 1.27)
				)
				(justify mirror)
			)
		)
		(property "Value" "10KR2F-2-GP"
			(at -0.064008 -3.993896 90)
			(unlocked yes)
			(layer "B.Fab")
			(hide yes)
			(effects
				(font
					(size 1.016 1.016)
					(thickness 0.1524)
				)
				(justify mirror)
			)
		)
		(property "Device Type" "R402H16"
			(at -0.064008 -5.517896 90)
			(unlocked yes)
			(layer "B.Fab")
			(hide yes)
			(effects
				(font
					(size 1.016 1.016)
					(thickness 0.1524)
				)
				(justify mirror)
			)
		)
		(duplicate_pad_numbers_are_jumpers no)
		(fp_line
			(start 0.508 -0.9398)
			(end 0.508 0.9398)
			(stroke
				(width 0.1524)
				(type default)
			)
			(layer "B.SilkS")
		)
		(fp_line
			(start -0.508 -0.9398)
			(end 0.508 -0.9398)
			(stroke
				(width 0.1524)
				(type default)
			)
			(layer "B.SilkS")
		)
		(fp_rect
			(start 0.508 0.9398)
			(end -0.508 -0.9398)
			(stroke
				(width 0)
				(type default)
			)
			(fill no)
			(layer "B.CrtYd")
		)
		(fp_rect
			(start 0.508 0.9398)
			(end -0.508 -0.9398)
			(stroke
				(width 0)
				(type default)
			)
			(fill no)
			(layer "B.Fab")
		)
		(pad "1" smd custom
			(at 0 -0.4445 270)
			(size 0.1397 0.1397)
			(layers "B.Cu" "B.Mask" "B.Paste")
			(net "P12V_STBY_SCC")
			(options
				(clearance outline)
				(anchor circle)
			)
			(primitives
				(gr_poly
					(pts
						(arc
							(start -0.1778 0.2794)
							(mid -0.249642 0.249642)
							(end -0.2794 0.1778)
						)
						(arc
							(start -0.2794 -0.1778)
							(mid -0.249642 -0.249642)
							(end -0.1778 -0.2794)
						)
						(arc
							(start 0.1778 -0.2794)
							(mid 0.249642 -0.249642)
							(end 0.2794 -0.1778)
						)
						(arc
							(start 0.2794 0.1778)
							(mid 0.249642 0.249642)
							(end 0.1778 0.2794)
						)
					)
					(width 0)
					(fill yes)
				)
			)
		)
		(pad "2" smd custom
			(at 0 0.4445 270)
			(size 0.1397 0.1397)
			(layers "B.Cu" "B.Mask" "B.Paste")
			(net "P1V5_C_PG_G")
			(options
				(clearance outline)
				(anchor circle)
			)
			(primitives
				(gr_poly
					(pts
						(arc
							(start -0.1778 0.2794)
							(mid -0.249642 0.249642)
							(end -0.2794 0.1778)
						)
						(arc
							(start -0.2794 -0.1778)
							(mid -0.249642 -0.249642)
							(end -0.1778 -0.2794)
						)
						(arc
							(start 0.1778 -0.2794)
							(mid 0.249642 -0.249642)
							(end 0.2794 -0.1778)
						)
						(arc
							(start 0.2794 0.1778)
							(mid 0.249642 0.249642)
							(end 0.1778 0.2794)
						)
					)
					(width 0)
					(fill yes)
				)
			)
		)
	)
	(footprint ""
		(layer "B.Cu")
		(at 203.3524 -45.80382)
		(property "Reference" "C346"
			(at 0 0 0)
			(layer "B.SilkS")
			(hide yes)
			(effects
				(font
					(size 1.27 1.27)
				)
				(justify mirror)
			)
		)
		(property "Value" "SCD01U25V2KX-3GP"
			(at -1.1811 -2.7051 0)
			(unlocked yes)
			(layer "B.Fab")
			(hide yes)
			(effects
				(font
					(size 1.016 1.016)
					(thickness 0.1524)
				)
				(justify mirror)
			)
		)
		(property "Device Type" "C402H22"
			(at -1.1811 -4.2291 0)
			(unlocked yes)
			(layer "B.Fab")
			(hide yes)
			(effects
				(font
					(size 1.016 1.016)
					(thickness 0.1524)
				)
				(justify mirror)
			)
		)
		(duplicate_pad_numbers_are_jumpers no)
		(fp_rect
			(start 0.4318 0.9525)
			(end -0.4318 -0.9525)
			(stroke
				(width 0)
				(type default)
			)
			(fill no)
			(layer "B.CrtYd")
		)
		(fp_rect
			(start 0.4318 0.9525)
			(end -0.4318 -0.9525)
			(stroke
				(width 0)
				(type default)
			)
			(fill no)
			(layer "B.Fab")
		)
		(pad "1" smd custom
			(at 0 -0.4445 180)
			(size 0.1524 0.1524)
			(layers "B.Cu" "B.Mask" "B.Paste")
			(net "GND")
			(options
				(clearance outline)
				(anchor circle)
			)
			(primitives
				(gr_poly
					(pts
						(arc
							(start 0.3048 0.2032)
							(mid 0.275042 0.275042)
							(end 0.2032 0.3048)
						)
						(arc
							(start -0.2032 0.3048)
							(mid -0.275042 0.275042)
							(end -0.3048 0.2032)
						)
						(arc
							(start -0.3048 -0.2032)
							(mid -0.275042 -0.275042)
							(end -0.2032 -0.3048)
						)
						(arc
							(start 0.2032 -0.3048)
							(mid 0.275042 -0.275042)
							(end 0.3048 -0.2032)
						)
					)
					(width 0)
					(fill yes)
				)
			)
		)
		(pad "2" smd custom
			(at 0 0.4445 180)
			(size 0.1524 0.1524)
			(layers "B.Cu" "B.Mask" "B.Paste")
			(net "P1V8_C")
			(options
				(clearance outline)
				(anchor circle)
			)
			(primitives
				(gr_poly
					(pts
						(arc
							(start 0.3048 0.2032)
							(mid 0.275042 0.275042)
							(end 0.2032 0.3048)
						)
						(arc
							(start -0.2032 0.3048)
							(mid -0.275042 0.275042)
							(end -0.3048 0.2032)
						)
						(arc
							(start -0.3048 -0.2032)
							(mid -0.275042 -0.275042)
							(end -0.2032 -0.3048)
						)
						(arc
							(start 0.2032 -0.3048)
							(mid 0.275042 -0.275042)
							(end 0.3048 -0.2032)
						)
					)
					(width 0)
					(fill yes)
				)
			)
		)
	)
	(footprint ""
		(layer "B.Cu")
		(at 160.782 -16.256)
		(property "Reference" "R81"
			(at 0 0 0)
			(layer "B.SilkS")
			(hide yes)
			(effects
				(font
					(size 1.27 1.27)
				)
				(justify mirror)
			)
		)
		(property "Value" "10KR2F-2-GP"
			(at -0.064008 -3.993896 0)
			(unlocked yes)
			(layer "B.Fab")
			(hide yes)
			(effects
				(font
					(size 1.016 1.016)
					(thickness 0.1524)
				)
				(justify mirror)
			)
		)
		(property "Device Type" "R402H16"
			(at -0.064008 -5.517896 0)
			(unlocked yes)
			(layer "B.Fab")
			(hide yes)
			(effects
				(font
					(size 1.016 1.016)
					(thickness 0.1524)
				)
				(justify mirror)
			)
		)
		(duplicate_pad_numbers_are_jumpers no)
		(fp_line
			(start -0.508 -0.9398)
			(end 0.508 -0.9398)
			(stroke
				(width 0.1524)
				(type default)
			)
			(layer "B.SilkS")
		)
		(fp_line
			(start 0.508 -0.9398)
			(end 0.508 0.9398)
			(stroke
				(width 0.1524)
				(type default)
			)
			(layer "B.SilkS")
		)
		(fp_rect
			(start 0.508 0.9398)
			(end -0.508 -0.9398)
			(stroke
				(width 0)
				(type default)
			)
			(fill no)
			(layer "B.CrtYd")
		)
		(fp_rect
			(start 0.508 0.9398)
			(end -0.508 -0.9398)
			(stroke
				(width 0)
				(type default)
			)
			(fill no)
			(layer "B.Fab")
		)
		(pad "1" smd custom
			(at 0 -0.4445 180)
			(size 0.1397 0.1397)
			(layers "B.Cu" "B.Mask" "B.Paste")
			(net "P12V_STBY_SCC")
			(options
				(clearance outline)
				(anchor circle)
			)
			(primitives
				(gr_poly
					(pts
						(arc
							(start -0.1778 0.2794)
							(mid -0.249642 0.249642)
							(end -0.2794 0.1778)
						)
						(arc
							(start -0.2794 -0.1778)
							(mid -0.249642 -0.249642)
							(end -0.1778 -0.2794)
						)
						(arc
							(start 0.1778 -0.2794)
							(mid 0.249642 -0.249642)
							(end 0.2794 -0.1778)
						)
						(arc
							(start 0.2794 0.1778)
							(mid 0.249642 0.249642)
							(end 0.1778 0.2794)
						)
					)
					(width 0)
					(fill yes)
				)
			)
		)
		(pad "2" smd custom
			(at 0 0.4445 180)
			(size 0.1397 0.1397)
			(layers "B.Cu" "B.Mask" "B.Paste")
			(net "LS_EN_N")
			(options
				(clearance outline)
				(anchor circle)
			)
			(primitives
				(gr_poly
					(pts
						(arc
							(start -0.1778 0.2794)
							(mid -0.249642 0.249642)
							(end -0.2794 0.1778)
						)
						(arc
							(start -0.2794 -0.1778)
							(mid -0.249642 -0.249642)
							(end -0.1778 -0.2794)
						)
						(arc
							(start 0.1778 -0.2794)
							(mid 0.249642 -0.249642)
							(end 0.2794 -0.1778)
						)
						(arc
							(start 0.2794 0.1778)
							(mid 0.249642 0.249642)
							(end 0.1778 0.2794)
						)
					)
					(width 0)
					(fill yes)
				)
			)
		)
	)
	(footprint ""
		(layer "B.Cu")
		(at 114.681 -61.488066)
		(property "Reference" "C222"
			(at 0 0 0)
			(layer "B.SilkS")
			(hide yes)
			(effects
				(font
					(size 1.27 1.27)
				)
				(justify mirror)
			)
		)
		(property "Value" "SCD1U16V2KX-3GP"
			(at -1.1811 -2.7051 0)
			(unlocked yes)
			(layer "B.Fab")
			(hide yes)
			(effects
				(font
					(size 1.016 1.016)
					(thickness 0.1524)
				)
				(justify mirror)
			)
		)
		(property "Device Type" "C402H22"
			(at -1.1811 -4.2291 0)
			(unlocked yes)
			(layer "B.Fab")
			(hide yes)
			(effects
				(font
					(size 1.016 1.016)
					(thickness 0.1524)
				)
				(justify mirror)
			)
		)
		(duplicate_pad_numbers_are_jumpers no)
		(fp_rect
			(start 0.4318 0.9525)
			(end -0.4318 -0.9525)
			(stroke
				(width 0)
				(type default)
			)
			(fill no)
			(layer "B.CrtYd")
		)
		(fp_rect
			(start 0.4318 0.9525)
			(end -0.4318 -0.9525)
			(stroke
				(width 0)
				(type default)
			)
			(fill no)
			(layer "B.Fab")
		)
		(pad "1" smd custom
			(at 0 -0.4445 180)
			(size 0.1524 0.1524)
			(layers "B.Cu" "B.Mask" "B.Paste")
			(net "GB_VDDH")
			(options
				(clearance outline)
				(anchor circle)
			)
			(primitives
				(gr_poly
					(pts
						(arc
							(start 0.3048 0.2032)
							(mid 0.275042 0.275042)
							(end 0.2032 0.3048)
						)
						(arc
							(start -0.2032 0.3048)
							(mid -0.275042 0.275042)
							(end -0.3048 0.2032)
						)
						(arc
							(start -0.3048 -0.2032)
							(mid -0.275042 -0.275042)
							(end -0.2032 -0.3048)
						)
						(arc
							(start 0.2032 -0.3048)
							(mid 0.275042 -0.275042)
							(end 0.3048 -0.2032)
						)
					)
					(width 0)
					(fill yes)
				)
			)
		)
		(pad "2" smd custom
			(at 0 0.4445 180)
			(size 0.1524 0.1524)
			(layers "B.Cu" "B.Mask" "B.Paste")
			(net "GND")
			(options
				(clearance outline)
				(anchor circle)
			)
			(primitives
				(gr_poly
					(pts
						(arc
							(start 0.3048 0.2032)
							(mid 0.275042 0.275042)
							(end 0.2032 0.3048)
						)
						(arc
							(start -0.2032 0.3048)
							(mid -0.275042 0.275042)
							(end -0.3048 0.2032)
						)
						(arc
							(start -0.3048 -0.2032)
							(mid -0.275042 -0.275042)
							(end -0.2032 -0.3048)
						)
						(arc
							(start 0.2032 -0.3048)
							(mid 0.275042 -0.275042)
							(end 0.3048 -0.2032)
						)
					)
					(width 0)
					(fill yes)
				)
			)
		)
	)
	(footprint ""
		(layer "B.Cu")
		(at 163.2966 -37.7952 90)
		(property "Reference" "C374"
			(at 0 0 90)
			(layer "B.SilkS")
			(hide yes)
			(effects
				(font
					(size 1.27 1.27)
				)
				(justify mirror)
			)
		)
		(property "Value" "SCD1U16V2KX-3GP"
			(at -1.1811 -2.7051 90)
			(unlocked yes)
			(layer "B.Fab")
			(hide yes)
			(effects
				(font
					(size 1.016 1.016)
					(thickness 0.1524)
				)
				(justify mirror)
			)
		)
		(property "Device Type" "C402H22"
			(at -1.1811 -4.2291 90)
			(unlocked yes)
			(layer "B.Fab")
			(hide yes)
			(effects
				(font
					(size 1.016 1.016)
					(thickness 0.1524)
				)
				(justify mirror)
			)
		)
		(duplicate_pad_numbers_are_jumpers no)
		(fp_rect
			(start 0.4318 0.9525)
			(end -0.4318 -0.9525)
			(stroke
				(width 0)
				(type default)
			)
			(fill no)
			(layer "B.CrtYd")
		)
		(fp_rect
			(start 0.4318 0.9525)
			(end -0.4318 -0.9525)
			(stroke
				(width 0)
				(type default)
			)
			(fill no)
			(layer "B.Fab")
		)
		(pad "1" smd custom
			(at 0 -0.4445 270)
			(size 0.1524 0.1524)
			(layers "B.Cu" "B.Mask" "B.Paste")
			(net "SAS0_VDDH")
			(options
				(clearance outline)
				(anchor circle)
			)
			(primitives
				(gr_poly
					(pts
						(arc
							(start 0.3048 0.2032)
							(mid 0.275042 0.275042)
							(end 0.2032 0.3048)
						)
						(arc
							(start -0.2032 0.3048)
							(mid -0.275042 0.275042)
							(end -0.3048 0.2032)
						)
						(arc
							(start -0.3048 -0.2032)
							(mid -0.275042 -0.275042)
							(end -0.2032 -0.3048)
						)
						(arc
							(start 0.2032 -0.3048)
							(mid 0.275042 -0.275042)
							(end 0.3048 -0.2032)
						)
					)
					(width 0)
					(fill yes)
				)
			)
		)
		(pad "2" smd custom
			(at 0 0.4445 270)
			(size 0.1524 0.1524)
			(layers "B.Cu" "B.Mask" "B.Paste")
			(net "GND")
			(options
				(clearance outline)
				(anchor circle)
			)
			(primitives
				(gr_poly
					(pts
						(arc
							(start 0.3048 0.2032)
							(mid 0.275042 0.275042)
							(end 0.2032 0.3048)
						)
						(arc
							(start -0.2032 0.3048)
							(mid -0.275042 0.275042)
							(end -0.3048 0.2032)
						)
						(arc
							(start -0.3048 -0.2032)
							(mid -0.275042 -0.275042)
							(end -0.2032 -0.3048)
						)
						(arc
							(start 0.2032 -0.3048)
							(mid 0.275042 -0.275042)
							(end 0.3048 -0.2032)
						)
					)
					(width 0)
					(fill yes)
				)
			)
		)
	)
	(footprint ""
		(layer "B.Cu")
		(at 163.068 -61.976 -90)
		(property "Reference" "C368"
			(at 0 0 90)
			(layer "B.SilkS")
			(hide yes)
			(effects
				(font
					(size 1.27 1.27)
				)
				(justify mirror)
			)
		)
		(property "Value" "SC10U6D3V5KX-4GP"
			(at 0.0762 -6.1214 270)
			(unlocked yes)
			(layer "B.Fab")
			(hide yes)
			(effects
				(font
					(size 1.016 1.016)
					(thickness 0.1524)
				)
				(justify mirror)
			)
		)
		(property "Device Type" "C805H58"
			(at 0.0762 -8.1534 270)
			(unlocked yes)
			(layer "B.Fab")
			(hide yes)
			(effects
				(font
					(size 1.016 1.016)
					(thickness 0.1524)
				)
				(justify mirror)
			)
		)
		(duplicate_pad_numbers_are_jumpers no)
		(fp_line
			(start -0.635 0)
			(end 0.635 0)
			(stroke
				(width 0.508)
				(type default)
			)
			(layer "B.SilkS")
		)
		(fp_rect
			(start 0.9652 1.778)
			(end -0.9652 -1.778)
			(stroke
				(width 0)
				(type default)
			)
			(fill no)
			(layer "B.CrtYd")
		)
		(fp_poly
			(pts
				(xy 0.9652 -1.778) (xy -0.9652 -1.778) (xy -0.9652 1.778) (xy 0.9652 1.778)
			)
			(stroke
				(width 0)
				(type default)
			)
			(fill no)
			(layer "B.Fab")
		)
		(pad "1" smd rect
			(at 0 -0.9652 90)
			(size 1.397 1.143)
			(layers "B.Cu" "B.Mask" "B.Paste")
			(net "VDDA_SAS_REF_CLK")
		)
		(pad "2" smd rect
			(at 0 0.9652 90)
			(size 1.397 1.143)
			(layers "B.Cu" "B.Mask" "B.Paste")
			(net "GND")
		)
	)
	(footprint ""
		(layer "B.Cu")
		(at 157.740604 -60.617608 90)
		(property "Reference" "C361"
			(at 0 0 90)
			(layer "B.SilkS")
			(hide yes)
			(effects
				(font
					(size 1.27 1.27)
				)
				(justify mirror)
			)
		)
		(property "Value" "SC1U16V2KX-7-GP"
			(at -1.7526 -1.6002 90)
			(unlocked yes)
			(layer "B.Fab")
			(hide yes)
			(effects
				(font
					(size 1.016 1.016)
					(thickness 0.1524)
				)
				(justify mirror)
			)
		)
		(property "Device Type" "C402-TO0D2H24"
			(at -1.7526 -3.1242 90)
			(unlocked yes)
			(layer "B.Fab")
			(hide yes)
			(effects
				(font
					(size 1.016 1.016)
					(thickness 0.1524)
				)
				(justify mirror)
			)
		)
		(duplicate_pad_numbers_are_jumpers no)
		(fp_rect
			(start 0.4826 0.889)
			(end -0.4826 -0.889)
			(stroke
				(width 0)
				(type default)
			)
			(fill no)
			(layer "B.CrtYd")
		)
		(fp_rect
			(start 0.4826 0.889)
			(end -0.4826 -0.889)
			(stroke
				(width 0)
				(type default)
			)
			(fill no)
			(layer "B.Fab")
		)
		(pad "1" smd custom
			(at 0 -0.4572 270)
			(size 0.1524 0.1524)
			(layers "B.Cu" "B.Mask" "B.Paste")
			(net "SHELL_PLL_VDD")
			(options
				(clearance outline)
				(anchor circle)
			)
			(primitives
				(gr_poly
					(pts
						(arc
							(start -0.254 -0.3048)
							(mid -0.325842 -0.275042)
							(end -0.3556 -0.2032)
						)
						(arc
							(start -0.3556 0.2032)
							(mid -0.325842 0.275042)
							(end -0.254 0.3048)
						)
						(arc
							(start 0.254 0.3048)
							(mid 0.325842 0.275042)
							(end 0.3556 0.2032)
						)
						(arc
							(start 0.3556 -0.2032)
							(mid 0.325842 -0.275042)
							(end 0.254 -0.3048)
						)
					)
					(width 0)
					(fill yes)
				)
			)
		)
		(pad "2" smd custom
			(at 0 0.4572 270)
			(size 0.1524 0.1524)
			(layers "B.Cu" "B.Mask" "B.Paste")
			(net "GND")
			(options
				(clearance outline)
				(anchor circle)
			)
			(primitives
				(gr_poly
					(pts
						(arc
							(start -0.254 -0.3048)
							(mid -0.325842 -0.275042)
							(end -0.3556 -0.2032)
						)
						(arc
							(start -0.3556 0.2032)
							(mid -0.325842 0.275042)
							(end -0.254 0.3048)
						)
						(arc
							(start 0.254 0.3048)
							(mid 0.325842 0.275042)
							(end 0.3556 0.2032)
						)
						(arc
							(start 0.3556 -0.2032)
							(mid 0.325842 -0.275042)
							(end 0.254 -0.3048)
						)
					)
					(width 0)
					(fill yes)
				)
			)
		)
	)
	(footprint ""
		(layer "B.Cu")
		(at 131.6863 -120.904 -90)
		(property "Reference" "R10"
			(at 0 0 90)
			(layer "B.SilkS")
			(hide yes)
			(effects
				(font
					(size 1.27 1.27)
				)
				(justify mirror)
			)
		)
		(property "Value" "1KR2F-3-GP"
			(at -0.064008 -3.993896 270)
			(unlocked yes)
			(layer "B.Fab")
			(hide yes)
			(effects
				(font
					(size 1.016 1.016)
					(thickness 0.1524)
				)
				(justify mirror)
			)
		)
		(property "Device Type" "R402H16"
			(at -0.064008 -5.517896 270)
			(unlocked yes)
			(layer "B.Fab")
			(hide yes)
			(effects
				(font
					(size 1.016 1.016)
					(thickness 0.1524)
				)
				(justify mirror)
			)
		)
		(duplicate_pad_numbers_are_jumpers no)
		(fp_line
			(start -0.508 -0.9398)
			(end 0.508 -0.9398)
			(stroke
				(width 0.1524)
				(type default)
			)
			(layer "B.SilkS")
		)
		(fp_line
			(start 0.508 -0.9398)
			(end 0.508 0.9398)
			(stroke
				(width 0.1524)
				(type default)
			)
			(layer "B.SilkS")
		)
		(fp_rect
			(start 0.508 0.9398)
			(end -0.508 -0.9398)
			(stroke
				(width 0)
				(type default)
			)
			(fill no)
			(layer "B.CrtYd")
		)
		(fp_rect
			(start 0.508 0.9398)
			(end -0.508 -0.9398)
			(stroke
				(width 0)
				(type default)
			)
			(fill no)
			(layer "B.Fab")
		)
		(pad "1" smd custom
			(at 0 -0.4445 90)
			(size 0.1397 0.1397)
			(layers "B.Cu" "B.Mask" "B.Paste")
			(net "P1V5_C")
			(options
				(clearance outline)
				(anchor circle)
			)
			(primitives
				(gr_poly
					(pts
						(arc
							(start -0.1778 0.2794)
							(mid -0.249642 0.249642)
							(end -0.2794 0.1778)
						)
						(arc
							(start -0.2794 -0.1778)
							(mid -0.249642 -0.249642)
							(end -0.1778 -0.2794)
						)
						(arc
							(start 0.1778 -0.2794)
							(mid 0.249642 -0.249642)
							(end 0.2794 -0.1778)
						)
						(arc
							(start 0.2794 0.1778)
							(mid 0.249642 0.249642)
							(end 0.1778 0.2794)
						)
					)
					(width 0)
					(fill yes)
				)
			)
		)
		(pad "2" smd custom
			(at 0 0.4445 90)
			(size 0.1397 0.1397)
			(layers "B.Cu" "B.Mask" "B.Paste")
			(net "GND")
			(options
				(clearance outline)
				(anchor circle)
			)
			(primitives
				(gr_poly
					(pts
						(arc
							(start -0.1778 0.2794)
							(mid -0.249642 0.249642)
							(end -0.2794 0.1778)
						)
						(arc
							(start -0.2794 -0.1778)
							(mid -0.249642 -0.249642)
							(end -0.1778 -0.2794)
						)
						(arc
							(start 0.1778 -0.2794)
							(mid 0.249642 -0.249642)
							(end 0.2794 -0.1778)
						)
						(arc
							(start 0.2794 0.1778)
							(mid 0.249642 0.249642)
							(end 0.1778 0.2794)
						)
					)
					(width 0)
					(fill yes)
				)
			)
		)
	)
	(footprint ""
		(layer "B.Cu")
		(at 171.532804 -20.88642)
		(property "Reference" "C318"
			(at 0 0 0)
			(layer "B.SilkS")
			(hide yes)
			(effects
				(font
					(size 1.27 1.27)
				)
				(justify mirror)
			)
		)
		(property "Value" "SCD22U10V1KX-GP"
			(at 2.8321 -1.7399 0)
			(unlocked yes)
			(layer "B.Fab")
			(hide yes)
			(effects
				(font
					(size 1.016 1.016)
					(thickness 0.1524)
				)
				(justify mirror)
			)
		)
		(property "Device Type" "C0201H13"
			(at 2.8321 -3.2639 0)
			(unlocked yes)
			(layer "B.Fab")
			(hide yes)
			(effects
				(font
					(size 1.016 1.016)
					(thickness 0.1524)
				)
				(justify mirror)
			)
		)
		(duplicate_pad_numbers_are_jumpers no)
		(fp_rect
			(start 0.2794 0.6477)
			(end -0.2794 -0.6477)
			(stroke
				(width 0)
				(type default)
			)
			(fill no)
			(layer "B.CrtYd")
		)
		(fp_rect
			(start 0.2794 0.6477)
			(end -0.2794 -0.6477)
			(stroke
				(width 0)
				(type default)
			)
			(fill no)
			(layer "B.Fab")
		)
		(pad "1" smd custom
			(at 0 -0.2794 180)
			(size 0.0762 0.0762)
			(layers "B.Cu" "B.Mask" "B.Paste")
			(net "PCIE_SCC_TO_COMP_C_3_DN")
			(options
				(clearance outline)
				(anchor circle)
			)
			(primitives
				(gr_poly
					(pts
						(arc
							(start 0.1524 0.127)
							(mid 0.137521 0.162921)
							(end 0.1016 0.1778)
						)
						(arc
							(start -0.1016 0.1778)
							(mid -0.137521 0.162921)
							(end -0.1524 0.127)
						)
						(arc
							(start -0.1524 -0.127)
							(mid -0.137521 -0.162921)
							(end -0.1016 -0.1778)
						)
						(arc
							(start 0.1016 -0.1778)
							(mid 0.137521 -0.162921)
							(end 0.1524 -0.127)
						)
					)
					(width 0)
					(fill yes)
				)
			)
		)
		(pad "2" smd custom
			(at 0 0.2794 180)
			(size 0.0762 0.0762)
			(layers "B.Cu" "B.Mask" "B.Paste")
			(net "PCIE_SCC_TO_COMP_3_DN")
			(options
				(clearance outline)
				(anchor circle)
			)
			(primitives
				(gr_poly
					(pts
						(arc
							(start 0.1524 0.127)
							(mid 0.137521 0.162921)
							(end 0.1016 0.1778)
						)
						(arc
							(start -0.1016 0.1778)
							(mid -0.137521 0.162921)
							(end -0.1524 0.127)
						)
						(arc
							(start -0.1524 -0.127)
							(mid -0.137521 -0.162921)
							(end -0.1016 -0.1778)
						)
						(arc
							(start 0.1016 -0.1778)
							(mid 0.137521 -0.162921)
							(end 0.1524 -0.127)
						)
					)
					(width 0)
					(fill yes)
				)
			)
		)
	)
	(footprint ""
		(layer "B.Cu")
		(at 113.6142 -87.0204)
		(property "Reference" "R405"
			(at 0 0 0)
			(layer "B.SilkS")
			(hide yes)
			(effects
				(font
					(size 1.27 1.27)
				)
				(justify mirror)
			)
		)
		(property "Value" "4K7R2F-GP"
			(at -0.064008 -3.993896 0)
			(unlocked yes)
			(layer "B.Fab")
			(hide yes)
			(effects
				(font
					(size 1.016 1.016)
					(thickness 0.1524)
				)
				(justify mirror)
			)
		)
		(property "Device Type" "R402H16"
			(at -0.064008 -5.517896 0)
			(unlocked yes)
			(layer "B.Fab")
			(hide yes)
			(effects
				(font
					(size 1.016 1.016)
					(thickness 0.1524)
				)
				(justify mirror)
			)
		)
		(duplicate_pad_numbers_are_jumpers no)
		(fp_line
			(start -0.508 -0.9398)
			(end 0.508 -0.9398)
			(stroke
				(width 0.1524)
				(type default)
			)
			(layer "B.SilkS")
		)
		(fp_line
			(start 0.508 -0.9398)
			(end 0.508 0.9398)
			(stroke
				(width 0.1524)
				(type default)
			)
			(layer "B.SilkS")
		)
		(fp_rect
			(start 0.508 0.9398)
			(end -0.508 -0.9398)
			(stroke
				(width 0)
				(type default)
			)
			(fill no)
			(layer "B.CrtYd")
		)
		(fp_rect
			(start 0.508 0.9398)
			(end -0.508 -0.9398)
			(stroke
				(width 0)
				(type default)
			)
			(fill no)
			(layer "B.Fab")
		)
		(pad "1" smd custom
			(at 0 -0.4445 180)
			(size 0.1397 0.1397)
			(layers "B.Cu" "B.Mask" "B.Paste")
			(net "P1V8_E")
			(options
				(clearance outline)
				(anchor circle)
			)
			(primitives
				(gr_poly
					(pts
						(arc
							(start -0.1778 0.2794)
							(mid -0.249642 0.249642)
							(end -0.2794 0.1778)
						)
						(arc
							(start -0.2794 -0.1778)
							(mid -0.249642 -0.249642)
							(end -0.1778 -0.2794)
						)
						(arc
							(start 0.1778 -0.2794)
							(mid 0.249642 -0.249642)
							(end 0.2794 -0.1778)
						)
						(arc
							(start 0.2794 0.1778)
							(mid 0.249642 0.249642)
							(end 0.1778 0.2794)
						)
					)
					(width 0)
					(fill yes)
				)
			)
		)
		(pad "2" smd custom
			(at 0 0.4445 180)
			(size 0.1397 0.1397)
			(layers "B.Cu" "B.Mask" "B.Paste")
			(net "EXP_XM_ADDR_19")
			(options
				(clearance outline)
				(anchor circle)
			)
			(primitives
				(gr_poly
					(pts
						(arc
							(start -0.1778 0.2794)
							(mid -0.249642 0.249642)
							(end -0.2794 0.1778)
						)
						(arc
							(start -0.2794 -0.1778)
							(mid -0.249642 -0.249642)
							(end -0.1778 -0.2794)
						)
						(arc
							(start 0.1778 -0.2794)
							(mid 0.249642 -0.249642)
							(end 0.2794 -0.1778)
						)
						(arc
							(start 0.2794 0.1778)
							(mid 0.249642 0.249642)
							(end 0.1778 0.2794)
						)
					)
					(width 0)
					(fill yes)
				)
			)
		)
	)
	(footprint ""
		(layer "B.Cu")
		(at 172.995336 -51.19243 -90)
		(property "Reference" "R232"
			(at 0 0 90)
			(layer "B.SilkS")
			(hide yes)
			(effects
				(font
					(size 1.27 1.27)
				)
				(justify mirror)
			)
		)
		(property "Value" "10KR2F-2-GP"
			(at -0.064008 -3.993896 270)
			(unlocked yes)
			(layer "B.Fab")
			(hide yes)
			(effects
				(font
					(size 1.016 1.016)
					(thickness 0.1524)
				)
				(justify mirror)
			)
		)
		(property "Device Type" "R402H16"
			(at -0.064008 -5.517896 270)
			(unlocked yes)
			(layer "B.Fab")
			(hide yes)
			(effects
				(font
					(size 1.016 1.016)
					(thickness 0.1524)
				)
				(justify mirror)
			)
		)
		(duplicate_pad_numbers_are_jumpers no)
		(fp_line
			(start -0.508 -0.9398)
			(end 0.508 -0.9398)
			(stroke
				(width 0.1524)
				(type default)
			)
			(layer "B.SilkS")
		)
		(fp_line
			(start 0.508 -0.9398)
			(end 0.508 0.9398)
			(stroke
				(width 0.1524)
				(type default)
			)
			(layer "B.SilkS")
		)
		(fp_rect
			(start 0.508 0.9398)
			(end -0.508 -0.9398)
			(stroke
				(width 0)
				(type default)
			)
			(fill no)
			(layer "B.CrtYd")
		)
		(fp_rect
			(start 0.508 0.9398)
			(end -0.508 -0.9398)
			(stroke
				(width 0)
				(type default)
			)
			(fill no)
			(layer "B.Fab")
		)
		(pad "1" smd custom
			(at 0 -0.4445 90)
			(size 0.1397 0.1397)
			(layers "B.Cu" "B.Mask" "B.Paste")
			(net "P1V8_C")
			(options
				(clearance outline)
				(anchor circle)
			)
			(primitives
				(gr_poly
					(pts
						(arc
							(start -0.1778 0.2794)
							(mid -0.249642 0.249642)
							(end -0.2794 0.1778)
						)
						(arc
							(start -0.2794 -0.1778)
							(mid -0.249642 -0.249642)
							(end -0.1778 -0.2794)
						)
						(arc
							(start 0.1778 -0.2794)
							(mid 0.249642 -0.249642)
							(end 0.2794 -0.1778)
						)
						(arc
							(start 0.2794 0.1778)
							(mid 0.249642 0.249642)
							(end 0.1778 0.2794)
						)
					)
					(width 0)
					(fill yes)
				)
			)
		)
		(pad "2" smd custom
			(at 0 0.4445 90)
			(size 0.1397 0.1397)
			(layers "B.Cu" "B.Mask" "B.Paste")
			(net "AVSO_IDDTN18")
			(options
				(clearance outline)
				(anchor circle)
			)
			(primitives
				(gr_poly
					(pts
						(arc
							(start -0.1778 0.2794)
							(mid -0.249642 0.249642)
							(end -0.2794 0.1778)
						)
						(arc
							(start -0.2794 -0.1778)
							(mid -0.249642 -0.249642)
							(end -0.1778 -0.2794)
						)
						(arc
							(start 0.1778 -0.2794)
							(mid 0.249642 -0.249642)
							(end 0.2794 -0.1778)
						)
						(arc
							(start 0.2794 0.1778)
							(mid 0.249642 0.249642)
							(end 0.1778 0.2794)
						)
					)
					(width 0)
					(fill yes)
				)
			)
		)
	)
	(footprint ""
		(layer "B.Cu")
		(at 115.834414 -90.51417 -90)
		(property "Reference" "R37"
			(at 0 0 90)
			(layer "B.SilkS")
			(hide yes)
			(effects
				(font
					(size 1.27 1.27)
				)
				(justify mirror)
			)
		)
		(property "Value" "4K7R2F-GP"
			(at -0.064008 -3.993896 270)
			(unlocked yes)
			(layer "B.Fab")
			(hide yes)
			(effects
				(font
					(size 1.016 1.016)
					(thickness 0.1524)
				)
				(justify mirror)
			)
		)
		(property "Device Type" "R402H16"
			(at -0.064008 -5.517896 270)
			(unlocked yes)
			(layer "B.Fab")
			(hide yes)
			(effects
				(font
					(size 1.016 1.016)
					(thickness 0.1524)
				)
				(justify mirror)
			)
		)
		(duplicate_pad_numbers_are_jumpers no)
		(fp_line
			(start -0.508 -0.9398)
			(end 0.508 -0.9398)
			(stroke
				(width 0.1524)
				(type default)
			)
			(layer "B.SilkS")
		)
		(fp_line
			(start 0.508 -0.9398)
			(end 0.508 0.9398)
			(stroke
				(width 0.1524)
				(type default)
			)
			(layer "B.SilkS")
		)
		(fp_rect
			(start 0.508 0.9398)
			(end -0.508 -0.9398)
			(stroke
				(width 0)
				(type default)
			)
			(fill no)
			(layer "B.CrtYd")
		)
		(fp_rect
			(start 0.508 0.9398)
			(end -0.508 -0.9398)
			(stroke
				(width 0)
				(type default)
			)
			(fill no)
			(layer "B.Fab")
		)
		(pad "1" smd custom
			(at 0 -0.4445 90)
			(size 0.1397 0.1397)
			(layers "B.Cu" "B.Mask" "B.Paste")
			(net "P1V8_E")
			(options
				(clearance outline)
				(anchor circle)
			)
			(primitives
				(gr_poly
					(pts
						(arc
							(start -0.1778 0.2794)
							(mid -0.249642 0.249642)
							(end -0.2794 0.1778)
						)
						(arc
							(start -0.2794 -0.1778)
							(mid -0.249642 -0.249642)
							(end -0.1778 -0.2794)
						)
						(arc
							(start 0.1778 -0.2794)
							(mid 0.249642 -0.249642)
							(end 0.2794 -0.1778)
						)
						(arc
							(start 0.2794 0.1778)
							(mid 0.249642 0.249642)
							(end 0.1778 0.2794)
						)
					)
					(width 0)
					(fill yes)
				)
			)
		)
		(pad "2" smd custom
			(at 0 0.4445 90)
			(size 0.1397 0.1397)
			(layers "B.Cu" "B.Mask" "B.Paste")
			(net "EXP_GPIO14")
			(options
				(clearance outline)
				(anchor circle)
			)
			(primitives
				(gr_poly
					(pts
						(arc
							(start -0.1778 0.2794)
							(mid -0.249642 0.249642)
							(end -0.2794 0.1778)
						)
						(arc
							(start -0.2794 -0.1778)
							(mid -0.249642 -0.249642)
							(end -0.1778 -0.2794)
						)
						(arc
							(start 0.1778 -0.2794)
							(mid 0.249642 -0.249642)
							(end 0.2794 -0.1778)
						)
						(arc
							(start 0.2794 0.1778)
							(mid 0.249642 0.249642)
							(end 0.1778 0.2794)
						)
					)
					(width 0)
					(fill yes)
				)
			)
		)
	)
	(footprint ""
		(layer "B.Cu")
		(at 134.493254 -65.066418 -90)
		(property "Reference" "C21"
			(at 0 0 90)
			(layer "B.SilkS")
			(hide yes)
			(effects
				(font
					(size 1.27 1.27)
				)
				(justify mirror)
			)
		)
		(property "Value" "SCD01U16V1KX-GP"
			(at 2.8321 -1.7399 270)
			(unlocked yes)
			(layer "B.Fab")
			(hide yes)
			(effects
				(font
					(size 1.016 1.016)
					(thickness 0.1524)
				)
				(justify mirror)
			)
		)
		(property "Device Type" "C0201H13"
			(at 2.8321 -3.2639 270)
			(unlocked yes)
			(layer "B.Fab")
			(hide yes)
			(effects
				(font
					(size 1.016 1.016)
					(thickness 0.1524)
				)
				(justify mirror)
			)
		)
		(duplicate_pad_numbers_are_jumpers no)
		(fp_rect
			(start 0.2794 0.6477)
			(end -0.2794 -0.6477)
			(stroke
				(width 0)
				(type default)
			)
			(fill no)
			(layer "B.CrtYd")
		)
		(fp_rect
			(start 0.2794 0.6477)
			(end -0.2794 -0.6477)
			(stroke
				(width 0)
				(type default)
			)
			(fill no)
			(layer "B.Fab")
		)
		(pad "1" smd custom
			(at 0 -0.2794 90)
			(size 0.0762 0.0762)
			(layers "B.Cu" "B.Mask" "B.Paste")
			(net "PHY_DPB_TO_SCC_1_DP")
			(options
				(clearance outline)
				(anchor circle)
			)
			(primitives
				(gr_poly
					(pts
						(arc
							(start 0.1524 0.127)
							(mid 0.137521 0.162921)
							(end 0.1016 0.1778)
						)
						(arc
							(start -0.1016 0.1778)
							(mid -0.137521 0.162921)
							(end -0.1524 0.127)
						)
						(arc
							(start -0.1524 -0.127)
							(mid -0.137521 -0.162921)
							(end -0.1016 -0.1778)
						)
						(arc
							(start 0.1016 -0.1778)
							(mid 0.137521 -0.162921)
							(end 0.1524 -0.127)
						)
					)
					(width 0)
					(fill yes)
				)
			)
		)
		(pad "2" smd custom
			(at 0 0.2794 90)
			(size 0.0762 0.0762)
			(layers "B.Cu" "B.Mask" "B.Paste")
			(net "PHY_DPB_TO_SCC_C_1_DP")
			(options
				(clearance outline)
				(anchor circle)
			)
			(primitives
				(gr_poly
					(pts
						(arc
							(start 0.1524 0.127)
							(mid 0.137521 0.162921)
							(end 0.1016 0.1778)
						)
						(arc
							(start -0.1016 0.1778)
							(mid -0.137521 0.162921)
							(end -0.1524 0.127)
						)
						(arc
							(start -0.1524 -0.127)
							(mid -0.137521 -0.162921)
							(end -0.1016 -0.1778)
						)
						(arc
							(start 0.1016 -0.1778)
							(mid 0.137521 -0.162921)
							(end 0.1524 -0.127)
						)
					)
					(width 0)
					(fill yes)
				)
			)
		)
	)
	(footprint ""
		(layer "B.Cu")
		(at 114.681 -68.6562)
		(property "Reference" "C166"
			(at 0 0 0)
			(layer "B.SilkS")
			(hide yes)
			(effects
				(font
					(size 1.27 1.27)
				)
				(justify mirror)
			)
		)
		(property "Value" "SCD1U6D3V1KX-GP"
			(at 2.8321 -1.7399 0)
			(unlocked yes)
			(layer "B.Fab")
			(hide yes)
			(effects
				(font
					(size 1.016 1.016)
					(thickness 0.1524)
				)
				(justify mirror)
			)
		)
		(property "Device Type" "C0201H13"
			(at 2.8321 -3.2639 0)
			(unlocked yes)
			(layer "B.Fab")
			(hide yes)
			(effects
				(font
					(size 1.016 1.016)
					(thickness 0.1524)
				)
				(justify mirror)
			)
		)
		(duplicate_pad_numbers_are_jumpers no)
		(fp_rect
			(start 0.2794 0.6477)
			(end -0.2794 -0.6477)
			(stroke
				(width 0)
				(type default)
			)
			(fill no)
			(layer "B.CrtYd")
		)
		(fp_rect
			(start 0.2794 0.6477)
			(end -0.2794 -0.6477)
			(stroke
				(width 0)
				(type default)
			)
			(fill no)
			(layer "B.Fab")
		)
		(pad "1" smd custom
			(at 0 -0.2794 180)
			(size 0.0762 0.0762)
			(layers "B.Cu" "B.Mask" "B.Paste")
			(net "P0V9")
			(options
				(clearance outline)
				(anchor circle)
			)
			(primitives
				(gr_poly
					(pts
						(arc
							(start 0.1524 0.127)
							(mid 0.137521 0.162921)
							(end 0.1016 0.1778)
						)
						(arc
							(start -0.1016 0.1778)
							(mid -0.137521 0.162921)
							(end -0.1524 0.127)
						)
						(arc
							(start -0.1524 -0.127)
							(mid -0.137521 -0.162921)
							(end -0.1016 -0.1778)
						)
						(arc
							(start 0.1016 -0.1778)
							(mid 0.137521 -0.162921)
							(end 0.1524 -0.127)
						)
					)
					(width 0)
					(fill yes)
				)
			)
		)
		(pad "2" smd custom
			(at 0 0.2794 180)
			(size 0.0762 0.0762)
			(layers "B.Cu" "B.Mask" "B.Paste")
			(net "GND")
			(options
				(clearance outline)
				(anchor circle)
			)
			(primitives
				(gr_poly
					(pts
						(arc
							(start 0.1524 0.127)
							(mid 0.137521 0.162921)
							(end 0.1016 0.1778)
						)
						(arc
							(start -0.1016 0.1778)
							(mid -0.137521 0.162921)
							(end -0.1524 0.127)
						)
						(arc
							(start -0.1524 -0.127)
							(mid -0.137521 -0.162921)
							(end -0.1016 -0.1778)
						)
						(arc
							(start 0.1016 -0.1778)
							(mid 0.137521 -0.162921)
							(end 0.1524 -0.127)
						)
					)
					(width 0)
					(fill yes)
				)
			)
		)
	)
	(footprint ""
		(layer "B.Cu")
		(at 116.5098 -75.9968 180)
		(property "Reference" "C138"
			(at 0 0 0)
			(layer "B.SilkS")
			(hide yes)
			(effects
				(font
					(size 1.27 1.27)
				)
				(justify mirror)
			)
		)
		(property "Value" "SCD1U6D3V1KX-GP"
			(at 2.8321 -1.7399 180)
			(unlocked yes)
			(layer "B.Fab")
			(hide yes)
			(effects
				(font
					(size 1.016 1.016)
					(thickness 0.1524)
				)
				(justify mirror)
			)
		)
		(property "Device Type" "C0201H13"
			(at 2.8321 -3.2639 180)
			(unlocked yes)
			(layer "B.Fab")
			(hide yes)
			(effects
				(font
					(size 1.016 1.016)
					(thickness 0.1524)
				)
				(justify mirror)
			)
		)
		(duplicate_pad_numbers_are_jumpers no)
		(fp_rect
			(start 0.2794 0.6477)
			(end -0.2794 -0.6477)
			(stroke
				(width 0)
				(type default)
			)
			(fill no)
			(layer "B.CrtYd")
		)
		(fp_rect
			(start 0.2794 0.6477)
			(end -0.2794 -0.6477)
			(stroke
				(width 0)
				(type default)
			)
			(fill no)
			(layer "B.Fab")
		)
		(pad "1" smd custom
			(at 0 -0.2794)
			(size 0.0762 0.0762)
			(layers "B.Cu" "B.Mask" "B.Paste")
			(net "P1V8_E")
			(options
				(clearance outline)
				(anchor circle)
			)
			(primitives
				(gr_poly
					(pts
						(arc
							(start 0.1524 0.127)
							(mid 0.137521 0.162921)
							(end 0.1016 0.1778)
						)
						(arc
							(start -0.1016 0.1778)
							(mid -0.137521 0.162921)
							(end -0.1524 0.127)
						)
						(arc
							(start -0.1524 -0.127)
							(mid -0.137521 -0.162921)
							(end -0.1016 -0.1778)
						)
						(arc
							(start 0.1016 -0.1778)
							(mid 0.137521 -0.162921)
							(end 0.1524 -0.127)
						)
					)
					(width 0)
					(fill yes)
				)
			)
		)
		(pad "2" smd custom
			(at 0 0.2794)
			(size 0.0762 0.0762)
			(layers "B.Cu" "B.Mask" "B.Paste")
			(net "GND")
			(options
				(clearance outline)
				(anchor circle)
			)
			(primitives
				(gr_poly
					(pts
						(arc
							(start 0.1524 0.127)
							(mid 0.137521 0.162921)
							(end 0.1016 0.1778)
						)
						(arc
							(start -0.1016 0.1778)
							(mid -0.137521 0.162921)
							(end -0.1524 0.127)
						)
						(arc
							(start -0.1524 -0.127)
							(mid -0.137521 -0.162921)
							(end -0.1016 -0.1778)
						)
						(arc
							(start 0.1016 -0.1778)
							(mid 0.137521 -0.162921)
							(end 0.1524 -0.127)
						)
					)
					(width 0)
					(fill yes)
				)
			)
		)
	)
	(footprint ""
		(layer "B.Cu")
		(at 123.150376 -91.23553 -90)
		(property "Reference" "R563"
			(at 0 0 90)
			(layer "B.SilkS")
			(hide yes)
			(effects
				(font
					(size 1.27 1.27)
				)
				(justify mirror)
			)
		)
		(property "Value" "10KR2F-2-GP"
			(at -0.064008 -3.993896 270)
			(unlocked yes)
			(layer "B.Fab")
			(hide yes)
			(effects
				(font
					(size 1.016 1.016)
					(thickness 0.1524)
				)
				(justify mirror)
			)
		)
		(property "Device Type" "R402H16"
			(at -0.064008 -5.517896 270)
			(unlocked yes)
			(layer "B.Fab")
			(hide yes)
			(effects
				(font
					(size 1.016 1.016)
					(thickness 0.1524)
				)
				(justify mirror)
			)
		)
		(duplicate_pad_numbers_are_jumpers no)
		(fp_line
			(start -0.508 -0.9398)
			(end 0.508 -0.9398)
			(stroke
				(width 0.1524)
				(type default)
			)
			(layer "B.SilkS")
		)
		(fp_line
			(start 0.508 -0.9398)
			(end 0.508 0.9398)
			(stroke
				(width 0.1524)
				(type default)
			)
			(layer "B.SilkS")
		)
		(fp_rect
			(start 0.508 0.9398)
			(end -0.508 -0.9398)
			(stroke
				(width 0)
				(type default)
			)
			(fill no)
			(layer "B.CrtYd")
		)
		(fp_rect
			(start 0.508 0.9398)
			(end -0.508 -0.9398)
			(stroke
				(width 0)
				(type default)
			)
			(fill no)
			(layer "B.Fab")
		)
		(pad "1" smd custom
			(at 0 -0.4445 90)
			(size 0.1397 0.1397)
			(layers "B.Cu" "B.Mask" "B.Paste")
			(net "BMC_SPARE_0_LS")
			(options
				(clearance outline)
				(anchor circle)
			)
			(primitives
				(gr_poly
					(pts
						(arc
							(start -0.1778 0.2794)
							(mid -0.249642 0.249642)
							(end -0.2794 0.1778)
						)
						(arc
							(start -0.2794 -0.1778)
							(mid -0.249642 -0.249642)
							(end -0.1778 -0.2794)
						)
						(arc
							(start 0.1778 -0.2794)
							(mid 0.249642 -0.249642)
							(end 0.2794 -0.1778)
						)
						(arc
							(start 0.2794 0.1778)
							(mid 0.249642 0.249642)
							(end 0.1778 0.2794)
						)
					)
					(width 0)
					(fill yes)
				)
			)
		)
		(pad "2" smd custom
			(at 0 0.4445 90)
			(size 0.1397 0.1397)
			(layers "B.Cu" "B.Mask" "B.Paste")
			(net "P1V8_E")
			(options
				(clearance outline)
				(anchor circle)
			)
			(primitives
				(gr_poly
					(pts
						(arc
							(start -0.1778 0.2794)
							(mid -0.249642 0.249642)
							(end -0.2794 0.1778)
						)
						(arc
							(start -0.2794 -0.1778)
							(mid -0.249642 -0.249642)
							(end -0.1778 -0.2794)
						)
						(arc
							(start 0.1778 -0.2794)
							(mid 0.249642 -0.249642)
							(end 0.2794 -0.1778)
						)
						(arc
							(start 0.2794 0.1778)
							(mid 0.249642 0.249642)
							(end 0.1778 0.2794)
						)
					)
					(width 0)
					(fill yes)
				)
			)
		)
	)
	(footprint ""
		(layer "B.Cu")
		(at 188.6458 -26.1874 90)
		(property "Reference" "TP65"
			(at 0 0 90)
			(layer "B.SilkS")
			(hide yes)
			(effects
				(font
					(size 1.27 1.27)
				)
				(justify mirror)
			)
		)
		(property "Value" "TPAD28-2-GP"
			(at 0.0127 -1.6637 90)
			(unlocked yes)
			(layer "B.Fab")
			(hide yes)
			(effects
				(font
					(size 1.016 1.016)
					(thickness 0.1524)
				)
				(justify mirror)
			)
		)
		(property "Device Type" "TPAD28"
			(at 0.0127 -3.1877 90)
			(unlocked yes)
			(layer "B.Fab")
			(hide yes)
			(effects
				(font
					(size 1.016 1.016)
					(thickness 0.1524)
				)
				(justify mirror)
			)
		)
		(duplicate_pad_numbers_are_jumpers no)
		(fp_poly
			(pts
				(arc
					(start 0 0.3556)
					(mid 0 -0.3556)
					(end 0 0.3556)
				)
			)
			(stroke
				(width 0)
				(type default)
			)
			(fill no)
			(layer "B.CrtYd")
		)
		(fp_poly
			(pts
				(arc
					(start 0 0.6096)
					(mid 0 -0.6096)
					(end 0 0.6096)
				)
			)
			(stroke
				(width 0)
				(type default)
			)
			(fill no)
			(layer "B.Fab")
		)
		(pad "1" smd circle
			(at 0 0 270)
			(size 0.7112 0.7112)
			(layers "B.Cu" "B.Mask" "B.Paste")
			(net "IOC_GPIO_12")
		)
	)
	(footprint ""
		(layer "B.Cu")
		(at 166.6748 -60.5536 90)
		(property "Reference" "C354"
			(at 0 0 90)
			(layer "B.SilkS")
			(hide yes)
			(effects
				(font
					(size 1.27 1.27)
				)
				(justify mirror)
			)
		)
		(property "Value" "SCD1U16V2KX-3GP"
			(at -1.1811 -2.7051 90)
			(unlocked yes)
			(layer "B.Fab")
			(hide yes)
			(effects
				(font
					(size 1.016 1.016)
					(thickness 0.1524)
				)
				(justify mirror)
			)
		)
		(property "Device Type" "C402H22"
			(at -1.1811 -4.2291 90)
			(unlocked yes)
			(layer "B.Fab")
			(hide yes)
			(effects
				(font
					(size 1.016 1.016)
					(thickness 0.1524)
				)
				(justify mirror)
			)
		)
		(duplicate_pad_numbers_are_jumpers no)
		(fp_rect
			(start 0.4318 0.9525)
			(end -0.4318 -0.9525)
			(stroke
				(width 0)
				(type default)
			)
			(fill no)
			(layer "B.CrtYd")
		)
		(fp_rect
			(start 0.4318 0.9525)
			(end -0.4318 -0.9525)
			(stroke
				(width 0)
				(type default)
			)
			(fill no)
			(layer "B.Fab")
		)
		(pad "1" smd custom
			(at 0 -0.4445 270)
			(size 0.1524 0.1524)
			(layers "B.Cu" "B.Mask" "B.Paste")
			(net "HM40ADC_VDDA")
			(options
				(clearance outline)
				(anchor circle)
			)
			(primitives
				(gr_poly
					(pts
						(arc
							(start 0.3048 0.2032)
							(mid 0.275042 0.275042)
							(end 0.2032 0.3048)
						)
						(arc
							(start -0.2032 0.3048)
							(mid -0.275042 0.275042)
							(end -0.3048 0.2032)
						)
						(arc
							(start -0.3048 -0.2032)
							(mid -0.275042 -0.275042)
							(end -0.2032 -0.3048)
						)
						(arc
							(start 0.2032 -0.3048)
							(mid 0.275042 -0.275042)
							(end 0.3048 -0.2032)
						)
					)
					(width 0)
					(fill yes)
				)
			)
		)
		(pad "2" smd custom
			(at 0 0.4445 270)
			(size 0.1524 0.1524)
			(layers "B.Cu" "B.Mask" "B.Paste")
			(net "GND")
			(options
				(clearance outline)
				(anchor circle)
			)
			(primitives
				(gr_poly
					(pts
						(arc
							(start 0.3048 0.2032)
							(mid 0.275042 0.275042)
							(end 0.2032 0.3048)
						)
						(arc
							(start -0.2032 0.3048)
							(mid -0.275042 0.275042)
							(end -0.3048 0.2032)
						)
						(arc
							(start -0.3048 -0.2032)
							(mid -0.275042 -0.275042)
							(end -0.2032 -0.3048)
						)
						(arc
							(start 0.2032 -0.3048)
							(mid 0.275042 -0.275042)
							(end 0.3048 -0.2032)
						)
					)
					(width 0)
					(fill yes)
				)
			)
		)
	)
	(footprint ""
		(layer "B.Cu")
		(at 164.923978 -20.583144)
		(property "Reference" "C311"
			(at 0 0 0)
			(layer "B.SilkS")
			(hide yes)
			(effects
				(font
					(size 1.27 1.27)
				)
				(justify mirror)
			)
		)
		(property "Value" "SCD22U10V1KX-GP"
			(at 2.8321 -1.7399 0)
			(unlocked yes)
			(layer "B.Fab")
			(hide yes)
			(effects
				(font
					(size 1.016 1.016)
					(thickness 0.1524)
				)
				(justify mirror)
			)
		)
		(property "Device Type" "C0201H13"
			(at 2.8321 -3.2639 0)
			(unlocked yes)
			(layer "B.Fab")
			(hide yes)
			(effects
				(font
					(size 1.016 1.016)
					(thickness 0.1524)
				)
				(justify mirror)
			)
		)
		(duplicate_pad_numbers_are_jumpers no)
		(fp_rect
			(start 0.2794 0.6477)
			(end -0.2794 -0.6477)
			(stroke
				(width 0)
				(type default)
			)
			(fill no)
			(layer "B.CrtYd")
		)
		(fp_rect
			(start 0.2794 0.6477)
			(end -0.2794 -0.6477)
			(stroke
				(width 0)
				(type default)
			)
			(fill no)
			(layer "B.Fab")
		)
		(pad "1" smd custom
			(at 0 -0.2794 180)
			(size 0.0762 0.0762)
			(layers "B.Cu" "B.Mask" "B.Paste")
			(net "PCIE_SCC_TO_COMP_C_0_DP")
			(options
				(clearance outline)
				(anchor circle)
			)
			(primitives
				(gr_poly
					(pts
						(arc
							(start 0.1524 0.127)
							(mid 0.137521 0.162921)
							(end 0.1016 0.1778)
						)
						(arc
							(start -0.1016 0.1778)
							(mid -0.137521 0.162921)
							(end -0.1524 0.127)
						)
						(arc
							(start -0.1524 -0.127)
							(mid -0.137521 -0.162921)
							(end -0.1016 -0.1778)
						)
						(arc
							(start 0.1016 -0.1778)
							(mid 0.137521 -0.162921)
							(end 0.1524 -0.127)
						)
					)
					(width 0)
					(fill yes)
				)
			)
		)
		(pad "2" smd custom
			(at 0 0.2794 180)
			(size 0.0762 0.0762)
			(layers "B.Cu" "B.Mask" "B.Paste")
			(net "PCIE_SCC_TO_COMP_0_DP")
			(options
				(clearance outline)
				(anchor circle)
			)
			(primitives
				(gr_poly
					(pts
						(arc
							(start 0.1524 0.127)
							(mid 0.137521 0.162921)
							(end 0.1016 0.1778)
						)
						(arc
							(start -0.1016 0.1778)
							(mid -0.137521 0.162921)
							(end -0.1524 0.127)
						)
						(arc
							(start -0.1524 -0.127)
							(mid -0.137521 -0.162921)
							(end -0.1016 -0.1778)
						)
						(arc
							(start 0.1016 -0.1778)
							(mid 0.137521 -0.162921)
							(end 0.1524 -0.127)
						)
					)
					(width 0)
					(fill yes)
				)
			)
		)
	)
	(footprint ""
		(layer "B.Cu")
		(at 131.8768 -117.4496 -90)
		(property "Reference" "C690"
			(at 0 0 90)
			(layer "B.SilkS")
			(hide yes)
			(effects
				(font
					(size 1.27 1.27)
				)
				(justify mirror)
			)
		)
		(property "Value" "SC10U6D3V5KX-4GP"
			(at 0.0762 -6.1214 270)
			(unlocked yes)
			(layer "B.Fab")
			(hide yes)
			(effects
				(font
					(size 1.016 1.016)
					(thickness 0.1524)
				)
				(justify mirror)
			)
		)
		(property "Device Type" "C805H58"
			(at 0.0762 -8.1534 270)
			(unlocked yes)
			(layer "B.Fab")
			(hide yes)
			(effects
				(font
					(size 1.016 1.016)
					(thickness 0.1524)
				)
				(justify mirror)
			)
		)
		(duplicate_pad_numbers_are_jumpers no)
		(fp_line
			(start -0.635 0)
			(end 0.635 0)
			(stroke
				(width 0.508)
				(type default)
			)
			(layer "B.SilkS")
		)
		(fp_rect
			(start 0.9652 1.778)
			(end -0.9652 -1.778)
			(stroke
				(width 0)
				(type default)
			)
			(fill no)
			(layer "B.CrtYd")
		)
		(fp_poly
			(pts
				(xy 0.9652 -1.778) (xy -0.9652 -1.778) (xy -0.9652 1.778) (xy 0.9652 1.778)
			)
			(stroke
				(width 0)
				(type default)
			)
			(fill no)
			(layer "B.Fab")
		)
		(pad "1" smd rect
			(at 0 -0.9652 90)
			(size 1.397 1.143)
			(layers "B.Cu" "B.Mask" "B.Paste")
			(net "P1V5_C")
		)
		(pad "2" smd rect
			(at 0 0.9652 90)
			(size 1.397 1.143)
			(layers "B.Cu" "B.Mask" "B.Paste")
			(net "GND")
		)
	)
	(footprint ""
		(layer "B.Cu")
		(at 124.714 -67.4624 90)
		(property "Reference" "C300"
			(at 0 0 90)
			(layer "B.SilkS")
			(hide yes)
			(effects
				(font
					(size 1.27 1.27)
				)
				(justify mirror)
			)
		)
		(property "Value" "SCD1U6D3V1KX-GP"
			(at 2.8321 -1.7399 90)
			(unlocked yes)
			(layer "B.Fab")
			(hide yes)
			(effects
				(font
					(size 1.016 1.016)
					(thickness 0.1524)
				)
				(justify mirror)
			)
		)
		(property "Device Type" "C0201H13"
			(at 2.8321 -3.2639 90)
			(unlocked yes)
			(layer "B.Fab")
			(hide yes)
			(effects
				(font
					(size 1.016 1.016)
					(thickness 0.1524)
				)
				(justify mirror)
			)
		)
		(duplicate_pad_numbers_are_jumpers no)
		(fp_rect
			(start 0.2794 0.6477)
			(end -0.2794 -0.6477)
			(stroke
				(width 0)
				(type default)
			)
			(fill no)
			(layer "B.CrtYd")
		)
		(fp_rect
			(start 0.2794 0.6477)
			(end -0.2794 -0.6477)
			(stroke
				(width 0)
				(type default)
			)
			(fill no)
			(layer "B.Fab")
		)
		(pad "1" smd custom
			(at 0 -0.2794 270)
			(size 0.0762 0.0762)
			(layers "B.Cu" "B.Mask" "B.Paste")
			(net "GB_VDDA")
			(options
				(clearance outline)
				(anchor circle)
			)
			(primitives
				(gr_poly
					(pts
						(arc
							(start 0.1524 0.127)
							(mid 0.137521 0.162921)
							(end 0.1016 0.1778)
						)
						(arc
							(start -0.1016 0.1778)
							(mid -0.137521 0.162921)
							(end -0.1524 0.127)
						)
						(arc
							(start -0.1524 -0.127)
							(mid -0.137521 -0.162921)
							(end -0.1016 -0.1778)
						)
						(arc
							(start 0.1016 -0.1778)
							(mid 0.137521 -0.162921)
							(end 0.1524 -0.127)
						)
					)
					(width 0)
					(fill yes)
				)
			)
		)
		(pad "2" smd custom
			(at 0 0.2794 270)
			(size 0.0762 0.0762)
			(layers "B.Cu" "B.Mask" "B.Paste")
			(net "GND")
			(options
				(clearance outline)
				(anchor circle)
			)
			(primitives
				(gr_poly
					(pts
						(arc
							(start 0.1524 0.127)
							(mid 0.137521 0.162921)
							(end 0.1016 0.1778)
						)
						(arc
							(start -0.1016 0.1778)
							(mid -0.137521 0.162921)
							(end -0.1524 0.127)
						)
						(arc
							(start -0.1524 -0.127)
							(mid -0.137521 -0.162921)
							(end -0.1016 -0.1778)
						)
						(arc
							(start 0.1016 -0.1778)
							(mid 0.137521 -0.162921)
							(end 0.1524 -0.127)
						)
					)
					(width 0)
					(fill yes)
				)
			)
		)
	)
	(footprint ""
		(layer "B.Cu")
		(at 104.4575 -83.8835 90)
		(property "Reference" "R35"
			(at 0 0 90)
			(layer "B.SilkS")
			(hide yes)
			(effects
				(font
					(size 1.27 1.27)
				)
				(justify mirror)
			)
		)
		(property "Value" "4K75R2F-1-GP"
			(at -0.064008 -3.993896 90)
			(unlocked yes)
			(layer "B.Fab")
			(hide yes)
			(effects
				(font
					(size 1.016 1.016)
					(thickness 0.1524)
				)
				(justify mirror)
			)
		)
		(property "Device Type" "R402H16"
			(at -0.064008 -5.517896 90)
			(unlocked yes)
			(layer "B.Fab")
			(hide yes)
			(effects
				(font
					(size 1.016 1.016)
					(thickness 0.1524)
				)
				(justify mirror)
			)
		)
		(duplicate_pad_numbers_are_jumpers no)
		(fp_line
			(start 0.508 -0.9398)
			(end 0.508 0.9398)
			(stroke
				(width 0.1524)
				(type default)
			)
			(layer "B.SilkS")
		)
		(fp_line
			(start -0.508 -0.9398)
			(end 0.508 -0.9398)
			(stroke
				(width 0.1524)
				(type default)
			)
			(layer "B.SilkS")
		)
		(fp_rect
			(start 0.508 0.9398)
			(end -0.508 -0.9398)
			(stroke
				(width 0)
				(type default)
			)
			(fill no)
			(layer "B.CrtYd")
		)
		(fp_rect
			(start 0.508 0.9398)
			(end -0.508 -0.9398)
			(stroke
				(width 0)
				(type default)
			)
			(fill no)
			(layer "B.Fab")
		)
		(pad "1" smd custom
			(at 0 -0.4445 270)
			(size 0.1397 0.1397)
			(layers "B.Cu" "B.Mask" "B.Paste")
			(net "GND")
			(options
				(clearance outline)
				(anchor circle)
			)
			(primitives
				(gr_poly
					(pts
						(arc
							(start -0.1778 0.2794)
							(mid -0.249642 0.249642)
							(end -0.2794 0.1778)
						)
						(arc
							(start -0.2794 -0.1778)
							(mid -0.249642 -0.249642)
							(end -0.1778 -0.2794)
						)
						(arc
							(start 0.1778 -0.2794)
							(mid 0.249642 -0.249642)
							(end 0.2794 -0.1778)
						)
						(arc
							(start 0.2794 0.1778)
							(mid 0.249642 0.249642)
							(end 0.1778 0.2794)
						)
					)
					(width 0)
					(fill yes)
				)
			)
		)
		(pad "2" smd custom
			(at 0 0.4445 270)
			(size 0.1397 0.1397)
			(layers "B.Cu" "B.Mask" "B.Paste")
			(net "EXP_ADC_IN0")
			(options
				(clearance outline)
				(anchor circle)
			)
			(primitives
				(gr_poly
					(pts
						(arc
							(start -0.1778 0.2794)
							(mid -0.249642 0.249642)
							(end -0.2794 0.1778)
						)
						(arc
							(start -0.2794 -0.1778)
							(mid -0.249642 -0.249642)
							(end -0.1778 -0.2794)
						)
						(arc
							(start 0.1778 -0.2794)
							(mid 0.249642 -0.249642)
							(end 0.2794 -0.1778)
						)
						(arc
							(start 0.2794 0.1778)
							(mid 0.249642 0.249642)
							(end 0.1778 0.2794)
						)
					)
					(width 0)
					(fill yes)
				)
			)
		)
	)
	(footprint ""
		(layer "B.Cu")
		(at 96.134936 -78.955138 -90)
		(property "Reference" "R207"
			(at 0 0 90)
			(layer "B.SilkS")
			(hide yes)
			(effects
				(font
					(size 1.27 1.27)
				)
				(justify mirror)
			)
		)
		(property "Value" "0R2J-2-GP"
			(at -0.064008 -3.993896 270)
			(unlocked yes)
			(layer "B.Fab")
			(hide yes)
			(effects
				(font
					(size 1.016 1.016)
					(thickness 0.1524)
				)
				(justify mirror)
			)
		)
		(property "Device Type" "R402H16"
			(at -0.064008 -5.517896 270)
			(unlocked yes)
			(layer "B.Fab")
			(hide yes)
			(effects
				(font
					(size 1.016 1.016)
					(thickness 0.1524)
				)
				(justify mirror)
			)
		)
		(duplicate_pad_numbers_are_jumpers no)
		(fp_line
			(start -0.508 -0.9398)
			(end 0.508 -0.9398)
			(stroke
				(width 0.1524)
				(type default)
			)
			(layer "B.SilkS")
		)
		(fp_line
			(start 0.508 -0.9398)
			(end 0.508 0.9398)
			(stroke
				(width 0.1524)
				(type default)
			)
			(layer "B.SilkS")
		)
		(fp_rect
			(start 0.508 0.9398)
			(end -0.508 -0.9398)
			(stroke
				(width 0)
				(type default)
			)
			(fill no)
			(layer "B.CrtYd")
		)
		(fp_rect
			(start 0.508 0.9398)
			(end -0.508 -0.9398)
			(stroke
				(width 0)
				(type default)
			)
			(fill no)
			(layer "B.Fab")
		)
		(pad "1" smd custom
			(at 0 -0.4445 90)
			(size 0.1397 0.1397)
			(layers "B.Cu" "B.Mask" "B.Paste")
			(net "FW_RESET_N")
			(options
				(clearance outline)
				(anchor circle)
			)
			(primitives
				(gr_poly
					(pts
						(arc
							(start -0.1778 0.2794)
							(mid -0.249642 0.249642)
							(end -0.2794 0.1778)
						)
						(arc
							(start -0.2794 -0.1778)
							(mid -0.249642 -0.249642)
							(end -0.1778 -0.2794)
						)
						(arc
							(start 0.1778 -0.2794)
							(mid 0.249642 -0.249642)
							(end 0.2794 -0.1778)
						)
						(arc
							(start 0.2794 0.1778)
							(mid 0.249642 0.249642)
							(end 0.1778 0.2794)
						)
					)
					(width 0)
					(fill yes)
				)
			)
		)
		(pad "2" smd custom
			(at 0 0.4445 90)
			(size 0.1397 0.1397)
			(layers "B.Cu" "B.Mask" "B.Paste")
			(net "EXP_SYS_RST_N")
			(options
				(clearance outline)
				(anchor circle)
			)
			(primitives
				(gr_poly
					(pts
						(arc
							(start -0.1778 0.2794)
							(mid -0.249642 0.249642)
							(end -0.2794 0.1778)
						)
						(arc
							(start -0.2794 -0.1778)
							(mid -0.249642 -0.249642)
							(end -0.1778 -0.2794)
						)
						(arc
							(start 0.1778 -0.2794)
							(mid 0.249642 -0.249642)
							(end 0.2794 -0.1778)
						)
						(arc
							(start 0.2794 0.1778)
							(mid 0.249642 0.249642)
							(end 0.1778 0.2794)
						)
					)
					(width 0)
					(fill yes)
				)
			)
		)
	)
	(footprint ""
		(layer "B.Cu")
		(at 176.1998 -38.1127 90)
		(property "Reference" "C429"
			(at 0 0 90)
			(layer "B.SilkS")
			(hide yes)
			(effects
				(font
					(size 1.27 1.27)
				)
				(justify mirror)
			)
		)
		(property "Value" "SCD1U6D3V1KX-GP"
			(at 2.8321 -1.7399 90)
			(unlocked yes)
			(layer "B.Fab")
			(hide yes)
			(effects
				(font
					(size 1.016 1.016)
					(thickness 0.1524)
				)
				(justify mirror)
			)
		)
		(property "Device Type" "C0201H13"
			(at 2.8321 -3.2639 90)
			(unlocked yes)
			(layer "B.Fab")
			(hide yes)
			(effects
				(font
					(size 1.016 1.016)
					(thickness 0.1524)
				)
				(justify mirror)
			)
		)
		(duplicate_pad_numbers_are_jumpers no)
		(fp_rect
			(start 0.2794 0.6477)
			(end -0.2794 -0.6477)
			(stroke
				(width 0)
				(type default)
			)
			(fill no)
			(layer "B.CrtYd")
		)
		(fp_rect
			(start 0.2794 0.6477)
			(end -0.2794 -0.6477)
			(stroke
				(width 0)
				(type default)
			)
			(fill no)
			(layer "B.Fab")
		)
		(pad "1" smd custom
			(at 0 -0.2794 270)
			(size 0.0762 0.0762)
			(layers "B.Cu" "B.Mask" "B.Paste")
			(net "P0V975")
			(options
				(clearance outline)
				(anchor circle)
			)
			(primitives
				(gr_poly
					(pts
						(arc
							(start 0.1524 0.127)
							(mid 0.137521 0.162921)
							(end 0.1016 0.1778)
						)
						(arc
							(start -0.1016 0.1778)
							(mid -0.137521 0.162921)
							(end -0.1524 0.127)
						)
						(arc
							(start -0.1524 -0.127)
							(mid -0.137521 -0.162921)
							(end -0.1016 -0.1778)
						)
						(arc
							(start 0.1016 -0.1778)
							(mid 0.137521 -0.162921)
							(end 0.1524 -0.127)
						)
					)
					(width 0)
					(fill yes)
				)
			)
		)
		(pad "2" smd custom
			(at 0 0.2794 270)
			(size 0.0762 0.0762)
			(layers "B.Cu" "B.Mask" "B.Paste")
			(net "GND")
			(options
				(clearance outline)
				(anchor circle)
			)
			(primitives
				(gr_poly
					(pts
						(arc
							(start 0.1524 0.127)
							(mid 0.137521 0.162921)
							(end 0.1016 0.1778)
						)
						(arc
							(start -0.1016 0.1778)
							(mid -0.137521 0.162921)
							(end -0.1524 0.127)
						)
						(arc
							(start -0.1524 -0.127)
							(mid -0.137521 -0.162921)
							(end -0.1016 -0.1778)
						)
						(arc
							(start 0.1016 -0.1778)
							(mid 0.137521 -0.162921)
							(end 0.1524 -0.127)
						)
					)
					(width 0)
					(fill yes)
				)
			)
		)
	)
	(footprint ""
		(layer "B.Cu")
		(at 176.202848 -41.31691 90)
		(property "Reference" "C431"
			(at 0 0 90)
			(layer "B.SilkS")
			(hide yes)
			(effects
				(font
					(size 1.27 1.27)
				)
				(justify mirror)
			)
		)
		(property "Value" "SCD1U6D3V1KX-GP"
			(at 2.8321 -1.7399 90)
			(unlocked yes)
			(layer "B.Fab")
			(hide yes)
			(effects
				(font
					(size 1.016 1.016)
					(thickness 0.1524)
				)
				(justify mirror)
			)
		)
		(property "Device Type" "C0201H13"
			(at 2.8321 -3.2639 90)
			(unlocked yes)
			(layer "B.Fab")
			(hide yes)
			(effects
				(font
					(size 1.016 1.016)
					(thickness 0.1524)
				)
				(justify mirror)
			)
		)
		(duplicate_pad_numbers_are_jumpers no)
		(fp_rect
			(start 0.2794 0.6477)
			(end -0.2794 -0.6477)
			(stroke
				(width 0)
				(type default)
			)
			(fill no)
			(layer "B.CrtYd")
		)
		(fp_rect
			(start 0.2794 0.6477)
			(end -0.2794 -0.6477)
			(stroke
				(width 0)
				(type default)
			)
			(fill no)
			(layer "B.Fab")
		)
		(pad "1" smd custom
			(at 0 -0.2794 270)
			(size 0.0762 0.0762)
			(layers "B.Cu" "B.Mask" "B.Paste")
			(net "P0V975")
			(options
				(clearance outline)
				(anchor circle)
			)
			(primitives
				(gr_poly
					(pts
						(arc
							(start 0.1524 0.127)
							(mid 0.137521 0.162921)
							(end 0.1016 0.1778)
						)
						(arc
							(start -0.1016 0.1778)
							(mid -0.137521 0.162921)
							(end -0.1524 0.127)
						)
						(arc
							(start -0.1524 -0.127)
							(mid -0.137521 -0.162921)
							(end -0.1016 -0.1778)
						)
						(arc
							(start 0.1016 -0.1778)
							(mid 0.137521 -0.162921)
							(end 0.1524 -0.127)
						)
					)
					(width 0)
					(fill yes)
				)
			)
		)
		(pad "2" smd custom
			(at 0 0.2794 270)
			(size 0.0762 0.0762)
			(layers "B.Cu" "B.Mask" "B.Paste")
			(net "GND")
			(options
				(clearance outline)
				(anchor circle)
			)
			(primitives
				(gr_poly
					(pts
						(arc
							(start 0.1524 0.127)
							(mid 0.137521 0.162921)
							(end 0.1016 0.1778)
						)
						(arc
							(start -0.1016 0.1778)
							(mid -0.137521 0.162921)
							(end -0.1524 0.127)
						)
						(arc
							(start -0.1524 -0.127)
							(mid -0.137521 -0.162921)
							(end -0.1016 -0.1778)
						)
						(arc
							(start 0.1016 -0.1778)
							(mid 0.137521 -0.162921)
							(end 0.1524 -0.127)
						)
					)
					(width 0)
					(fill yes)
				)
			)
		)
	)
	(footprint ""
		(layer "B.Cu")
		(at 184.465468 -36.87191 90)
		(property "Reference" "C491"
			(at 0 0 90)
			(layer "B.SilkS")
			(hide yes)
			(effects
				(font
					(size 1.27 1.27)
				)
				(justify mirror)
			)
		)
		(property "Value" "SCD1U6D3V1KX-GP"
			(at 2.8321 -1.7399 90)
			(unlocked yes)
			(layer "B.Fab")
			(hide yes)
			(effects
				(font
					(size 1.016 1.016)
					(thickness 0.1524)
				)
				(justify mirror)
			)
		)
		(property "Device Type" "C0201H13"
			(at 2.8321 -3.2639 90)
			(unlocked yes)
			(layer "B.Fab")
			(hide yes)
			(effects
				(font
					(size 1.016 1.016)
					(thickness 0.1524)
				)
				(justify mirror)
			)
		)
		(duplicate_pad_numbers_are_jumpers no)
		(fp_rect
			(start 0.2794 0.6477)
			(end -0.2794 -0.6477)
			(stroke
				(width 0)
				(type default)
			)
			(fill no)
			(layer "B.CrtYd")
		)
		(fp_rect
			(start 0.2794 0.6477)
			(end -0.2794 -0.6477)
			(stroke
				(width 0)
				(type default)
			)
			(fill no)
			(layer "B.Fab")
		)
		(pad "1" smd custom
			(at 0 -0.2794 270)
			(size 0.0762 0.0762)
			(layers "B.Cu" "B.Mask" "B.Paste")
			(net "P1V8_C")
			(options
				(clearance outline)
				(anchor circle)
			)
			(primitives
				(gr_poly
					(pts
						(arc
							(start 0.1524 0.127)
							(mid 0.137521 0.162921)
							(end 0.1016 0.1778)
						)
						(arc
							(start -0.1016 0.1778)
							(mid -0.137521 0.162921)
							(end -0.1524 0.127)
						)
						(arc
							(start -0.1524 -0.127)
							(mid -0.137521 -0.162921)
							(end -0.1016 -0.1778)
						)
						(arc
							(start 0.1016 -0.1778)
							(mid 0.137521 -0.162921)
							(end 0.1524 -0.127)
						)
					)
					(width 0)
					(fill yes)
				)
			)
		)
		(pad "2" smd custom
			(at 0 0.2794 270)
			(size 0.0762 0.0762)
			(layers "B.Cu" "B.Mask" "B.Paste")
			(net "GND")
			(options
				(clearance outline)
				(anchor circle)
			)
			(primitives
				(gr_poly
					(pts
						(arc
							(start 0.1524 0.127)
							(mid 0.137521 0.162921)
							(end 0.1016 0.1778)
						)
						(arc
							(start -0.1016 0.1778)
							(mid -0.137521 0.162921)
							(end -0.1524 0.127)
						)
						(arc
							(start -0.1524 -0.127)
							(mid -0.137521 -0.162921)
							(end -0.1016 -0.1778)
						)
						(arc
							(start 0.1016 -0.1778)
							(mid 0.137521 -0.162921)
							(end 0.1524 -0.127)
						)
					)
					(width 0)
					(fill yes)
				)
			)
		)
	)
	(footprint ""
		(layer "B.Cu")
		(at 174.1932 -120.488964 90)
		(property "Reference" "C706"
			(at 0 0 90)
			(layer "B.SilkS")
			(hide yes)
			(effects
				(font
					(size 1.27 1.27)
				)
				(justify mirror)
			)
		)
		(property "Value" "SC10U6D3V5KX-4GP"
			(at 0.0762 -6.1214 90)
			(unlocked yes)
			(layer "B.Fab")
			(hide yes)
			(effects
				(font
					(size 1.016 1.016)
					(thickness 0.1524)
				)
				(justify mirror)
			)
		)
		(property "Device Type" "C805H58"
			(at 0.0762 -8.1534 90)
			(unlocked yes)
			(layer "B.Fab")
			(hide yes)
			(effects
				(font
					(size 1.016 1.016)
					(thickness 0.1524)
				)
				(justify mirror)
			)
		)
		(duplicate_pad_numbers_are_jumpers no)
		(fp_line
			(start -0.635 0)
			(end 0.635 0)
			(stroke
				(width 0.508)
				(type default)
			)
			(layer "B.SilkS")
		)
		(fp_rect
			(start 0.9652 1.778)
			(end -0.9652 -1.778)
			(stroke
				(width 0)
				(type default)
			)
			(fill no)
			(layer "B.CrtYd")
		)
		(fp_poly
			(pts
				(xy 0.9652 -1.778) (xy -0.9652 -1.778) (xy -0.9652 1.778) (xy 0.9652 1.778)
			)
			(stroke
				(width 0)
				(type default)
			)
			(fill no)
			(layer "B.Fab")
		)
		(pad "1" smd rect
			(at 0 -0.9652 270)
			(size 1.397 1.143)
			(layers "B.Cu" "B.Mask" "B.Paste")
			(net "P3V3")
		)
		(pad "2" smd rect
			(at 0 0.9652 270)
			(size 1.397 1.143)
			(layers "B.Cu" "B.Mask" "B.Paste")
			(net "GND")
		)
	)
	(footprint ""
		(layer "B.Cu")
		(at 173.045882 -20.886166)
		(property "Reference" "C319"
			(at 0 0 0)
			(layer "B.SilkS")
			(hide yes)
			(effects
				(font
					(size 1.27 1.27)
				)
				(justify mirror)
			)
		)
		(property "Value" "SCD22U10V1KX-GP"
			(at 2.8321 -1.7399 0)
			(unlocked yes)
			(layer "B.Fab")
			(hide yes)
			(effects
				(font
					(size 1.016 1.016)
					(thickness 0.1524)
				)
				(justify mirror)
			)
		)
		(property "Device Type" "C0201H13"
			(at 2.8321 -3.2639 0)
			(unlocked yes)
			(layer "B.Fab")
			(hide yes)
			(effects
				(font
					(size 1.016 1.016)
					(thickness 0.1524)
				)
				(justify mirror)
			)
		)
		(duplicate_pad_numbers_are_jumpers no)
		(fp_rect
			(start 0.2794 0.6477)
			(end -0.2794 -0.6477)
			(stroke
				(width 0)
				(type default)
			)
			(fill no)
			(layer "B.CrtYd")
		)
		(fp_rect
			(start 0.2794 0.6477)
			(end -0.2794 -0.6477)
			(stroke
				(width 0)
				(type default)
			)
			(fill no)
			(layer "B.Fab")
		)
		(pad "1" smd custom
			(at 0 -0.2794 180)
			(size 0.0762 0.0762)
			(layers "B.Cu" "B.Mask" "B.Paste")
			(net "PCIE_SCC_TO_COMP_C_4_DP")
			(options
				(clearance outline)
				(anchor circle)
			)
			(primitives
				(gr_poly
					(pts
						(arc
							(start 0.1524 0.127)
							(mid 0.137521 0.162921)
							(end 0.1016 0.1778)
						)
						(arc
							(start -0.1016 0.1778)
							(mid -0.137521 0.162921)
							(end -0.1524 0.127)
						)
						(arc
							(start -0.1524 -0.127)
							(mid -0.137521 -0.162921)
							(end -0.1016 -0.1778)
						)
						(arc
							(start 0.1016 -0.1778)
							(mid 0.137521 -0.162921)
							(end 0.1524 -0.127)
						)
					)
					(width 0)
					(fill yes)
				)
			)
		)
		(pad "2" smd custom
			(at 0 0.2794 180)
			(size 0.0762 0.0762)
			(layers "B.Cu" "B.Mask" "B.Paste")
			(net "PCIE_SCC_TO_COMP_4_DP")
			(options
				(clearance outline)
				(anchor circle)
			)
			(primitives
				(gr_poly
					(pts
						(arc
							(start 0.1524 0.127)
							(mid 0.137521 0.162921)
							(end 0.1016 0.1778)
						)
						(arc
							(start -0.1016 0.1778)
							(mid -0.137521 0.162921)
							(end -0.1524 0.127)
						)
						(arc
							(start -0.1524 -0.127)
							(mid -0.137521 -0.162921)
							(end -0.1016 -0.1778)
						)
						(arc
							(start 0.1016 -0.1778)
							(mid 0.137521 -0.162921)
							(end 0.1524 -0.127)
						)
					)
					(width 0)
					(fill yes)
				)
			)
		)
	)
	(footprint ""
		(layer "B.Cu")
		(at 134.523988 -87.260684)
		(property "Reference" "R70"
			(at 0 0 0)
			(layer "B.SilkS")
			(hide yes)
			(effects
				(font
					(size 1.27 1.27)
				)
				(justify mirror)
			)
		)
		(property "Value" "1KR2F-3-GP"
			(at -0.064008 -3.993896 0)
			(unlocked yes)
			(layer "B.Fab")
			(hide yes)
			(effects
				(font
					(size 1.016 1.016)
					(thickness 0.1524)
				)
				(justify mirror)
			)
		)
		(property "Device Type" "R402H16"
			(at -0.064008 -5.517896 0)
			(unlocked yes)
			(layer "B.Fab")
			(hide yes)
			(effects
				(font
					(size 1.016 1.016)
					(thickness 0.1524)
				)
				(justify mirror)
			)
		)
		(duplicate_pad_numbers_are_jumpers no)
		(fp_line
			(start -0.508 -0.9398)
			(end 0.508 -0.9398)
			(stroke
				(width 0.1524)
				(type default)
			)
			(layer "B.SilkS")
		)
		(fp_line
			(start 0.508 -0.9398)
			(end 0.508 0.9398)
			(stroke
				(width 0.1524)
				(type default)
			)
			(layer "B.SilkS")
		)
		(fp_rect
			(start 0.508 0.9398)
			(end -0.508 -0.9398)
			(stroke
				(width 0)
				(type default)
			)
			(fill no)
			(layer "B.CrtYd")
		)
		(fp_rect
			(start 0.508 0.9398)
			(end -0.508 -0.9398)
			(stroke
				(width 0)
				(type default)
			)
			(fill no)
			(layer "B.Fab")
		)
		(pad "1" smd custom
			(at 0 -0.4445 180)
			(size 0.1397 0.1397)
			(layers "B.Cu" "B.Mask" "B.Paste")
			(net "P1V8_E")
			(options
				(clearance outline)
				(anchor circle)
			)
			(primitives
				(gr_poly
					(pts
						(arc
							(start -0.1778 0.2794)
							(mid -0.249642 0.249642)
							(end -0.2794 0.1778)
						)
						(arc
							(start -0.2794 -0.1778)
							(mid -0.249642 -0.249642)
							(end -0.1778 -0.2794)
						)
						(arc
							(start 0.1778 -0.2794)
							(mid 0.249642 -0.249642)
							(end 0.2794 -0.1778)
						)
						(arc
							(start 0.2794 0.1778)
							(mid 0.249642 0.249642)
							(end 0.1778 0.2794)
						)
					)
					(width 0)
					(fill yes)
				)
			)
		)
		(pad "2" smd custom
			(at 0 0.4445 180)
			(size 0.1397 0.1397)
			(layers "B.Cu" "B.Mask" "B.Paste")
			(net "EXP_I2C_SCL11")
			(options
				(clearance outline)
				(anchor circle)
			)
			(primitives
				(gr_poly
					(pts
						(arc
							(start -0.1778 0.2794)
							(mid -0.249642 0.249642)
							(end -0.2794 0.1778)
						)
						(arc
							(start -0.2794 -0.1778)
							(mid -0.249642 -0.249642)
							(end -0.1778 -0.2794)
						)
						(arc
							(start 0.1778 -0.2794)
							(mid 0.249642 -0.249642)
							(end 0.2794 -0.1778)
						)
						(arc
							(start 0.2794 0.1778)
							(mid 0.249642 0.249642)
							(end 0.1778 0.2794)
						)
					)
					(width 0)
					(fill yes)
				)
			)
		)
	)
	(footprint ""
		(layer "B.Cu")
		(at 179.451 -31.75 -90)
		(property "Reference" "C470"
			(at 0 0 90)
			(layer "B.SilkS")
			(hide yes)
			(effects
				(font
					(size 1.27 1.27)
				)
				(justify mirror)
			)
		)
		(property "Value" "SCD1U6D3V1KX-GP"
			(at 2.8321 -1.7399 270)
			(unlocked yes)
			(layer "B.Fab")
			(hide yes)
			(effects
				(font
					(size 1.016 1.016)
					(thickness 0.1524)
				)
				(justify mirror)
			)
		)
		(property "Device Type" "C0201H13"
			(at 2.8321 -3.2639 270)
			(unlocked yes)
			(layer "B.Fab")
			(hide yes)
			(effects
				(font
					(size 1.016 1.016)
					(thickness 0.1524)
				)
				(justify mirror)
			)
		)
		(duplicate_pad_numbers_are_jumpers no)
		(fp_rect
			(start 0.2794 0.6477)
			(end -0.2794 -0.6477)
			(stroke
				(width 0)
				(type default)
			)
			(fill no)
			(layer "B.CrtYd")
		)
		(fp_rect
			(start 0.2794 0.6477)
			(end -0.2794 -0.6477)
			(stroke
				(width 0)
				(type default)
			)
			(fill no)
			(layer "B.Fab")
		)
		(pad "1" smd custom
			(at 0 -0.2794 90)
			(size 0.0762 0.0762)
			(layers "B.Cu" "B.Mask" "B.Paste")
			(net "P1V8_C")
			(options
				(clearance outline)
				(anchor circle)
			)
			(primitives
				(gr_poly
					(pts
						(arc
							(start 0.1524 0.127)
							(mid 0.137521 0.162921)
							(end 0.1016 0.1778)
						)
						(arc
							(start -0.1016 0.1778)
							(mid -0.137521 0.162921)
							(end -0.1524 0.127)
						)
						(arc
							(start -0.1524 -0.127)
							(mid -0.137521 -0.162921)
							(end -0.1016 -0.1778)
						)
						(arc
							(start 0.1016 -0.1778)
							(mid 0.137521 -0.162921)
							(end 0.1524 -0.127)
						)
					)
					(width 0)
					(fill yes)
				)
			)
		)
		(pad "2" smd custom
			(at 0 0.2794 90)
			(size 0.0762 0.0762)
			(layers "B.Cu" "B.Mask" "B.Paste")
			(net "GND")
			(options
				(clearance outline)
				(anchor circle)
			)
			(primitives
				(gr_poly
					(pts
						(arc
							(start 0.1524 0.127)
							(mid 0.137521 0.162921)
							(end 0.1016 0.1778)
						)
						(arc
							(start -0.1016 0.1778)
							(mid -0.137521 0.162921)
							(end -0.1524 0.127)
						)
						(arc
							(start -0.1524 -0.127)
							(mid -0.137521 -0.162921)
							(end -0.1016 -0.1778)
						)
						(arc
							(start 0.1016 -0.1778)
							(mid 0.137521 -0.162921)
							(end 0.1524 -0.127)
						)
					)
					(width 0)
					(fill yes)
				)
			)
		)
	)
	(footprint ""
		(layer "B.Cu")
		(at 110.5408 -84.4042 180)
		(property "Reference" "R137"
			(at 0 0 0)
			(layer "B.SilkS")
			(hide yes)
			(effects
				(font
					(size 1.27 1.27)
				)
				(justify mirror)
			)
		)
		(property "Value" "4K75R2F-1-GP"
			(at -0.064008 -3.993896 180)
			(unlocked yes)
			(layer "B.Fab")
			(hide yes)
			(effects
				(font
					(size 1.016 1.016)
					(thickness 0.1524)
				)
				(justify mirror)
			)
		)
		(property "Device Type" "R402H16"
			(at -0.064008 -5.517896 180)
			(unlocked yes)
			(layer "B.Fab")
			(hide yes)
			(effects
				(font
					(size 1.016 1.016)
					(thickness 0.1524)
				)
				(justify mirror)
			)
		)
		(duplicate_pad_numbers_are_jumpers no)
		(fp_line
			(start 0.508 -0.9398)
			(end 0.508 0.9398)
			(stroke
				(width 0.1524)
				(type default)
			)
			(layer "B.SilkS")
		)
		(fp_line
			(start -0.508 -0.9398)
			(end 0.508 -0.9398)
			(stroke
				(width 0.1524)
				(type default)
			)
			(layer "B.SilkS")
		)
		(fp_rect
			(start 0.508 0.9398)
			(end -0.508 -0.9398)
			(stroke
				(width 0)
				(type default)
			)
			(fill no)
			(layer "B.CrtYd")
		)
		(fp_rect
			(start 0.508 0.9398)
			(end -0.508 -0.9398)
			(stroke
				(width 0)
				(type default)
			)
			(fill no)
			(layer "B.Fab")
		)
		(pad "1" smd custom
			(at 0 -0.4445)
			(size 0.1397 0.1397)
			(layers "B.Cu" "B.Mask" "B.Paste")
			(net "EXP_XM_WE_N")
			(options
				(clearance outline)
				(anchor circle)
			)
			(primitives
				(gr_poly
					(pts
						(arc
							(start -0.1778 0.2794)
							(mid -0.249642 0.249642)
							(end -0.2794 0.1778)
						)
						(arc
							(start -0.2794 -0.1778)
							(mid -0.249642 -0.249642)
							(end -0.1778 -0.2794)
						)
						(arc
							(start 0.1778 -0.2794)
							(mid 0.249642 -0.249642)
							(end 0.2794 -0.1778)
						)
						(arc
							(start 0.2794 0.1778)
							(mid 0.249642 0.249642)
							(end 0.1778 0.2794)
						)
					)
					(width 0)
					(fill yes)
				)
			)
		)
		(pad "2" smd custom
			(at 0 0.4445)
			(size 0.1397 0.1397)
			(layers "B.Cu" "B.Mask" "B.Paste")
			(net "P1V8_E")
			(options
				(clearance outline)
				(anchor circle)
			)
			(primitives
				(gr_poly
					(pts
						(arc
							(start -0.1778 0.2794)
							(mid -0.249642 0.249642)
							(end -0.2794 0.1778)
						)
						(arc
							(start -0.2794 -0.1778)
							(mid -0.249642 -0.249642)
							(end -0.1778 -0.2794)
						)
						(arc
							(start 0.1778 -0.2794)
							(mid 0.249642 -0.249642)
							(end 0.2794 -0.1778)
						)
						(arc
							(start 0.2794 0.1778)
							(mid 0.249642 0.249642)
							(end 0.1778 0.2794)
						)
					)
					(width 0)
					(fill yes)
				)
			)
		)
	)
	(footprint ""
		(layer "B.Cu")
		(at 124.515118 -59.488832 90)
		(property "Reference" "C286"
			(at 0 0 90)
			(layer "B.SilkS")
			(hide yes)
			(effects
				(font
					(size 1.27 1.27)
				)
				(justify mirror)
			)
		)
		(property "Value" "SCD1U6D3V1KX-GP"
			(at 2.8321 -1.7399 90)
			(unlocked yes)
			(layer "B.Fab")
			(hide yes)
			(effects
				(font
					(size 1.016 1.016)
					(thickness 0.1524)
				)
				(justify mirror)
			)
		)
		(property "Device Type" "C0201H13"
			(at 2.8321 -3.2639 90)
			(unlocked yes)
			(layer "B.Fab")
			(hide yes)
			(effects
				(font
					(size 1.016 1.016)
					(thickness 0.1524)
				)
				(justify mirror)
			)
		)
		(duplicate_pad_numbers_are_jumpers no)
		(fp_rect
			(start 0.2794 0.6477)
			(end -0.2794 -0.6477)
			(stroke
				(width 0)
				(type default)
			)
			(fill no)
			(layer "B.CrtYd")
		)
		(fp_rect
			(start 0.2794 0.6477)
			(end -0.2794 -0.6477)
			(stroke
				(width 0)
				(type default)
			)
			(fill no)
			(layer "B.Fab")
		)
		(pad "1" smd custom
			(at 0 -0.2794 270)
			(size 0.0762 0.0762)
			(layers "B.Cu" "B.Mask" "B.Paste")
			(net "GB_VDDA")
			(options
				(clearance outline)
				(anchor circle)
			)
			(primitives
				(gr_poly
					(pts
						(arc
							(start 0.1524 0.127)
							(mid 0.137521 0.162921)
							(end 0.1016 0.1778)
						)
						(arc
							(start -0.1016 0.1778)
							(mid -0.137521 0.162921)
							(end -0.1524 0.127)
						)
						(arc
							(start -0.1524 -0.127)
							(mid -0.137521 -0.162921)
							(end -0.1016 -0.1778)
						)
						(arc
							(start 0.1016 -0.1778)
							(mid 0.137521 -0.162921)
							(end 0.1524 -0.127)
						)
					)
					(width 0)
					(fill yes)
				)
			)
		)
		(pad "2" smd custom
			(at 0 0.2794 270)
			(size 0.0762 0.0762)
			(layers "B.Cu" "B.Mask" "B.Paste")
			(net "GND")
			(options
				(clearance outline)
				(anchor circle)
			)
			(primitives
				(gr_poly
					(pts
						(arc
							(start 0.1524 0.127)
							(mid 0.137521 0.162921)
							(end 0.1016 0.1778)
						)
						(arc
							(start -0.1016 0.1778)
							(mid -0.137521 0.162921)
							(end -0.1524 0.127)
						)
						(arc
							(start -0.1524 -0.127)
							(mid -0.137521 -0.162921)
							(end -0.1016 -0.1778)
						)
						(arc
							(start 0.1016 -0.1778)
							(mid 0.137521 -0.162921)
							(end 0.1524 -0.127)
						)
					)
					(width 0)
					(fill yes)
				)
			)
		)
	)
	(footprint ""
		(layer "B.Cu")
		(at 135.66648 -61.304678 180)
		(property "Reference" "C23"
			(at 0 0 0)
			(layer "B.SilkS")
			(hide yes)
			(effects
				(font
					(size 1.27 1.27)
				)
				(justify mirror)
			)
		)
		(property "Value" "SCD01U16V1KX-GP"
			(at 2.8321 -1.7399 180)
			(unlocked yes)
			(layer "B.Fab")
			(hide yes)
			(effects
				(font
					(size 1.016 1.016)
					(thickness 0.1524)
				)
				(justify mirror)
			)
		)
		(property "Device Type" "C0201H13"
			(at 2.8321 -3.2639 180)
			(unlocked yes)
			(layer "B.Fab")
			(hide yes)
			(effects
				(font
					(size 1.016 1.016)
					(thickness 0.1524)
				)
				(justify mirror)
			)
		)
		(duplicate_pad_numbers_are_jumpers no)
		(fp_rect
			(start 0.2794 0.6477)
			(end -0.2794 -0.6477)
			(stroke
				(width 0)
				(type default)
			)
			(fill no)
			(layer "B.CrtYd")
		)
		(fp_rect
			(start 0.2794 0.6477)
			(end -0.2794 -0.6477)
			(stroke
				(width 0)
				(type default)
			)
			(fill no)
			(layer "B.Fab")
		)
		(pad "1" smd custom
			(at 0 -0.2794)
			(size 0.0762 0.0762)
			(layers "B.Cu" "B.Mask" "B.Paste")
			(net "PHY_DPB_TO_SCC_0_DP")
			(options
				(clearance outline)
				(anchor circle)
			)
			(primitives
				(gr_poly
					(pts
						(arc
							(start 0.1524 0.127)
							(mid 0.137521 0.162921)
							(end 0.1016 0.1778)
						)
						(arc
							(start -0.1016 0.1778)
							(mid -0.137521 0.162921)
							(end -0.1524 0.127)
						)
						(arc
							(start -0.1524 -0.127)
							(mid -0.137521 -0.162921)
							(end -0.1016 -0.1778)
						)
						(arc
							(start 0.1016 -0.1778)
							(mid 0.137521 -0.162921)
							(end 0.1524 -0.127)
						)
					)
					(width 0)
					(fill yes)
				)
			)
		)
		(pad "2" smd custom
			(at 0 0.2794)
			(size 0.0762 0.0762)
			(layers "B.Cu" "B.Mask" "B.Paste")
			(net "PHY_DPB_TO_SCC_C_0_DP")
			(options
				(clearance outline)
				(anchor circle)
			)
			(primitives
				(gr_poly
					(pts
						(arc
							(start 0.1524 0.127)
							(mid 0.137521 0.162921)
							(end 0.1016 0.1778)
						)
						(arc
							(start -0.1016 0.1778)
							(mid -0.137521 0.162921)
							(end -0.1524 0.127)
						)
						(arc
							(start -0.1524 -0.127)
							(mid -0.137521 -0.162921)
							(end -0.1016 -0.1778)
						)
						(arc
							(start 0.1016 -0.1778)
							(mid 0.137521 -0.162921)
							(end 0.1524 -0.127)
						)
					)
					(width 0)
					(fill yes)
				)
			)
		)
	)
	(footprint ""
		(layer "B.Cu")
		(at 120.523 -68.7324 -90)
		(property "Reference" "C215"
			(at 0 0 90)
			(layer "B.SilkS")
			(hide yes)
			(effects
				(font
					(size 1.27 1.27)
				)
				(justify mirror)
			)
		)
		(property "Value" "SCD1U16V2KX-3GP"
			(at -1.1811 -2.7051 270)
			(unlocked yes)
			(layer "B.Fab")
			(hide yes)
			(effects
				(font
					(size 1.016 1.016)
					(thickness 0.1524)
				)
				(justify mirror)
			)
		)
		(property "Device Type" "C402H22"
			(at -1.1811 -4.2291 270)
			(unlocked yes)
			(layer "B.Fab")
			(hide yes)
			(effects
				(font
					(size 1.016 1.016)
					(thickness 0.1524)
				)
				(justify mirror)
			)
		)
		(duplicate_pad_numbers_are_jumpers no)
		(fp_rect
			(start 0.4318 0.9525)
			(end -0.4318 -0.9525)
			(stroke
				(width 0)
				(type default)
			)
			(fill no)
			(layer "B.CrtYd")
		)
		(fp_rect
			(start 0.4318 0.9525)
			(end -0.4318 -0.9525)
			(stroke
				(width 0)
				(type default)
			)
			(fill no)
			(layer "B.Fab")
		)
		(pad "1" smd custom
			(at 0 -0.4445 90)
			(size 0.1524 0.1524)
			(layers "B.Cu" "B.Mask" "B.Paste")
			(net "GB_VDDH")
			(options
				(clearance outline)
				(anchor circle)
			)
			(primitives
				(gr_poly
					(pts
						(arc
							(start 0.3048 0.2032)
							(mid 0.275042 0.275042)
							(end 0.2032 0.3048)
						)
						(arc
							(start -0.2032 0.3048)
							(mid -0.275042 0.275042)
							(end -0.3048 0.2032)
						)
						(arc
							(start -0.3048 -0.2032)
							(mid -0.275042 -0.275042)
							(end -0.2032 -0.3048)
						)
						(arc
							(start 0.2032 -0.3048)
							(mid 0.275042 -0.275042)
							(end 0.3048 -0.2032)
						)
					)
					(width 0)
					(fill yes)
				)
			)
		)
		(pad "2" smd custom
			(at 0 0.4445 90)
			(size 0.1524 0.1524)
			(layers "B.Cu" "B.Mask" "B.Paste")
			(net "GND")
			(options
				(clearance outline)
				(anchor circle)
			)
			(primitives
				(gr_poly
					(pts
						(arc
							(start 0.3048 0.2032)
							(mid 0.275042 0.275042)
							(end 0.2032 0.3048)
						)
						(arc
							(start -0.2032 0.3048)
							(mid -0.275042 0.275042)
							(end -0.3048 0.2032)
						)
						(arc
							(start -0.3048 -0.2032)
							(mid -0.275042 -0.275042)
							(end -0.2032 -0.3048)
						)
						(arc
							(start 0.2032 -0.3048)
							(mid 0.275042 -0.275042)
							(end 0.3048 -0.2032)
						)
					)
					(width 0)
					(fill yes)
				)
			)
		)
	)
	(footprint ""
		(layer "B.Cu")
		(at 165.283388 -46.593506)
		(property "Reference" "TP85"
			(at 0 0 0)
			(layer "B.SilkS")
			(hide yes)
			(effects
				(font
					(size 1.27 1.27)
				)
				(justify mirror)
			)
		)
		(property "Value" "TPAD28-2-GP"
			(at 0.0127 -1.6637 0)
			(unlocked yes)
			(layer "B.Fab")
			(hide yes)
			(effects
				(font
					(size 1.016 1.016)
					(thickness 0.1524)
				)
				(justify mirror)
			)
		)
		(property "Device Type" "TPAD28"
			(at 0.0127 -3.1877 0)
			(unlocked yes)
			(layer "B.Fab")
			(hide yes)
			(effects
				(font
					(size 1.016 1.016)
					(thickness 0.1524)
				)
				(justify mirror)
			)
		)
		(duplicate_pad_numbers_are_jumpers no)
		(fp_poly
			(pts
				(arc
					(start 0.3556 0)
					(mid -0.3556 0)
					(end 0.3556 0)
				)
			)
			(stroke
				(width 0)
				(type default)
			)
			(fill no)
			(layer "B.CrtYd")
		)
		(fp_poly
			(pts
				(arc
					(start 0.6096 0)
					(mid -0.6096 0)
					(end 0.6096 0)
				)
			)
			(stroke
				(width 0)
				(type default)
			)
			(fill no)
			(layer "B.Fab")
		)
		(pad "1" smd circle
			(at 0 0 180)
			(size 0.7112 0.7112)
			(layers "B.Cu" "B.Mask" "B.Paste")
			(net "SIO_LOAD_0")
		)
	)
	(footprint ""
		(layer "B.Cu")
		(at 183.144668 -48.05299 -90)
		(property "Reference" "C481"
			(at 0 0 90)
			(layer "B.SilkS")
			(hide yes)
			(effects
				(font
					(size 1.27 1.27)
				)
				(justify mirror)
			)
		)
		(property "Value" "SCD1U6D3V1KX-GP"
			(at 2.8321 -1.7399 270)
			(unlocked yes)
			(layer "B.Fab")
			(hide yes)
			(effects
				(font
					(size 1.016 1.016)
					(thickness 0.1524)
				)
				(justify mirror)
			)
		)
		(property "Device Type" "C0201H13"
			(at 2.8321 -3.2639 270)
			(unlocked yes)
			(layer "B.Fab")
			(hide yes)
			(effects
				(font
					(size 1.016 1.016)
					(thickness 0.1524)
				)
				(justify mirror)
			)
		)
		(duplicate_pad_numbers_are_jumpers no)
		(fp_rect
			(start 0.2794 0.6477)
			(end -0.2794 -0.6477)
			(stroke
				(width 0)
				(type default)
			)
			(fill no)
			(layer "B.CrtYd")
		)
		(fp_rect
			(start 0.2794 0.6477)
			(end -0.2794 -0.6477)
			(stroke
				(width 0)
				(type default)
			)
			(fill no)
			(layer "B.Fab")
		)
		(pad "1" smd custom
			(at 0 -0.2794 90)
			(size 0.0762 0.0762)
			(layers "B.Cu" "B.Mask" "B.Paste")
			(net "P1V8_C")
			(options
				(clearance outline)
				(anchor circle)
			)
			(primitives
				(gr_poly
					(pts
						(arc
							(start 0.1524 0.127)
							(mid 0.137521 0.162921)
							(end 0.1016 0.1778)
						)
						(arc
							(start -0.1016 0.1778)
							(mid -0.137521 0.162921)
							(end -0.1524 0.127)
						)
						(arc
							(start -0.1524 -0.127)
							(mid -0.137521 -0.162921)
							(end -0.1016 -0.1778)
						)
						(arc
							(start 0.1016 -0.1778)
							(mid 0.137521 -0.162921)
							(end 0.1524 -0.127)
						)
					)
					(width 0)
					(fill yes)
				)
			)
		)
		(pad "2" smd custom
			(at 0 0.2794 90)
			(size 0.0762 0.0762)
			(layers "B.Cu" "B.Mask" "B.Paste")
			(net "GND")
			(options
				(clearance outline)
				(anchor circle)
			)
			(primitives
				(gr_poly
					(pts
						(arc
							(start 0.1524 0.127)
							(mid 0.137521 0.162921)
							(end 0.1016 0.1778)
						)
						(arc
							(start -0.1016 0.1778)
							(mid -0.137521 0.162921)
							(end -0.1524 0.127)
						)
						(arc
							(start -0.1524 -0.127)
							(mid -0.137521 -0.162921)
							(end -0.1016 -0.1778)
						)
						(arc
							(start 0.1016 -0.1778)
							(mid 0.137521 -0.162921)
							(end 0.1524 -0.127)
						)
					)
					(width 0)
					(fill yes)
				)
			)
		)
	)
	(footprint ""
		(layer "B.Cu")
		(at 168.98239 -21.006816)
		(property "Reference" "C315"
			(at 0 0 0)
			(layer "B.SilkS")
			(hide yes)
			(effects
				(font
					(size 1.27 1.27)
				)
				(justify mirror)
			)
		)
		(property "Value" "SCD22U10V1KX-GP"
			(at 2.8321 -1.7399 0)
			(unlocked yes)
			(layer "B.Fab")
			(hide yes)
			(effects
				(font
					(size 1.016 1.016)
					(thickness 0.1524)
				)
				(justify mirror)
			)
		)
		(property "Device Type" "C0201H13"
			(at 2.8321 -3.2639 0)
			(unlocked yes)
			(layer "B.Fab")
			(hide yes)
			(effects
				(font
					(size 1.016 1.016)
					(thickness 0.1524)
				)
				(justify mirror)
			)
		)
		(duplicate_pad_numbers_are_jumpers no)
		(fp_rect
			(start 0.2794 0.6477)
			(end -0.2794 -0.6477)
			(stroke
				(width 0)
				(type default)
			)
			(fill no)
			(layer "B.CrtYd")
		)
		(fp_rect
			(start 0.2794 0.6477)
			(end -0.2794 -0.6477)
			(stroke
				(width 0)
				(type default)
			)
			(fill no)
			(layer "B.Fab")
		)
		(pad "1" smd custom
			(at 0 -0.2794 180)
			(size 0.0762 0.0762)
			(layers "B.Cu" "B.Mask" "B.Paste")
			(net "PCIE_SCC_TO_COMP_C_2_DP")
			(options
				(clearance outline)
				(anchor circle)
			)
			(primitives
				(gr_poly
					(pts
						(arc
							(start 0.1524 0.127)
							(mid 0.137521 0.162921)
							(end 0.1016 0.1778)
						)
						(arc
							(start -0.1016 0.1778)
							(mid -0.137521 0.162921)
							(end -0.1524 0.127)
						)
						(arc
							(start -0.1524 -0.127)
							(mid -0.137521 -0.162921)
							(end -0.1016 -0.1778)
						)
						(arc
							(start 0.1016 -0.1778)
							(mid 0.137521 -0.162921)
							(end 0.1524 -0.127)
						)
					)
					(width 0)
					(fill yes)
				)
			)
		)
		(pad "2" smd custom
			(at 0 0.2794 180)
			(size 0.0762 0.0762)
			(layers "B.Cu" "B.Mask" "B.Paste")
			(net "PCIE_SCC_TO_COMP_2_DP")
			(options
				(clearance outline)
				(anchor circle)
			)
			(primitives
				(gr_poly
					(pts
						(arc
							(start 0.1524 0.127)
							(mid 0.137521 0.162921)
							(end 0.1016 0.1778)
						)
						(arc
							(start -0.1016 0.1778)
							(mid -0.137521 0.162921)
							(end -0.1524 0.127)
						)
						(arc
							(start -0.1524 -0.127)
							(mid -0.137521 -0.162921)
							(end -0.1016 -0.1778)
						)
						(arc
							(start 0.1016 -0.1778)
							(mid 0.137521 -0.162921)
							(end 0.1524 -0.127)
						)
					)
					(width 0)
					(fill yes)
				)
			)
		)
	)
	(footprint ""
		(layer "B.Cu")
		(at 106.0196 -86.9442)
		(property "Reference" "R86"
			(at 0 0 0)
			(layer "B.SilkS")
			(hide yes)
			(effects
				(font
					(size 1.27 1.27)
				)
				(justify mirror)
			)
		)
		(property "Value" "4K75R2F-1-GP"
			(at -0.064008 -3.993896 0)
			(unlocked yes)
			(layer "B.Fab")
			(hide yes)
			(effects
				(font
					(size 1.016 1.016)
					(thickness 0.1524)
				)
				(justify mirror)
			)
		)
		(property "Device Type" "R402H16"
			(at -0.064008 -5.517896 0)
			(unlocked yes)
			(layer "B.Fab")
			(hide yes)
			(effects
				(font
					(size 1.016 1.016)
					(thickness 0.1524)
				)
				(justify mirror)
			)
		)
		(duplicate_pad_numbers_are_jumpers no)
		(fp_line
			(start -0.508 -0.9398)
			(end 0.508 -0.9398)
			(stroke
				(width 0.1524)
				(type default)
			)
			(layer "B.SilkS")
		)
		(fp_line
			(start 0.508 -0.9398)
			(end 0.508 0.9398)
			(stroke
				(width 0.1524)
				(type default)
			)
			(layer "B.SilkS")
		)
		(fp_rect
			(start 0.508 0.9398)
			(end -0.508 -0.9398)
			(stroke
				(width 0)
				(type default)
			)
			(fill no)
			(layer "B.CrtYd")
		)
		(fp_rect
			(start 0.508 0.9398)
			(end -0.508 -0.9398)
			(stroke
				(width 0)
				(type default)
			)
			(fill no)
			(layer "B.Fab")
		)
		(pad "1" smd custom
			(at 0 -0.4445 180)
			(size 0.1397 0.1397)
			(layers "B.Cu" "B.Mask" "B.Paste")
			(net "P1V8_E")
			(options
				(clearance outline)
				(anchor circle)
			)
			(primitives
				(gr_poly
					(pts
						(arc
							(start -0.1778 0.2794)
							(mid -0.249642 0.249642)
							(end -0.2794 0.1778)
						)
						(arc
							(start -0.2794 -0.1778)
							(mid -0.249642 -0.249642)
							(end -0.1778 -0.2794)
						)
						(arc
							(start 0.1778 -0.2794)
							(mid 0.249642 -0.249642)
							(end 0.2794 -0.1778)
						)
						(arc
							(start 0.2794 0.1778)
							(mid 0.249642 0.249642)
							(end 0.1778 0.2794)
						)
					)
					(width 0)
					(fill yes)
				)
			)
		)
		(pad "2" smd custom
			(at 0 0.4445 180)
			(size 0.1397 0.1397)
			(layers "B.Cu" "B.Mask" "B.Paste")
			(net "SXP_ACTIVE_1")
			(options
				(clearance outline)
				(anchor circle)
			)
			(primitives
				(gr_poly
					(pts
						(arc
							(start -0.1778 0.2794)
							(mid -0.249642 0.249642)
							(end -0.2794 0.1778)
						)
						(arc
							(start -0.2794 -0.1778)
							(mid -0.249642 -0.249642)
							(end -0.1778 -0.2794)
						)
						(arc
							(start 0.1778 -0.2794)
							(mid 0.249642 -0.249642)
							(end 0.2794 -0.1778)
						)
						(arc
							(start 0.2794 0.1778)
							(mid 0.249642 0.249642)
							(end 0.1778 0.2794)
						)
					)
					(width 0)
					(fill yes)
				)
			)
		)
	)
	(footprint ""
		(layer "B.Cu")
		(at 113.2586 -66.3575)
		(property "Reference" "C180"
			(at 0 0 0)
			(layer "B.SilkS")
			(hide yes)
			(effects
				(font
					(size 1.27 1.27)
				)
				(justify mirror)
			)
		)
		(property "Value" "SCD1U6D3V1KX-GP"
			(at 2.8321 -1.7399 0)
			(unlocked yes)
			(layer "B.Fab")
			(hide yes)
			(effects
				(font
					(size 1.016 1.016)
					(thickness 0.1524)
				)
				(justify mirror)
			)
		)
		(property "Device Type" "C0201H13"
			(at 2.8321 -3.2639 0)
			(unlocked yes)
			(layer "B.Fab")
			(hide yes)
			(effects
				(font
					(size 1.016 1.016)
					(thickness 0.1524)
				)
				(justify mirror)
			)
		)
		(duplicate_pad_numbers_are_jumpers no)
		(fp_rect
			(start 0.2794 0.6477)
			(end -0.2794 -0.6477)
			(stroke
				(width 0)
				(type default)
			)
			(fill no)
			(layer "B.CrtYd")
		)
		(fp_rect
			(start 0.2794 0.6477)
			(end -0.2794 -0.6477)
			(stroke
				(width 0)
				(type default)
			)
			(fill no)
			(layer "B.Fab")
		)
		(pad "1" smd custom
			(at 0 -0.2794 180)
			(size 0.0762 0.0762)
			(layers "B.Cu" "B.Mask" "B.Paste")
			(net "P0V9")
			(options
				(clearance outline)
				(anchor circle)
			)
			(primitives
				(gr_poly
					(pts
						(arc
							(start 0.1524 0.127)
							(mid 0.137521 0.162921)
							(end 0.1016 0.1778)
						)
						(arc
							(start -0.1016 0.1778)
							(mid -0.137521 0.162921)
							(end -0.1524 0.127)
						)
						(arc
							(start -0.1524 -0.127)
							(mid -0.137521 -0.162921)
							(end -0.1016 -0.1778)
						)
						(arc
							(start 0.1016 -0.1778)
							(mid 0.137521 -0.162921)
							(end 0.1524 -0.127)
						)
					)
					(width 0)
					(fill yes)
				)
			)
		)
		(pad "2" smd custom
			(at 0 0.2794 180)
			(size 0.0762 0.0762)
			(layers "B.Cu" "B.Mask" "B.Paste")
			(net "GND")
			(options
				(clearance outline)
				(anchor circle)
			)
			(primitives
				(gr_poly
					(pts
						(arc
							(start 0.1524 0.127)
							(mid 0.137521 0.162921)
							(end 0.1016 0.1778)
						)
						(arc
							(start -0.1016 0.1778)
							(mid -0.137521 0.162921)
							(end -0.1524 0.127)
						)
						(arc
							(start -0.1524 -0.127)
							(mid -0.137521 -0.162921)
							(end -0.1016 -0.1778)
						)
						(arc
							(start 0.1016 -0.1778)
							(mid 0.137521 -0.162921)
							(end 0.1524 -0.127)
						)
					)
					(width 0)
					(fill yes)
				)
			)
		)
	)
	(footprint ""
		(layer "B.Cu")
		(at 107.499912 -77.499972)
		(property "Reference" "TP26"
			(at 0 0 0)
			(layer "B.SilkS")
			(hide yes)
			(effects
				(font
					(size 1.27 1.27)
				)
				(justify mirror)
			)
		)
		(property "Value" "TPAD28-2-GP"
			(at 0.0127 -1.6637 0)
			(unlocked yes)
			(layer "B.Fab")
			(hide yes)
			(effects
				(font
					(size 1.016 1.016)
					(thickness 0.1524)
				)
				(justify mirror)
			)
		)
		(property "Device Type" "TPAD28"
			(at 0.0127 -3.1877 0)
			(unlocked yes)
			(layer "B.Fab")
			(hide yes)
			(effects
				(font
					(size 1.016 1.016)
					(thickness 0.1524)
				)
				(justify mirror)
			)
		)
		(duplicate_pad_numbers_are_jumpers no)
		(fp_poly
			(pts
				(arc
					(start 0.3556 0)
					(mid -0.3556 0)
					(end 0.3556 0)
				)
			)
			(stroke
				(width 0)
				(type default)
			)
			(fill no)
			(layer "B.CrtYd")
		)
		(fp_poly
			(pts
				(arc
					(start 0.6096 0)
					(mid -0.6096 0)
					(end 0.6096 0)
				)
			)
			(stroke
				(width 0)
				(type default)
			)
			(fill no)
			(layer "B.Fab")
		)
		(pad "1" smd circle
			(at 0 0 180)
			(size 0.7112 0.7112)
			(layers "B.Cu" "B.Mask" "B.Paste")
			(net "SXP_ACTIVE_0")
		)
	)
	(footprint ""
		(layer "B.Cu")
		(at 164.3126 -92.6846 90)
		(property "Reference" "C645"
			(at 0 0 90)
			(layer "B.SilkS")
			(hide yes)
			(effects
				(font
					(size 1.27 1.27)
				)
				(justify mirror)
			)
		)
		(property "Value" "SC10U16V5KX-7-GP-U"
			(at 0.0762 -6.1214 90)
			(unlocked yes)
			(layer "B.Fab")
			(hide yes)
			(effects
				(font
					(size 1.016 1.016)
					(thickness 0.1524)
				)
				(justify mirror)
			)
		)
		(property "Device Type" "C805H58"
			(at 0.0762 -8.1534 90)
			(unlocked yes)
			(layer "B.Fab")
			(hide yes)
			(effects
				(font
					(size 1.016 1.016)
					(thickness 0.1524)
				)
				(justify mirror)
			)
		)
		(duplicate_pad_numbers_are_jumpers no)
		(fp_line
			(start -0.635 0)
			(end 0.635 0)
			(stroke
				(width 0.508)
				(type default)
			)
			(layer "B.SilkS")
		)
		(fp_rect
			(start 0.9652 1.778)
			(end -0.9652 -1.778)
			(stroke
				(width 0)
				(type default)
			)
			(fill no)
			(layer "B.CrtYd")
		)
		(fp_poly
			(pts
				(xy 0.9652 -1.778) (xy -0.9652 -1.778) (xy -0.9652 1.778) (xy 0.9652 1.778)
			)
			(stroke
				(width 0)
				(type default)
			)
			(fill no)
			(layer "B.Fab")
		)
		(pad "1" smd rect
			(at 0 -0.9652 270)
			(size 1.397 1.143)
			(layers "B.Cu" "B.Mask" "B.Paste")
			(net "P12V_SYBY_VDD_U6")
		)
		(pad "2" smd rect
			(at 0 0.9652 270)
			(size 1.397 1.143)
			(layers "B.Cu" "B.Mask" "B.Paste")
			(net "GND")
		)
	)
	(footprint ""
		(layer "B.Cu")
		(at 108.6358 -57.4802)
		(property "Reference" "C261"
			(at 0 0 0)
			(layer "B.SilkS")
			(hide yes)
			(effects
				(font
					(size 1.27 1.27)
				)
				(justify mirror)
			)
		)
		(property "Value" "SCD1U6D3V1KX-GP"
			(at 2.8321 -1.7399 0)
			(unlocked yes)
			(layer "B.Fab")
			(hide yes)
			(effects
				(font
					(size 1.016 1.016)
					(thickness 0.1524)
				)
				(justify mirror)
			)
		)
		(property "Device Type" "C0201H13"
			(at 2.8321 -3.2639 0)
			(unlocked yes)
			(layer "B.Fab")
			(hide yes)
			(effects
				(font
					(size 1.016 1.016)
					(thickness 0.1524)
				)
				(justify mirror)
			)
		)
		(duplicate_pad_numbers_are_jumpers no)
		(fp_rect
			(start 0.2794 0.6477)
			(end -0.2794 -0.6477)
			(stroke
				(width 0)
				(type default)
			)
			(fill no)
			(layer "B.CrtYd")
		)
		(fp_rect
			(start 0.2794 0.6477)
			(end -0.2794 -0.6477)
			(stroke
				(width 0)
				(type default)
			)
			(fill no)
			(layer "B.Fab")
		)
		(pad "1" smd custom
			(at 0 -0.2794 180)
			(size 0.0762 0.0762)
			(layers "B.Cu" "B.Mask" "B.Paste")
			(net "GB_VDDA")
			(options
				(clearance outline)
				(anchor circle)
			)
			(primitives
				(gr_poly
					(pts
						(arc
							(start 0.1524 0.127)
							(mid 0.137521 0.162921)
							(end 0.1016 0.1778)
						)
						(arc
							(start -0.1016 0.1778)
							(mid -0.137521 0.162921)
							(end -0.1524 0.127)
						)
						(arc
							(start -0.1524 -0.127)
							(mid -0.137521 -0.162921)
							(end -0.1016 -0.1778)
						)
						(arc
							(start 0.1016 -0.1778)
							(mid 0.137521 -0.162921)
							(end 0.1524 -0.127)
						)
					)
					(width 0)
					(fill yes)
				)
			)
		)
		(pad "2" smd custom
			(at 0 0.2794 180)
			(size 0.0762 0.0762)
			(layers "B.Cu" "B.Mask" "B.Paste")
			(net "GND")
			(options
				(clearance outline)
				(anchor circle)
			)
			(primitives
				(gr_poly
					(pts
						(arc
							(start 0.1524 0.127)
							(mid 0.137521 0.162921)
							(end 0.1016 0.1778)
						)
						(arc
							(start -0.1016 0.1778)
							(mid -0.137521 0.162921)
							(end -0.1524 0.127)
						)
						(arc
							(start -0.1524 -0.127)
							(mid -0.137521 -0.162921)
							(end -0.1016 -0.1778)
						)
						(arc
							(start 0.1016 -0.1778)
							(mid 0.137521 -0.162921)
							(end 0.1524 -0.127)
						)
					)
					(width 0)
					(fill yes)
				)
			)
		)
	)
	(footprint ""
		(layer "B.Cu")
		(at 163.892992 -11.70813)
		(property "Reference" "C104"
			(at 0 0 0)
			(layer "B.SilkS")
			(hide yes)
			(effects
				(font
					(size 1.27 1.27)
				)
				(justify mirror)
			)
		)
		(property "Value" "SCD1U16V2KX-3GP"
			(at -1.1811 -2.7051 0)
			(unlocked yes)
			(layer "B.Fab")
			(hide yes)
			(effects
				(font
					(size 1.016 1.016)
					(thickness 0.1524)
				)
				(justify mirror)
			)
		)
		(property "Device Type" "C402H22"
			(at -1.1811 -4.2291 0)
			(unlocked yes)
			(layer "B.Fab")
			(hide yes)
			(effects
				(font
					(size 1.016 1.016)
					(thickness 0.1524)
				)
				(justify mirror)
			)
		)
		(duplicate_pad_numbers_are_jumpers no)
		(fp_rect
			(start 0.4318 0.9525)
			(end -0.4318 -0.9525)
			(stroke
				(width 0)
				(type default)
			)
			(fill no)
			(layer "B.CrtYd")
		)
		(fp_rect
			(start 0.4318 0.9525)
			(end -0.4318 -0.9525)
			(stroke
				(width 0)
				(type default)
			)
			(fill no)
			(layer "B.Fab")
		)
		(pad "1" smd custom
			(at 0 -0.4445 180)
			(size 0.1524 0.1524)
			(layers "B.Cu" "B.Mask" "B.Paste")
			(net "P3V3")
			(options
				(clearance outline)
				(anchor circle)
			)
			(primitives
				(gr_poly
					(pts
						(arc
							(start 0.3048 0.2032)
							(mid 0.275042 0.275042)
							(end 0.2032 0.3048)
						)
						(arc
							(start -0.2032 0.3048)
							(mid -0.275042 0.275042)
							(end -0.3048 0.2032)
						)
						(arc
							(start -0.3048 -0.2032)
							(mid -0.275042 -0.275042)
							(end -0.2032 -0.3048)
						)
						(arc
							(start 0.2032 -0.3048)
							(mid 0.275042 -0.275042)
							(end 0.3048 -0.2032)
						)
					)
					(width 0)
					(fill yes)
				)
			)
		)
		(pad "2" smd custom
			(at 0 0.4445 180)
			(size 0.1524 0.1524)
			(layers "B.Cu" "B.Mask" "B.Paste")
			(net "GND")
			(options
				(clearance outline)
				(anchor circle)
			)
			(primitives
				(gr_poly
					(pts
						(arc
							(start 0.3048 0.2032)
							(mid 0.275042 0.275042)
							(end 0.2032 0.3048)
						)
						(arc
							(start -0.2032 0.3048)
							(mid -0.275042 0.275042)
							(end -0.3048 0.2032)
						)
						(arc
							(start -0.3048 -0.2032)
							(mid -0.275042 -0.275042)
							(end -0.2032 -0.3048)
						)
						(arc
							(start 0.2032 -0.3048)
							(mid 0.275042 -0.275042)
							(end 0.3048 -0.2032)
						)
					)
					(width 0)
					(fill yes)
				)
			)
		)
	)
	(footprint ""
		(layer "B.Cu")
		(at 118.756938 -66.3575)
		(property "Reference" "C185"
			(at 0 0 0)
			(layer "B.SilkS")
			(hide yes)
			(effects
				(font
					(size 1.27 1.27)
				)
				(justify mirror)
			)
		)
		(property "Value" "SC10U6D3V2MX-GP-U"
			(at 1.524 -1.905 0)
			(unlocked yes)
			(layer "B.Fab")
			(hide yes)
			(effects
				(font
					(size 1.016 1.016)
					(thickness 0.1524)
				)
				(justify mirror)
			)
		)
		(property "Device Type" "C402-TO0D2H28"
			(at 1.524 -3.429 0)
			(unlocked yes)
			(layer "B.Fab")
			(hide yes)
			(effects
				(font
					(size 1.016 1.016)
					(thickness 0.1524)
				)
				(justify mirror)
			)
		)
		(duplicate_pad_numbers_are_jumpers no)
		(fp_rect
			(start 0.4826 0.889)
			(end -0.4826 -0.889)
			(stroke
				(width 0)
				(type default)
			)
			(fill no)
			(layer "B.CrtYd")
		)
		(fp_rect
			(start 0.4826 0.889)
			(end -0.4826 -0.889)
			(stroke
				(width 0)
				(type default)
			)
			(fill no)
			(layer "B.Fab")
		)
		(pad "1" smd custom
			(at 0 -0.4572 180)
			(size 0.1524 0.1524)
			(layers "B.Cu" "B.Mask" "B.Paste")
			(net "P0V9")
			(options
				(clearance outline)
				(anchor circle)
			)
			(primitives
				(gr_poly
					(pts
						(arc
							(start -0.254 -0.3048)
							(mid -0.325842 -0.275042)
							(end -0.3556 -0.2032)
						)
						(arc
							(start -0.3556 0.2032)
							(mid -0.325842 0.275042)
							(end -0.254 0.3048)
						)
						(arc
							(start 0.254 0.3048)
							(mid 0.325842 0.275042)
							(end 0.3556 0.2032)
						)
						(arc
							(start 0.3556 -0.2032)
							(mid 0.325842 -0.275042)
							(end 0.254 -0.3048)
						)
					)
					(width 0)
					(fill yes)
				)
			)
		)
		(pad "2" smd custom
			(at 0 0.4572 180)
			(size 0.1524 0.1524)
			(layers "B.Cu" "B.Mask" "B.Paste")
			(net "GND")
			(options
				(clearance outline)
				(anchor circle)
			)
			(primitives
				(gr_poly
					(pts
						(arc
							(start -0.254 -0.3048)
							(mid -0.325842 -0.275042)
							(end -0.3556 -0.2032)
						)
						(arc
							(start -0.3556 0.2032)
							(mid -0.325842 0.275042)
							(end -0.254 0.3048)
						)
						(arc
							(start 0.254 0.3048)
							(mid 0.325842 0.275042)
							(end 0.3556 0.2032)
						)
						(arc
							(start 0.3556 -0.2032)
							(mid 0.325842 -0.275042)
							(end 0.254 -0.3048)
						)
					)
					(width 0)
					(fill yes)
				)
			)
		)
	)
	(footprint ""
		(layer "B.Cu")
		(at 113.2586 -57.4802)
		(property "Reference" "C538"
			(at 0 0 0)
			(layer "B.SilkS")
			(hide yes)
			(effects
				(font
					(size 1.27 1.27)
				)
				(justify mirror)
			)
		)
		(property "Value" "SCD1U6D3V1KX-GP"
			(at 2.8321 -1.7399 0)
			(unlocked yes)
			(layer "B.Fab")
			(hide yes)
			(effects
				(font
					(size 1.016 1.016)
					(thickness 0.1524)
				)
				(justify mirror)
			)
		)
		(property "Device Type" "C0201H13"
			(at 2.8321 -3.2639 0)
			(unlocked yes)
			(layer "B.Fab")
			(hide yes)
			(effects
				(font
					(size 1.016 1.016)
					(thickness 0.1524)
				)
				(justify mirror)
			)
		)
		(duplicate_pad_numbers_are_jumpers no)
		(fp_rect
			(start 0.2794 0.6477)
			(end -0.2794 -0.6477)
			(stroke
				(width 0)
				(type default)
			)
			(fill no)
			(layer "B.CrtYd")
		)
		(fp_rect
			(start 0.2794 0.6477)
			(end -0.2794 -0.6477)
			(stroke
				(width 0)
				(type default)
			)
			(fill no)
			(layer "B.Fab")
		)
		(pad "1" smd custom
			(at 0 -0.2794 180)
			(size 0.0762 0.0762)
			(layers "B.Cu" "B.Mask" "B.Paste")
			(net "GB_VDDA")
			(options
				(clearance outline)
				(anchor circle)
			)
			(primitives
				(gr_poly
					(pts
						(arc
							(start 0.1524 0.127)
							(mid 0.137521 0.162921)
							(end 0.1016 0.1778)
						)
						(arc
							(start -0.1016 0.1778)
							(mid -0.137521 0.162921)
							(end -0.1524 0.127)
						)
						(arc
							(start -0.1524 -0.127)
							(mid -0.137521 -0.162921)
							(end -0.1016 -0.1778)
						)
						(arc
							(start 0.1016 -0.1778)
							(mid 0.137521 -0.162921)
							(end 0.1524 -0.127)
						)
					)
					(width 0)
					(fill yes)
				)
			)
		)
		(pad "2" smd custom
			(at 0 0.2794 180)
			(size 0.0762 0.0762)
			(layers "B.Cu" "B.Mask" "B.Paste")
			(net "GND")
			(options
				(clearance outline)
				(anchor circle)
			)
			(primitives
				(gr_poly
					(pts
						(arc
							(start 0.1524 0.127)
							(mid 0.137521 0.162921)
							(end 0.1016 0.1778)
						)
						(arc
							(start -0.1016 0.1778)
							(mid -0.137521 0.162921)
							(end -0.1524 0.127)
						)
						(arc
							(start -0.1524 -0.127)
							(mid -0.137521 -0.162921)
							(end -0.1016 -0.1778)
						)
						(arc
							(start 0.1016 -0.1778)
							(mid 0.137521 -0.162921)
							(end 0.1524 -0.127)
						)
					)
					(width 0)
					(fill yes)
				)
			)
		)
	)
	(footprint ""
		(layer "B.Cu")
		(at 122.584972 -86.650068 180)
		(property "Reference" "R78"
			(at 0 0 0)
			(layer "B.SilkS")
			(hide yes)
			(effects
				(font
					(size 1.27 1.27)
				)
				(justify mirror)
			)
		)
		(property "Value" "4K7R2F-GP"
			(at -0.064008 -3.993896 180)
			(unlocked yes)
			(layer "B.Fab")
			(hide yes)
			(effects
				(font
					(size 1.016 1.016)
					(thickness 0.1524)
				)
				(justify mirror)
			)
		)
		(property "Device Type" "R402H16"
			(at -0.064008 -5.517896 180)
			(unlocked yes)
			(layer "B.Fab")
			(hide yes)
			(effects
				(font
					(size 1.016 1.016)
					(thickness 0.1524)
				)
				(justify mirror)
			)
		)
		(duplicate_pad_numbers_are_jumpers no)
		(fp_line
			(start 0.508 -0.9398)
			(end 0.508 0.9398)
			(stroke
				(width 0.1524)
				(type default)
			)
			(layer "B.SilkS")
		)
		(fp_line
			(start -0.508 -0.9398)
			(end 0.508 -0.9398)
			(stroke
				(width 0.1524)
				(type default)
			)
			(layer "B.SilkS")
		)
		(fp_rect
			(start 0.508 0.9398)
			(end -0.508 -0.9398)
			(stroke
				(width 0)
				(type default)
			)
			(fill no)
			(layer "B.CrtYd")
		)
		(fp_rect
			(start 0.508 0.9398)
			(end -0.508 -0.9398)
			(stroke
				(width 0)
				(type default)
			)
			(fill no)
			(layer "B.Fab")
		)
		(pad "1" smd custom
			(at 0 -0.4445)
			(size 0.1397 0.1397)
			(layers "B.Cu" "B.Mask" "B.Paste")
			(net "SCC_TYPE_2_LS")
			(options
				(clearance outline)
				(anchor circle)
			)
			(primitives
				(gr_poly
					(pts
						(arc
							(start -0.1778 0.2794)
							(mid -0.249642 0.249642)
							(end -0.2794 0.1778)
						)
						(arc
							(start -0.2794 -0.1778)
							(mid -0.249642 -0.249642)
							(end -0.1778 -0.2794)
						)
						(arc
							(start 0.1778 -0.2794)
							(mid 0.249642 -0.249642)
							(end 0.2794 -0.1778)
						)
						(arc
							(start 0.2794 0.1778)
							(mid 0.249642 0.249642)
							(end 0.1778 0.2794)
						)
					)
					(width 0)
					(fill yes)
				)
			)
		)
		(pad "2" smd custom
			(at 0 0.4445)
			(size 0.1397 0.1397)
			(layers "B.Cu" "B.Mask" "B.Paste")
			(net "GND")
			(options
				(clearance outline)
				(anchor circle)
			)
			(primitives
				(gr_poly
					(pts
						(arc
							(start -0.1778 0.2794)
							(mid -0.249642 0.249642)
							(end -0.2794 0.1778)
						)
						(arc
							(start -0.2794 -0.1778)
							(mid -0.249642 -0.249642)
							(end -0.1778 -0.2794)
						)
						(arc
							(start 0.1778 -0.2794)
							(mid 0.249642 -0.249642)
							(end 0.2794 -0.1778)
						)
						(arc
							(start 0.2794 0.1778)
							(mid 0.249642 0.249642)
							(end 0.1778 0.2794)
						)
					)
					(width 0)
					(fill yes)
				)
			)
		)
	)
	(footprint ""
		(layer "B.Cu")
		(at 164.085016 -45.661072)
		(property "Reference" "TP90"
			(at 0 0 0)
			(layer "B.SilkS")
			(hide yes)
			(effects
				(font
					(size 1.27 1.27)
				)
				(justify mirror)
			)
		)
		(property "Value" "TPAD28-2-GP"
			(at 0.0127 -1.6637 0)
			(unlocked yes)
			(layer "B.Fab")
			(hide yes)
			(effects
				(font
					(size 1.016 1.016)
					(thickness 0.1524)
				)
				(justify mirror)
			)
		)
		(property "Device Type" "TPAD28"
			(at 0.0127 -3.1877 0)
			(unlocked yes)
			(layer "B.Fab")
			(hide yes)
			(effects
				(font
					(size 1.016 1.016)
					(thickness 0.1524)
				)
				(justify mirror)
			)
		)
		(duplicate_pad_numbers_are_jumpers no)
		(fp_poly
			(pts
				(arc
					(start 0.3556 0)
					(mid -0.3556 0)
					(end 0.3556 0)
				)
			)
			(stroke
				(width 0)
				(type default)
			)
			(fill no)
			(layer "B.CrtYd")
		)
		(fp_poly
			(pts
				(arc
					(start 0.6096 0)
					(mid -0.6096 0)
					(end 0.6096 0)
				)
			)
			(stroke
				(width 0)
				(type default)
			)
			(fill no)
			(layer "B.Fab")
		)
		(pad "1" smd circle
			(at 0 0 180)
			(size 0.7112 0.7112)
			(layers "B.Cu" "B.Mask" "B.Paste")
			(net "SIO_DIN_1")
		)
	)
	(footprint ""
		(layer "B.Cu")
		(at 176.193196 -33.60293)
		(property "Reference" "TP147"
			(at 0 0 0)
			(layer "B.SilkS")
			(hide yes)
			(effects
				(font
					(size 1.27 1.27)
				)
				(justify mirror)
			)
		)
		(property "Value" "TPAD28-2-GP"
			(at 0.0127 -1.6637 0)
			(unlocked yes)
			(layer "B.Fab")
			(hide yes)
			(effects
				(font
					(size 1.016 1.016)
					(thickness 0.1524)
				)
				(justify mirror)
			)
		)
		(property "Device Type" "TPAD28"
			(at 0.0127 -3.1877 0)
			(unlocked yes)
			(layer "B.Fab")
			(hide yes)
			(effects
				(font
					(size 1.016 1.016)
					(thickness 0.1524)
				)
				(justify mirror)
			)
		)
		(duplicate_pad_numbers_are_jumpers no)
		(fp_poly
			(pts
				(arc
					(start 0.3556 0)
					(mid -0.3556 0)
					(end 0.3556 0)
				)
			)
			(stroke
				(width 0)
				(type default)
			)
			(fill no)
			(layer "B.CrtYd")
		)
		(fp_poly
			(pts
				(arc
					(start 0.6096 0)
					(mid -0.6096 0)
					(end 0.6096 0)
				)
			)
			(stroke
				(width 0)
				(type default)
			)
			(fill no)
			(layer "B.Fab")
		)
		(pad "1" smd circle
			(at 0 0 180)
			(size 0.7112 0.7112)
			(layers "B.Cu" "B.Mask" "B.Paste")
			(net "SPARE3")
		)
	)
	(footprint ""
		(layer "B.Cu")
		(at 172.844206 -68.199 90)
		(property "Reference" "R317"
			(at 0 0 90)
			(layer "B.SilkS")
			(hide yes)
			(effects
				(font
					(size 1.27 1.27)
				)
				(justify mirror)
			)
		)
		(property "Value" "4K7R2F-GP"
			(at -0.064008 -3.993896 90)
			(unlocked yes)
			(layer "B.Fab")
			(hide yes)
			(effects
				(font
					(size 1.016 1.016)
					(thickness 0.1524)
				)
				(justify mirror)
			)
		)
		(property "Device Type" "R402H16"
			(at -0.064008 -5.517896 90)
			(unlocked yes)
			(layer "B.Fab")
			(hide yes)
			(effects
				(font
					(size 1.016 1.016)
					(thickness 0.1524)
				)
				(justify mirror)
			)
		)
		(duplicate_pad_numbers_are_jumpers no)
		(fp_line
			(start 0.508 -0.9398)
			(end 0.508 0.9398)
			(stroke
				(width 0.1524)
				(type default)
			)
			(layer "B.SilkS")
		)
		(fp_line
			(start -0.508 -0.9398)
			(end 0.508 -0.9398)
			(stroke
				(width 0.1524)
				(type default)
			)
			(layer "B.SilkS")
		)
		(fp_rect
			(start 0.508 0.9398)
			(end -0.508 -0.9398)
			(stroke
				(width 0)
				(type default)
			)
			(fill no)
			(layer "B.CrtYd")
		)
		(fp_rect
			(start 0.508 0.9398)
			(end -0.508 -0.9398)
			(stroke
				(width 0)
				(type default)
			)
			(fill no)
			(layer "B.Fab")
		)
		(pad "1" smd custom
			(at 0 -0.4445 270)
			(size 0.1397 0.1397)
			(layers "B.Cu" "B.Mask" "B.Paste")
			(net "P3V3")
			(options
				(clearance outline)
				(anchor circle)
			)
			(primitives
				(gr_poly
					(pts
						(arc
							(start -0.1778 0.2794)
							(mid -0.249642 0.249642)
							(end -0.2794 0.1778)
						)
						(arc
							(start -0.2794 -0.1778)
							(mid -0.249642 -0.249642)
							(end -0.1778 -0.2794)
						)
						(arc
							(start 0.1778 -0.2794)
							(mid 0.249642 -0.249642)
							(end 0.2794 -0.1778)
						)
						(arc
							(start 0.2794 0.1778)
							(mid 0.249642 0.249642)
							(end 0.1778 0.2794)
						)
					)
					(width 0)
					(fill yes)
				)
			)
		)
		(pad "2" smd custom
			(at 0 0.4445 270)
			(size 0.1397 0.1397)
			(layers "B.Cu" "B.Mask" "B.Paste")
			(net "SYS_RST_Q8")
			(options
				(clearance outline)
				(anchor circle)
			)
			(primitives
				(gr_poly
					(pts
						(arc
							(start -0.1778 0.2794)
							(mid -0.249642 0.249642)
							(end -0.2794 0.1778)
						)
						(arc
							(start -0.2794 -0.1778)
							(mid -0.249642 -0.249642)
							(end -0.1778 -0.2794)
						)
						(arc
							(start 0.1778 -0.2794)
							(mid 0.249642 -0.249642)
							(end 0.2794 -0.1778)
						)
						(arc
							(start 0.2794 0.1778)
							(mid 0.249642 0.249642)
							(end 0.1778 0.2794)
						)
					)
					(width 0)
					(fill yes)
				)
			)
		)
	)
	(footprint ""
		(layer "B.Cu")
		(at 110.744 -59.4487)
		(property "Reference" "C240"
			(at 0 0 0)
			(layer "B.SilkS")
			(hide yes)
			(effects
				(font
					(size 1.27 1.27)
				)
				(justify mirror)
			)
		)
		(property "Value" "SCD1U6D3V1KX-GP"
			(at 2.8321 -1.7399 0)
			(unlocked yes)
			(layer "B.Fab")
			(hide yes)
			(effects
				(font
					(size 1.016 1.016)
					(thickness 0.1524)
				)
				(justify mirror)
			)
		)
		(property "Device Type" "C0201H13"
			(at 2.8321 -3.2639 0)
			(unlocked yes)
			(layer "B.Fab")
			(hide yes)
			(effects
				(font
					(size 1.016 1.016)
					(thickness 0.1524)
				)
				(justify mirror)
			)
		)
		(duplicate_pad_numbers_are_jumpers no)
		(fp_rect
			(start 0.2794 0.6477)
			(end -0.2794 -0.6477)
			(stroke
				(width 0)
				(type default)
			)
			(fill no)
			(layer "B.CrtYd")
		)
		(fp_rect
			(start 0.2794 0.6477)
			(end -0.2794 -0.6477)
			(stroke
				(width 0)
				(type default)
			)
			(fill no)
			(layer "B.Fab")
		)
		(pad "1" smd custom
			(at 0 -0.2794 180)
			(size 0.0762 0.0762)
			(layers "B.Cu" "B.Mask" "B.Paste")
			(net "GB_VDDA")
			(options
				(clearance outline)
				(anchor circle)
			)
			(primitives
				(gr_poly
					(pts
						(arc
							(start 0.1524 0.127)
							(mid 0.137521 0.162921)
							(end 0.1016 0.1778)
						)
						(arc
							(start -0.1016 0.1778)
							(mid -0.137521 0.162921)
							(end -0.1524 0.127)
						)
						(arc
							(start -0.1524 -0.127)
							(mid -0.137521 -0.162921)
							(end -0.1016 -0.1778)
						)
						(arc
							(start 0.1016 -0.1778)
							(mid 0.137521 -0.162921)
							(end 0.1524 -0.127)
						)
					)
					(width 0)
					(fill yes)
				)
			)
		)
		(pad "2" smd custom
			(at 0 0.2794 180)
			(size 0.0762 0.0762)
			(layers "B.Cu" "B.Mask" "B.Paste")
			(net "GND")
			(options
				(clearance outline)
				(anchor circle)
			)
			(primitives
				(gr_poly
					(pts
						(arc
							(start 0.1524 0.127)
							(mid 0.137521 0.162921)
							(end 0.1016 0.1778)
						)
						(arc
							(start -0.1016 0.1778)
							(mid -0.137521 0.162921)
							(end -0.1524 0.127)
						)
						(arc
							(start -0.1524 -0.127)
							(mid -0.137521 -0.162921)
							(end -0.1016 -0.1778)
						)
						(arc
							(start 0.1016 -0.1778)
							(mid 0.137521 -0.162921)
							(end 0.1524 -0.127)
						)
					)
					(width 0)
					(fill yes)
				)
			)
		)
	)
	(footprint ""
		(layer "B.Cu")
		(at 182.8038 -54.9402)
		(property "Reference" "R218"
			(at 0 0 0)
			(layer "B.SilkS")
			(hide yes)
			(effects
				(font
					(size 1.27 1.27)
				)
				(justify mirror)
			)
		)
		(property "Value" "10KR2F-2-GP"
			(at -0.064008 -3.993896 0)
			(unlocked yes)
			(layer "B.Fab")
			(hide yes)
			(effects
				(font
					(size 1.016 1.016)
					(thickness 0.1524)
				)
				(justify mirror)
			)
		)
		(property "Device Type" "R402H16"
			(at -0.064008 -5.517896 0)
			(unlocked yes)
			(layer "B.Fab")
			(hide yes)
			(effects
				(font
					(size 1.016 1.016)
					(thickness 0.1524)
				)
				(justify mirror)
			)
		)
		(duplicate_pad_numbers_are_jumpers no)
		(fp_line
			(start -0.508 -0.9398)
			(end 0.508 -0.9398)
			(stroke
				(width 0.1524)
				(type default)
			)
			(layer "B.SilkS")
		)
		(fp_line
			(start 0.508 -0.9398)
			(end 0.508 0.9398)
			(stroke
				(width 0.1524)
				(type default)
			)
			(layer "B.SilkS")
		)
		(fp_rect
			(start 0.508 0.9398)
			(end -0.508 -0.9398)
			(stroke
				(width 0)
				(type default)
			)
			(fill no)
			(layer "B.CrtYd")
		)
		(fp_rect
			(start 0.508 0.9398)
			(end -0.508 -0.9398)
			(stroke
				(width 0)
				(type default)
			)
			(fill no)
			(layer "B.Fab")
		)
		(pad "1" smd custom
			(at 0 -0.4445 180)
			(size 0.1397 0.1397)
			(layers "B.Cu" "B.Mask" "B.Paste")
			(net "P1V8_C")
			(options
				(clearance outline)
				(anchor circle)
			)
			(primitives
				(gr_poly
					(pts
						(arc
							(start -0.1778 0.2794)
							(mid -0.249642 0.249642)
							(end -0.2794 0.1778)
						)
						(arc
							(start -0.2794 -0.1778)
							(mid -0.249642 -0.249642)
							(end -0.1778 -0.2794)
						)
						(arc
							(start 0.1778 -0.2794)
							(mid 0.249642 -0.249642)
							(end 0.2794 -0.1778)
						)
						(arc
							(start 0.2794 0.1778)
							(mid 0.249642 0.249642)
							(end 0.1778 0.2794)
						)
					)
					(width 0)
					(fill yes)
				)
			)
		)
		(pad "2" smd custom
			(at 0 0.4445 180)
			(size 0.1397 0.1397)
			(layers "B.Cu" "B.Mask" "B.Paste")
			(net "XM_WE_N")
			(options
				(clearance outline)
				(anchor circle)
			)
			(primitives
				(gr_poly
					(pts
						(arc
							(start -0.1778 0.2794)
							(mid -0.249642 0.249642)
							(end -0.2794 0.1778)
						)
						(arc
							(start -0.2794 -0.1778)
							(mid -0.249642 -0.249642)
							(end -0.1778 -0.2794)
						)
						(arc
							(start 0.1778 -0.2794)
							(mid 0.249642 -0.249642)
							(end 0.2794 -0.1778)
						)
						(arc
							(start 0.2794 0.1778)
							(mid 0.249642 0.249642)
							(end 0.1778 0.2794)
						)
					)
					(width 0)
					(fill yes)
				)
			)
		)
	)
	(footprint ""
		(layer "B.Cu")
		(at 177.8127 -38.11016 90)
		(property "Reference" "C434"
			(at 0 0 90)
			(layer "B.SilkS")
			(hide yes)
			(effects
				(font
					(size 1.27 1.27)
				)
				(justify mirror)
			)
		)
		(property "Value" "SCD1U6D3V1KX-GP"
			(at 2.8321 -1.7399 90)
			(unlocked yes)
			(layer "B.Fab")
			(hide yes)
			(effects
				(font
					(size 1.016 1.016)
					(thickness 0.1524)
				)
				(justify mirror)
			)
		)
		(property "Device Type" "C0201H13"
			(at 2.8321 -3.2639 90)
			(unlocked yes)
			(layer "B.Fab")
			(hide yes)
			(effects
				(font
					(size 1.016 1.016)
					(thickness 0.1524)
				)
				(justify mirror)
			)
		)
		(duplicate_pad_numbers_are_jumpers no)
		(fp_rect
			(start 0.2794 0.6477)
			(end -0.2794 -0.6477)
			(stroke
				(width 0)
				(type default)
			)
			(fill no)
			(layer "B.CrtYd")
		)
		(fp_rect
			(start 0.2794 0.6477)
			(end -0.2794 -0.6477)
			(stroke
				(width 0)
				(type default)
			)
			(fill no)
			(layer "B.Fab")
		)
		(pad "1" smd custom
			(at 0 -0.2794 270)
			(size 0.0762 0.0762)
			(layers "B.Cu" "B.Mask" "B.Paste")
			(net "P0V975")
			(options
				(clearance outline)
				(anchor circle)
			)
			(primitives
				(gr_poly
					(pts
						(arc
							(start 0.1524 0.127)
							(mid 0.137521 0.162921)
							(end 0.1016 0.1778)
						)
						(arc
							(start -0.1016 0.1778)
							(mid -0.137521 0.162921)
							(end -0.1524 0.127)
						)
						(arc
							(start -0.1524 -0.127)
							(mid -0.137521 -0.162921)
							(end -0.1016 -0.1778)
						)
						(arc
							(start 0.1016 -0.1778)
							(mid 0.137521 -0.162921)
							(end 0.1524 -0.127)
						)
					)
					(width 0)
					(fill yes)
				)
			)
		)
		(pad "2" smd custom
			(at 0 0.2794 270)
			(size 0.0762 0.0762)
			(layers "B.Cu" "B.Mask" "B.Paste")
			(net "GND")
			(options
				(clearance outline)
				(anchor circle)
			)
			(primitives
				(gr_poly
					(pts
						(arc
							(start 0.1524 0.127)
							(mid 0.137521 0.162921)
							(end 0.1016 0.1778)
						)
						(arc
							(start -0.1016 0.1778)
							(mid -0.137521 0.162921)
							(end -0.1524 0.127)
						)
						(arc
							(start -0.1524 -0.127)
							(mid -0.137521 -0.162921)
							(end -0.1016 -0.1778)
						)
						(arc
							(start 0.1016 -0.1778)
							(mid 0.137521 -0.162921)
							(end 0.1524 -0.127)
						)
					)
					(width 0)
					(fill yes)
				)
			)
		)
	)
	(footprint ""
		(layer "B.Cu")
		(at 163.957 -66.7766)
		(property "Reference" "R281"
			(at 0 0 0)
			(layer "B.SilkS")
			(hide yes)
			(effects
				(font
					(size 1.27 1.27)
				)
				(justify mirror)
			)
		)
		(property "Value" "10R2F-L-GP"
			(at -0.064008 -3.993896 0)
			(unlocked yes)
			(layer "B.Fab")
			(hide yes)
			(effects
				(font
					(size 1.016 1.016)
					(thickness 0.1524)
				)
				(justify mirror)
			)
		)
		(property "Device Type" "R402H14"
			(at -0.064008 -5.517896 0)
			(unlocked yes)
			(layer "B.Fab")
			(hide yes)
			(effects
				(font
					(size 1.016 1.016)
					(thickness 0.1524)
				)
				(justify mirror)
			)
		)
		(duplicate_pad_numbers_are_jumpers no)
		(fp_line
			(start -0.508 -0.9398)
			(end 0.508 -0.9398)
			(stroke
				(width 0.1524)
				(type default)
			)
			(layer "B.SilkS")
		)
		(fp_line
			(start 0.508 -0.9398)
			(end 0.508 0.9398)
			(stroke
				(width 0.1524)
				(type default)
			)
			(layer "B.SilkS")
		)
		(fp_rect
			(start 0.508 0.9398)
			(end -0.508 -0.9398)
			(stroke
				(width 0)
				(type default)
			)
			(fill no)
			(layer "B.CrtYd")
		)
		(fp_rect
			(start 0.508 0.9398)
			(end -0.508 -0.9398)
			(stroke
				(width 0)
				(type default)
			)
			(fill no)
			(layer "B.Fab")
		)
		(pad "1" smd custom
			(at 0 -0.4445 180)
			(size 0.1397 0.1397)
			(layers "B.Cu" "B.Mask" "B.Paste")
			(net "P1V8_C")
			(options
				(clearance outline)
				(anchor circle)
			)
			(primitives
				(gr_poly
					(pts
						(arc
							(start -0.1778 0.2794)
							(mid -0.249642 0.249642)
							(end -0.2794 0.1778)
						)
						(arc
							(start -0.2794 -0.1778)
							(mid -0.249642 -0.249642)
							(end -0.1778 -0.2794)
						)
						(arc
							(start 0.1778 -0.2794)
							(mid 0.249642 -0.249642)
							(end 0.2794 -0.1778)
						)
						(arc
							(start 0.2794 0.1778)
							(mid 0.249642 0.249642)
							(end 0.1778 0.2794)
						)
					)
					(width 0)
					(fill yes)
				)
			)
		)
		(pad "2" smd custom
			(at 0 0.4445 180)
			(size 0.1397 0.1397)
			(layers "B.Cu" "B.Mask" "B.Paste")
			(net "VDDA_SAS_REF_CLK")
			(options
				(clearance outline)
				(anchor circle)
			)
			(primitives
				(gr_poly
					(pts
						(arc
							(start -0.1778 0.2794)
							(mid -0.249642 0.249642)
							(end -0.2794 0.1778)
						)
						(arc
							(start -0.2794 -0.1778)
							(mid -0.249642 -0.249642)
							(end -0.1778 -0.2794)
						)
						(arc
							(start 0.1778 -0.2794)
							(mid 0.249642 -0.249642)
							(end 0.2794 -0.1778)
						)
						(arc
							(start 0.2794 0.1778)
							(mid 0.249642 0.249642)
							(end 0.1778 0.2794)
						)
					)
					(width 0)
					(fill yes)
				)
			)
		)
	)
	(footprint ""
		(layer "B.Cu")
		(at 158.821374 -33.403032 180)
		(property "Reference" "C372"
			(at 0 0 0)
			(layer "B.SilkS")
			(hide yes)
			(effects
				(font
					(size 1.27 1.27)
				)
				(justify mirror)
			)
		)
		(property "Value" "SC10U6D3V5KX-4GP"
			(at 0.0762 -6.1214 180)
			(unlocked yes)
			(layer "B.Fab")
			(hide yes)
			(effects
				(font
					(size 1.016 1.016)
					(thickness 0.1524)
				)
				(justify mirror)
			)
		)
		(property "Device Type" "C805H58"
			(at 0.0762 -8.1534 180)
			(unlocked yes)
			(layer "B.Fab")
			(hide yes)
			(effects
				(font
					(size 1.016 1.016)
					(thickness 0.1524)
				)
				(justify mirror)
			)
		)
		(duplicate_pad_numbers_are_jumpers no)
		(fp_line
			(start -0.635 0)
			(end 0.635 0)
			(stroke
				(width 0.508)
				(type default)
			)
			(layer "B.SilkS")
		)
		(fp_rect
			(start 0.9652 1.778)
			(end -0.9652 -1.778)
			(stroke
				(width 0)
				(type default)
			)
			(fill no)
			(layer "B.CrtYd")
		)
		(fp_poly
			(pts
				(xy 0.9652 -1.778) (xy -0.9652 -1.778) (xy -0.9652 1.778) (xy 0.9652 1.778)
			)
			(stroke
				(width 0)
				(type default)
			)
			(fill no)
			(layer "B.Fab")
		)
		(pad "1" smd rect
			(at 0 -0.9652)
			(size 1.397 1.143)
			(layers "B.Cu" "B.Mask" "B.Paste")
			(net "SAS0_VDDH")
		)
		(pad "2" smd rect
			(at 0 0.9652)
			(size 1.397 1.143)
			(layers "B.Cu" "B.Mask" "B.Paste")
			(net "GND")
		)
	)
	(footprint ""
		(layer "B.Cu")
		(at 166.885874 -96.109282 180)
		(property "Reference" "R485"
			(at 0 0 0)
			(layer "B.SilkS")
			(hide yes)
			(effects
				(font
					(size 1.27 1.27)
				)
				(justify mirror)
			)
		)
		(property "Value" "69K8R2F-GP"
			(at -0.064008 -3.993896 180)
			(unlocked yes)
			(layer "B.Fab")
			(hide yes)
			(effects
				(font
					(size 1.016 1.016)
					(thickness 0.1524)
				)
				(justify mirror)
			)
		)
		(property "Device Type" "R402H16"
			(at -0.064008 -5.517896 180)
			(unlocked yes)
			(layer "B.Fab")
			(hide yes)
			(effects
				(font
					(size 1.016 1.016)
					(thickness 0.1524)
				)
				(justify mirror)
			)
		)
		(duplicate_pad_numbers_are_jumpers no)
		(fp_line
			(start 0.508 -0.9398)
			(end 0.508 0.9398)
			(stroke
				(width 0.1524)
				(type default)
			)
			(layer "B.SilkS")
		)
		(fp_line
			(start -0.508 -0.9398)
			(end 0.508 -0.9398)
			(stroke
				(width 0.1524)
				(type default)
			)
			(layer "B.SilkS")
		)
		(fp_rect
			(start 0.508 0.9398)
			(end -0.508 -0.9398)
			(stroke
				(width 0)
				(type default)
			)
			(fill no)
			(layer "B.CrtYd")
		)
		(fp_rect
			(start 0.508 0.9398)
			(end -0.508 -0.9398)
			(stroke
				(width 0)
				(type default)
			)
			(fill no)
			(layer "B.Fab")
		)
		(pad "1" smd custom
			(at 0 -0.4445)
			(size 0.1397 0.1397)
			(layers "B.Cu" "B.Mask" "B.Paste")
			(net "AGND_P0V975")
			(options
				(clearance outline)
				(anchor circle)
			)
			(primitives
				(gr_poly
					(pts
						(arc
							(start -0.1778 0.2794)
							(mid -0.249642 0.249642)
							(end -0.2794 0.1778)
						)
						(arc
							(start -0.2794 -0.1778)
							(mid -0.249642 -0.249642)
							(end -0.1778 -0.2794)
						)
						(arc
							(start 0.1778 -0.2794)
							(mid 0.249642 -0.249642)
							(end 0.2794 -0.1778)
						)
						(arc
							(start 0.2794 0.1778)
							(mid 0.249642 0.249642)
							(end 0.1778 0.2794)
						)
					)
					(width 0)
					(fill yes)
				)
			)
		)
		(pad "2" smd custom
			(at 0 0.4445)
			(size 0.1397 0.1397)
			(layers "B.Cu" "B.Mask" "B.Paste")
			(net "VT235_IRIP")
			(options
				(clearance outline)
				(anchor circle)
			)
			(primitives
				(gr_poly
					(pts
						(arc
							(start -0.1778 0.2794)
							(mid -0.249642 0.249642)
							(end -0.2794 0.1778)
						)
						(arc
							(start -0.2794 -0.1778)
							(mid -0.249642 -0.249642)
							(end -0.1778 -0.2794)
						)
						(arc
							(start 0.1778 -0.2794)
							(mid 0.249642 -0.249642)
							(end 0.2794 -0.1778)
						)
						(arc
							(start 0.2794 0.1778)
							(mid 0.249642 0.249642)
							(end 0.1778 0.2794)
						)
					)
					(width 0)
					(fill yes)
				)
			)
		)
	)
	(footprint ""
		(layer "B.Cu")
		(at 167.64 -52.07)
		(property "Reference" "R261"
			(at 0 0 0)
			(layer "B.SilkS")
			(hide yes)
			(effects
				(font
					(size 1.27 1.27)
				)
				(justify mirror)
			)
		)
		(property "Value" "4K7R2F-GP"
			(at -0.064008 -3.993896 0)
			(unlocked yes)
			(layer "B.Fab")
			(hide yes)
			(effects
				(font
					(size 1.016 1.016)
					(thickness 0.1524)
				)
				(justify mirror)
			)
		)
		(property "Device Type" "R402H16"
			(at -0.064008 -5.517896 0)
			(unlocked yes)
			(layer "B.Fab")
			(hide yes)
			(effects
				(font
					(size 1.016 1.016)
					(thickness 0.1524)
				)
				(justify mirror)
			)
		)
		(duplicate_pad_numbers_are_jumpers no)
		(fp_line
			(start -0.508 -0.9398)
			(end 0.508 -0.9398)
			(stroke
				(width 0.1524)
				(type default)
			)
			(layer "B.SilkS")
		)
		(fp_line
			(start 0.508 -0.9398)
			(end 0.508 0.9398)
			(stroke
				(width 0.1524)
				(type default)
			)
			(layer "B.SilkS")
		)
		(fp_rect
			(start 0.508 0.9398)
			(end -0.508 -0.9398)
			(stroke
				(width 0)
				(type default)
			)
			(fill no)
			(layer "B.CrtYd")
		)
		(fp_rect
			(start 0.508 0.9398)
			(end -0.508 -0.9398)
			(stroke
				(width 0)
				(type default)
			)
			(fill no)
			(layer "B.Fab")
		)
		(pad "1" smd custom
			(at 0 -0.4445 180)
			(size 0.1397 0.1397)
			(layers "B.Cu" "B.Mask" "B.Paste")
			(net "P1V8_C")
			(options
				(clearance outline)
				(anchor circle)
			)
			(primitives
				(gr_poly
					(pts
						(arc
							(start -0.1778 0.2794)
							(mid -0.249642 0.249642)
							(end -0.2794 0.1778)
						)
						(arc
							(start -0.2794 -0.1778)
							(mid -0.249642 -0.249642)
							(end -0.1778 -0.2794)
						)
						(arc
							(start 0.1778 -0.2794)
							(mid 0.249642 -0.249642)
							(end 0.2794 -0.1778)
						)
						(arc
							(start 0.2794 0.1778)
							(mid 0.249642 0.249642)
							(end 0.1778 0.2794)
						)
					)
					(width 0)
					(fill yes)
				)
			)
		)
		(pad "2" smd custom
			(at 0 0.4445 180)
			(size 0.1397 0.1397)
			(layers "B.Cu" "B.Mask" "B.Paste")
			(net "ICE1_TDI")
			(options
				(clearance outline)
				(anchor circle)
			)
			(primitives
				(gr_poly
					(pts
						(arc
							(start -0.1778 0.2794)
							(mid -0.249642 0.249642)
							(end -0.2794 0.1778)
						)
						(arc
							(start -0.2794 -0.1778)
							(mid -0.249642 -0.249642)
							(end -0.1778 -0.2794)
						)
						(arc
							(start 0.1778 -0.2794)
							(mid 0.249642 -0.249642)
							(end 0.2794 -0.1778)
						)
						(arc
							(start 0.2794 0.1778)
							(mid 0.249642 0.249642)
							(end 0.1778 0.2794)
						)
					)
					(width 0)
					(fill yes)
				)
			)
		)
	)
	(footprint ""
		(layer "B.Cu")
		(at 193.26098 -21.8694 90)
		(property "Reference" "R241"
			(at 0 0 90)
			(layer "B.SilkS")
			(hide yes)
			(effects
				(font
					(size 1.27 1.27)
				)
				(justify mirror)
			)
		)
		(property "Value" "10KR2F-2-GP"
			(at -0.064008 -3.993896 90)
			(unlocked yes)
			(layer "B.Fab")
			(hide yes)
			(effects
				(font
					(size 1.016 1.016)
					(thickness 0.1524)
				)
				(justify mirror)
			)
		)
		(property "Device Type" "R402H16"
			(at -0.064008 -5.517896 90)
			(unlocked yes)
			(layer "B.Fab")
			(hide yes)
			(effects
				(font
					(size 1.016 1.016)
					(thickness 0.1524)
				)
				(justify mirror)
			)
		)
		(duplicate_pad_numbers_are_jumpers no)
		(fp_line
			(start 0.508 -0.9398)
			(end 0.508 0.9398)
			(stroke
				(width 0.1524)
				(type default)
			)
			(layer "B.SilkS")
		)
		(fp_line
			(start -0.508 -0.9398)
			(end 0.508 -0.9398)
			(stroke
				(width 0.1524)
				(type default)
			)
			(layer "B.SilkS")
		)
		(fp_rect
			(start 0.508 0.9398)
			(end -0.508 -0.9398)
			(stroke
				(width 0)
				(type default)
			)
			(fill no)
			(layer "B.CrtYd")
		)
		(fp_rect
			(start 0.508 0.9398)
			(end -0.508 -0.9398)
			(stroke
				(width 0)
				(type default)
			)
			(fill no)
			(layer "B.Fab")
		)
		(pad "1" smd custom
			(at 0 -0.4445 270)
			(size 0.1397 0.1397)
			(layers "B.Cu" "B.Mask" "B.Paste")
			(net "P1V8_C")
			(options
				(clearance outline)
				(anchor circle)
			)
			(primitives
				(gr_poly
					(pts
						(arc
							(start -0.1778 0.2794)
							(mid -0.249642 0.249642)
							(end -0.2794 0.1778)
						)
						(arc
							(start -0.2794 -0.1778)
							(mid -0.249642 -0.249642)
							(end -0.1778 -0.2794)
						)
						(arc
							(start 0.1778 -0.2794)
							(mid 0.249642 -0.249642)
							(end 0.2794 -0.1778)
						)
						(arc
							(start 0.2794 0.1778)
							(mid 0.249642 0.249642)
							(end 0.1778 0.2794)
						)
					)
					(width 0)
					(fill yes)
				)
			)
		)
		(pad "2" smd custom
			(at 0 0.4445 270)
			(size 0.1397 0.1397)
			(layers "B.Cu" "B.Mask" "B.Paste")
			(net "SYS_HB_LED")
			(options
				(clearance outline)
				(anchor circle)
			)
			(primitives
				(gr_poly
					(pts
						(arc
							(start -0.1778 0.2794)
							(mid -0.249642 0.249642)
							(end -0.2794 0.1778)
						)
						(arc
							(start -0.2794 -0.1778)
							(mid -0.249642 -0.249642)
							(end -0.1778 -0.2794)
						)
						(arc
							(start 0.1778 -0.2794)
							(mid 0.249642 -0.249642)
							(end 0.2794 -0.1778)
						)
						(arc
							(start 0.2794 0.1778)
							(mid 0.249642 0.249642)
							(end 0.1778 0.2794)
						)
					)
					(width 0)
					(fill yes)
				)
			)
		)
	)
	(footprint ""
		(layer "B.Cu")
		(at 124.2822 -66.5353 -90)
		(property "Reference" "C307"
			(at 0 0 90)
			(layer "B.SilkS")
			(hide yes)
			(effects
				(font
					(size 1.27 1.27)
				)
				(justify mirror)
			)
		)
		(property "Value" "SCD1U6D3V1KX-GP"
			(at 2.8321 -1.7399 270)
			(unlocked yes)
			(layer "B.Fab")
			(hide yes)
			(effects
				(font
					(size 1.016 1.016)
					(thickness 0.1524)
				)
				(justify mirror)
			)
		)
		(property "Device Type" "C0201H13"
			(at 2.8321 -3.2639 270)
			(unlocked yes)
			(layer "B.Fab")
			(hide yes)
			(effects
				(font
					(size 1.016 1.016)
					(thickness 0.1524)
				)
				(justify mirror)
			)
		)
		(duplicate_pad_numbers_are_jumpers no)
		(fp_rect
			(start 0.2794 0.6477)
			(end -0.2794 -0.6477)
			(stroke
				(width 0)
				(type default)
			)
			(fill no)
			(layer "B.CrtYd")
		)
		(fp_rect
			(start 0.2794 0.6477)
			(end -0.2794 -0.6477)
			(stroke
				(width 0)
				(type default)
			)
			(fill no)
			(layer "B.Fab")
		)
		(pad "1" smd custom
			(at 0 -0.2794 90)
			(size 0.0762 0.0762)
			(layers "B.Cu" "B.Mask" "B.Paste")
			(net "GB_VDDA")
			(options
				(clearance outline)
				(anchor circle)
			)
			(primitives
				(gr_poly
					(pts
						(arc
							(start 0.1524 0.127)
							(mid 0.137521 0.162921)
							(end 0.1016 0.1778)
						)
						(arc
							(start -0.1016 0.1778)
							(mid -0.137521 0.162921)
							(end -0.1524 0.127)
						)
						(arc
							(start -0.1524 -0.127)
							(mid -0.137521 -0.162921)
							(end -0.1016 -0.1778)
						)
						(arc
							(start 0.1016 -0.1778)
							(mid 0.137521 -0.162921)
							(end 0.1524 -0.127)
						)
					)
					(width 0)
					(fill yes)
				)
			)
		)
		(pad "2" smd custom
			(at 0 0.2794 90)
			(size 0.0762 0.0762)
			(layers "B.Cu" "B.Mask" "B.Paste")
			(net "GND")
			(options
				(clearance outline)
				(anchor circle)
			)
			(primitives
				(gr_poly
					(pts
						(arc
							(start 0.1524 0.127)
							(mid 0.137521 0.162921)
							(end 0.1016 0.1778)
						)
						(arc
							(start -0.1016 0.1778)
							(mid -0.137521 0.162921)
							(end -0.1524 0.127)
						)
						(arc
							(start -0.1524 -0.127)
							(mid -0.137521 -0.162921)
							(end -0.1016 -0.1778)
						)
						(arc
							(start 0.1016 -0.1778)
							(mid 0.137521 -0.162921)
							(end 0.1524 -0.127)
						)
					)
					(width 0)
					(fill yes)
				)
			)
		)
	)
	(footprint ""
		(layer "B.Cu")
		(at 202.311 -58.674)
		(property "Reference" "R304"
			(at 0 0 0)
			(layer "B.SilkS")
			(hide yes)
			(effects
				(font
					(size 1.27 1.27)
				)
				(justify mirror)
			)
		)
		(property "Value" "10KR2F-2-GP"
			(at -0.064008 -3.993896 0)
			(unlocked yes)
			(layer "B.Fab")
			(hide yes)
			(effects
				(font
					(size 1.016 1.016)
					(thickness 0.1524)
				)
				(justify mirror)
			)
		)
		(property "Device Type" "R402H16"
			(at -0.064008 -5.517896 0)
			(unlocked yes)
			(layer "B.Fab")
			(hide yes)
			(effects
				(font
					(size 1.016 1.016)
					(thickness 0.1524)
				)
				(justify mirror)
			)
		)
		(duplicate_pad_numbers_are_jumpers no)
		(fp_line
			(start -0.508 -0.9398)
			(end 0.508 -0.9398)
			(stroke
				(width 0.1524)
				(type default)
			)
			(layer "B.SilkS")
		)
		(fp_line
			(start 0.508 -0.9398)
			(end 0.508 0.9398)
			(stroke
				(width 0.1524)
				(type default)
			)
			(layer "B.SilkS")
		)
		(fp_rect
			(start 0.508 0.9398)
			(end -0.508 -0.9398)
			(stroke
				(width 0)
				(type default)
			)
			(fill no)
			(layer "B.CrtYd")
		)
		(fp_rect
			(start 0.508 0.9398)
			(end -0.508 -0.9398)
			(stroke
				(width 0)
				(type default)
			)
			(fill no)
			(layer "B.Fab")
		)
		(pad "1" smd custom
			(at 0 -0.4445 180)
			(size 0.1397 0.1397)
			(layers "B.Cu" "B.Mask" "B.Paste")
			(net "IOC_BYTE_N")
			(options
				(clearance outline)
				(anchor circle)
			)
			(primitives
				(gr_poly
					(pts
						(arc
							(start -0.1778 0.2794)
							(mid -0.249642 0.249642)
							(end -0.2794 0.1778)
						)
						(arc
							(start -0.2794 -0.1778)
							(mid -0.249642 -0.249642)
							(end -0.1778 -0.2794)
						)
						(arc
							(start 0.1778 -0.2794)
							(mid 0.249642 -0.249642)
							(end 0.2794 -0.1778)
						)
						(arc
							(start 0.2794 0.1778)
							(mid 0.249642 0.249642)
							(end 0.1778 0.2794)
						)
					)
					(width 0)
					(fill yes)
				)
			)
		)
		(pad "2" smd custom
			(at 0 0.4445 180)
			(size 0.1397 0.1397)
			(layers "B.Cu" "B.Mask" "B.Paste")
			(net "GND")
			(options
				(clearance outline)
				(anchor circle)
			)
			(primitives
				(gr_poly
					(pts
						(arc
							(start -0.1778 0.2794)
							(mid -0.249642 0.249642)
							(end -0.2794 0.1778)
						)
						(arc
							(start -0.2794 -0.1778)
							(mid -0.249642 -0.249642)
							(end -0.1778 -0.2794)
						)
						(arc
							(start 0.1778 -0.2794)
							(mid 0.249642 -0.249642)
							(end 0.2794 -0.1778)
						)
						(arc
							(start 0.2794 0.1778)
							(mid 0.249642 0.249642)
							(end 0.1778 0.2794)
						)
					)
					(width 0)
					(fill yes)
				)
			)
		)
	)
	(footprint ""
		(layer "B.Cu")
		(at 202.057 -19.939 90)
		(property "Reference" "Q6"
			(at 0 0 90)
			(layer "B.SilkS")
			(hide yes)
			(effects
				(font
					(size 1.27 1.27)
				)
				(justify mirror)
			)
		)
		(property "Value" "2N7002K-1-GP"
			(at -0.127 -8.9662 90)
			(unlocked yes)
			(layer "B.Fab")
			(hide yes)
			(effects
				(font
					(size 1.016 1.016)
					(thickness 0.1524)
				)
				(justify mirror)
			)
		)
		(property "Device Type" "SOT23DGS2D4H44"
			(at -0.127 -10.4902 90)
			(unlocked yes)
			(layer "B.Fab")
			(hide yes)
			(effects
				(font
					(size 1.016 1.016)
					(thickness 0.1524)
				)
				(justify mirror)
			)
		)
		(duplicate_pad_numbers_are_jumpers no)
		(fp_line
			(start 1.651 -1.778)
			(end 1.651 1.778)
			(stroke
				(width 0.1524)
				(type default)
			)
			(layer "B.SilkS")
		)
		(fp_line
			(start -1.651 -1.778)
			(end 1.651 -1.778)
			(stroke
				(width 0.1524)
				(type default)
			)
			(layer "B.SilkS")
		)
		(fp_line
			(start 1.651 1.778)
			(end -1.651 1.778)
			(stroke
				(width 0.1524)
				(type default)
			)
			(layer "B.SilkS")
		)
		(fp_line
			(start -1.651 1.778)
			(end -1.651 -1.778)
			(stroke
				(width 0.1524)
				(type default)
			)
			(layer "B.SilkS")
		)
		(fp_poly
			(pts
				(xy 1.778 1.8796) (xy 1.778 -1.8796) (xy -1.778 -1.8796) (xy -1.778 1.8796)
			)
			(stroke
				(width 0)
				(type default)
			)
			(fill no)
			(layer "B.CrtYd")
		)
		(fp_poly
			(pts
				(xy 1.778 1.8796) (xy 1.778 -1.8796) (xy -1.778 -1.8796) (xy -1.778 1.8796)
			)
			(stroke
				(width 0)
				(type default)
			)
			(fill no)
			(layer "B.Fab")
		)
		(pad "D" smd custom
			(at 0 -0.9525 270)
			(size 0.1905 0.1905)
			(layers "B.Cu" "B.Mask" "B.Paste")
			(net "P3V3_STBY_R")
			(options
				(clearance outline)
				(anchor circle)
			)
			(primitives
				(gr_poly
					(pts
						(arc
							(start -0.1778 -0.5715)
							(mid -0.321484 -0.511984)
							(end -0.381 -0.3683)
						)
						(arc
							(start -0.381 0.3683)
							(mid -0.321484 0.511984)
							(end -0.1778 0.5715)
						)
						(arc
							(start 0.1778 0.5715)
							(mid 0.321484 0.511984)
							(end 0.381 0.3683)
						)
						(arc
							(start 0.381 -0.3683)
							(mid 0.321484 -0.511984)
							(end 0.1778 -0.5715)
						)
					)
					(width 0)
					(fill yes)
				)
			)
		)
		(pad "G" smd custom
			(at 0.98425 0.9525 270)
			(size 0.1905 0.1905)
			(layers "B.Cu" "B.Mask" "B.Paste")
			(net "PCIE_COMP_TO_SCC_RST_0")
			(options
				(clearance outline)
				(anchor circle)
			)
			(primitives
				(gr_poly
					(pts
						(arc
							(start -0.1778 -0.5715)
							(mid -0.321484 -0.511984)
							(end -0.381 -0.3683)
						)
						(arc
							(start -0.381 0.3683)
							(mid -0.321484 0.511984)
							(end -0.1778 0.5715)
						)
						(arc
							(start 0.1778 0.5715)
							(mid 0.321484 0.511984)
							(end 0.381 0.3683)
						)
						(arc
							(start 0.381 -0.3683)
							(mid 0.321484 -0.511984)
							(end 0.1778 -0.5715)
						)
					)
					(width 0)
					(fill yes)
				)
			)
		)
		(pad "S" smd custom
			(at -0.98425 0.9525 270)
			(size 0.1905 0.1905)
			(layers "B.Cu" "B.Mask" "B.Paste")
			(net "GND")
			(options
				(clearance outline)
				(anchor circle)
			)
			(primitives
				(gr_poly
					(pts
						(arc
							(start -0.1778 -0.5715)
							(mid -0.321484 -0.511984)
							(end -0.381 -0.3683)
						)
						(arc
							(start -0.381 0.3683)
							(mid -0.321484 0.511984)
							(end -0.1778 0.5715)
						)
						(arc
							(start 0.1778 0.5715)
							(mid 0.321484 0.511984)
							(end 0.381 0.3683)
						)
						(arc
							(start 0.381 -0.3683)
							(mid 0.321484 -0.511984)
							(end 0.1778 -0.5715)
						)
					)
					(width 0)
					(fill yes)
				)
			)
		)
	)
	(footprint ""
		(layer "B.Cu")
		(at 104.267 -44.2214 180)
		(property "Reference" "C77"
			(at 0 0 0)
			(layer "B.SilkS")
			(hide yes)
			(effects
				(font
					(size 1.27 1.27)
				)
				(justify mirror)
			)
		)
		(property "Value" "SCD01U16V1KX-GP"
			(at 2.8321 -1.7399 180)
			(unlocked yes)
			(layer "B.Fab")
			(hide yes)
			(effects
				(font
					(size 1.016 1.016)
					(thickness 0.1524)
				)
				(justify mirror)
			)
		)
		(property "Device Type" "C0201H13"
			(at 2.8321 -3.2639 180)
			(unlocked yes)
			(layer "B.Fab")
			(hide yes)
			(effects
				(font
					(size 1.016 1.016)
					(thickness 0.1524)
				)
				(justify mirror)
			)
		)
		(duplicate_pad_numbers_are_jumpers no)
		(fp_rect
			(start 0.2794 0.6477)
			(end -0.2794 -0.6477)
			(stroke
				(width 0)
				(type default)
			)
			(fill no)
			(layer "B.CrtYd")
		)
		(fp_rect
			(start 0.2794 0.6477)
			(end -0.2794 -0.6477)
			(stroke
				(width 0)
				(type default)
			)
			(fill no)
			(layer "B.Fab")
		)
		(pad "1" smd custom
			(at 0 -0.2794)
			(size 0.0762 0.0762)
			(layers "B.Cu" "B.Mask" "B.Paste")
			(net "PHY_DPB_TO_SCC_21_DN")
			(options
				(clearance outline)
				(anchor circle)
			)
			(primitives
				(gr_poly
					(pts
						(arc
							(start 0.1524 0.127)
							(mid 0.137521 0.162921)
							(end 0.1016 0.1778)
						)
						(arc
							(start -0.1016 0.1778)
							(mid -0.137521 0.162921)
							(end -0.1524 0.127)
						)
						(arc
							(start -0.1524 -0.127)
							(mid -0.137521 -0.162921)
							(end -0.1016 -0.1778)
						)
						(arc
							(start 0.1016 -0.1778)
							(mid 0.137521 -0.162921)
							(end 0.1524 -0.127)
						)
					)
					(width 0)
					(fill yes)
				)
			)
		)
		(pad "2" smd custom
			(at 0 0.2794)
			(size 0.0762 0.0762)
			(layers "B.Cu" "B.Mask" "B.Paste")
			(net "PHY_DPB_TO_SCC_C_21_DN")
			(options
				(clearance outline)
				(anchor circle)
			)
			(primitives
				(gr_poly
					(pts
						(arc
							(start 0.1524 0.127)
							(mid 0.137521 0.162921)
							(end 0.1016 0.1778)
						)
						(arc
							(start -0.1016 0.1778)
							(mid -0.137521 0.162921)
							(end -0.1524 0.127)
						)
						(arc
							(start -0.1524 -0.127)
							(mid -0.137521 -0.162921)
							(end -0.1016 -0.1778)
						)
						(arc
							(start 0.1016 -0.1778)
							(mid 0.137521 -0.162921)
							(end 0.1524 -0.127)
						)
					)
					(width 0)
					(fill yes)
				)
			)
		)
	)
	(footprint ""
		(layer "B.Cu")
		(at 99.695 -44.2214 180)
		(property "Reference" "C84"
			(at 0 0 0)
			(layer "B.SilkS")
			(hide yes)
			(effects
				(font
					(size 1.27 1.27)
				)
				(justify mirror)
			)
		)
		(property "Value" "SCD01U16V1KX-GP"
			(at 2.8321 -1.7399 180)
			(unlocked yes)
			(layer "B.Fab")
			(hide yes)
			(effects
				(font
					(size 1.016 1.016)
					(thickness 0.1524)
				)
				(justify mirror)
			)
		)
		(property "Device Type" "C0201H13"
			(at 2.8321 -3.2639 180)
			(unlocked yes)
			(layer "B.Fab")
			(hide yes)
			(effects
				(font
					(size 1.016 1.016)
					(thickness 0.1524)
				)
				(justify mirror)
			)
		)
		(duplicate_pad_numbers_are_jumpers no)
		(fp_rect
			(start 0.2794 0.6477)
			(end -0.2794 -0.6477)
			(stroke
				(width 0)
				(type default)
			)
			(fill no)
			(layer "B.CrtYd")
		)
		(fp_rect
			(start 0.2794 0.6477)
			(end -0.2794 -0.6477)
			(stroke
				(width 0)
				(type default)
			)
			(fill no)
			(layer "B.Fab")
		)
		(pad "1" smd custom
			(at 0 -0.2794)
			(size 0.0762 0.0762)
			(layers "B.Cu" "B.Mask" "B.Paste")
			(net "PHY_DPB_TO_SCC_18_DN")
			(options
				(clearance outline)
				(anchor circle)
			)
			(primitives
				(gr_poly
					(pts
						(arc
							(start 0.1524 0.127)
							(mid 0.137521 0.162921)
							(end 0.1016 0.1778)
						)
						(arc
							(start -0.1016 0.1778)
							(mid -0.137521 0.162921)
							(end -0.1524 0.127)
						)
						(arc
							(start -0.1524 -0.127)
							(mid -0.137521 -0.162921)
							(end -0.1016 -0.1778)
						)
						(arc
							(start 0.1016 -0.1778)
							(mid 0.137521 -0.162921)
							(end 0.1524 -0.127)
						)
					)
					(width 0)
					(fill yes)
				)
			)
		)
		(pad "2" smd custom
			(at 0 0.2794)
			(size 0.0762 0.0762)
			(layers "B.Cu" "B.Mask" "B.Paste")
			(net "PHY_DPB_TO_SCC_C_18_DN")
			(options
				(clearance outline)
				(anchor circle)
			)
			(primitives
				(gr_poly
					(pts
						(arc
							(start 0.1524 0.127)
							(mid 0.137521 0.162921)
							(end 0.1016 0.1778)
						)
						(arc
							(start -0.1016 0.1778)
							(mid -0.137521 0.162921)
							(end -0.1524 0.127)
						)
						(arc
							(start -0.1524 -0.127)
							(mid -0.137521 -0.162921)
							(end -0.1016 -0.1778)
						)
						(arc
							(start 0.1016 -0.1778)
							(mid 0.137521 -0.162921)
							(end 0.1524 -0.127)
						)
					)
					(width 0)
					(fill yes)
				)
			)
		)
	)
	(footprint ""
		(layer "B.Cu")
		(at 187.87872 -110.14456 180)
		(property "Reference" "D2"
			(at 0 0 0)
			(layer "B.SilkS")
			(hide yes)
			(effects
				(font
					(size 1.27 1.27)
				)
				(justify mirror)
			)
		)
		(property "Value" "RB551V30-GP"
			(at 0 -6.7818 180)
			(unlocked yes)
			(layer "B.Fab")
			(hide yes)
			(effects
				(font
					(size 1.016 1.016)
					(thickness 0.1524)
				)
				(justify mirror)
			)
		)
		(property "Device Type" "SOD323AKH38"
			(at 0 -8.6868 180)
			(unlocked yes)
			(layer "B.Fab")
			(hide yes)
			(effects
				(font
					(size 1.016 1.016)
					(thickness 0.1524)
				)
				(justify mirror)
			)
		)
		(duplicate_pad_numbers_are_jumpers no)
		(fp_line
			(start 0.889 2.159)
			(end 0.889 -1.9304)
			(stroke
				(width 0.1524)
				(type default)
			)
			(layer "B.SilkS")
		)
		(fp_line
			(start 0.889 -1.9304)
			(end -0.889 -1.9304)
			(stroke
				(width 0.1524)
				(type default)
			)
			(layer "B.SilkS")
		)
		(fp_line
			(start -0.762 2.0574)
			(end 0.762 2.0574)
			(stroke
				(width 0.508)
				(type default)
			)
			(layer "B.SilkS")
		)
		(fp_line
			(start -0.889 2.159)
			(end 0.889 2.159)
			(stroke
				(width 0.1524)
				(type default)
			)
			(layer "B.SilkS")
		)
		(fp_line
			(start -0.889 -1.9304)
			(end -0.889 2.159)
			(stroke
				(width 0.1524)
				(type default)
			)
			(layer "B.SilkS")
		)
		(fp_rect
			(start 1.016 2.3114)
			(end -1.016 -2.0066)
			(stroke
				(width 0)
				(type default)
			)
			(fill no)
			(layer "B.CrtYd")
		)
		(fp_poly
			(pts
				(xy 1.016 -2.0066) (xy -1.016 -2.0066) (xy -1.016 2.3114) (xy 1.016 2.3114)
			)
			(stroke
				(width 0)
				(type default)
			)
			(fill no)
			(layer "B.Fab")
		)
		(pad "A" smd rect
			(at 0 -1.143)
			(size 0.5588 1.016)
			(layers "B.Cu" "B.Mask" "B.Paste")
			(net "P1V8_C_S")
		)
		(pad "K" smd rect
			(at 0 1.143)
			(size 0.5588 1.016)
			(layers "B.Cu" "B.Mask" "B.Paste")
			(net "P0V9_PG")
		)
	)
	(footprint ""
		(layer "B.Cu")
		(at 80.463644 -98.613468)
		(property "Reference" "R149"
			(at 0 0 0)
			(layer "B.SilkS")
			(hide yes)
			(effects
				(font
					(size 1.27 1.27)
				)
				(justify mirror)
			)
		)
		(property "Value" "10KR2F-2-GP"
			(at -0.064008 -3.993896 0)
			(unlocked yes)
			(layer "B.Fab")
			(hide yes)
			(effects
				(font
					(size 1.016 1.016)
					(thickness 0.1524)
				)
				(justify mirror)
			)
		)
		(property "Device Type" "R402H16"
			(at -0.064008 -5.517896 0)
			(unlocked yes)
			(layer "B.Fab")
			(hide yes)
			(effects
				(font
					(size 1.016 1.016)
					(thickness 0.1524)
				)
				(justify mirror)
			)
		)
		(duplicate_pad_numbers_are_jumpers no)
		(fp_line
			(start -0.508 -0.9398)
			(end 0.508 -0.9398)
			(stroke
				(width 0.1524)
				(type default)
			)
			(layer "B.SilkS")
		)
		(fp_line
			(start 0.508 -0.9398)
			(end 0.508 0.9398)
			(stroke
				(width 0.1524)
				(type default)
			)
			(layer "B.SilkS")
		)
		(fp_rect
			(start 0.508 0.9398)
			(end -0.508 -0.9398)
			(stroke
				(width 0)
				(type default)
			)
			(fill no)
			(layer "B.CrtYd")
		)
		(fp_rect
			(start 0.508 0.9398)
			(end -0.508 -0.9398)
			(stroke
				(width 0)
				(type default)
			)
			(fill no)
			(layer "B.Fab")
		)
		(pad "1" smd custom
			(at 0 -0.4445 180)
			(size 0.1397 0.1397)
			(layers "B.Cu" "B.Mask" "B.Paste")
			(net "P1V8_E")
			(options
				(clearance outline)
				(anchor circle)
			)
			(primitives
				(gr_poly
					(pts
						(arc
							(start -0.1778 0.2794)
							(mid -0.249642 0.249642)
							(end -0.2794 0.1778)
						)
						(arc
							(start -0.2794 -0.1778)
							(mid -0.249642 -0.249642)
							(end -0.1778 -0.2794)
						)
						(arc
							(start 0.1778 -0.2794)
							(mid 0.249642 -0.249642)
							(end 0.2794 -0.1778)
						)
						(arc
							(start 0.2794 0.1778)
							(mid 0.249642 0.249642)
							(end 0.1778 0.2794)
						)
					)
					(width 0)
					(fill yes)
				)
			)
		)
		(pad "2" smd custom
			(at 0 0.4445 180)
			(size 0.1397 0.1397)
			(layers "B.Cu" "B.Mask" "B.Paste")
			(net "EXP_WP_N")
			(options
				(clearance outline)
				(anchor circle)
			)
			(primitives
				(gr_poly
					(pts
						(arc
							(start -0.1778 0.2794)
							(mid -0.249642 0.249642)
							(end -0.2794 0.1778)
						)
						(arc
							(start -0.2794 -0.1778)
							(mid -0.249642 -0.249642)
							(end -0.1778 -0.2794)
						)
						(arc
							(start 0.1778 -0.2794)
							(mid 0.249642 -0.249642)
							(end 0.2794 -0.1778)
						)
						(arc
							(start 0.2794 0.1778)
							(mid 0.249642 0.249642)
							(end 0.1778 0.2794)
						)
					)
					(width 0)
					(fill yes)
				)
			)
		)
	)
	(footprint ""
		(layer "B.Cu")
		(at 122.4788 -60.4774 -90)
		(property "Reference" "C590"
			(at 0 0 90)
			(layer "B.SilkS")
			(hide yes)
			(effects
				(font
					(size 1.27 1.27)
				)
				(justify mirror)
			)
		)
		(property "Value" "SCD1U6D3V1KX-GP"
			(at 2.8321 -1.7399 270)
			(unlocked yes)
			(layer "B.Fab")
			(hide yes)
			(effects
				(font
					(size 1.016 1.016)
					(thickness 0.1524)
				)
				(justify mirror)
			)
		)
		(property "Device Type" "C0201H13"
			(at 2.8321 -3.2639 270)
			(unlocked yes)
			(layer "B.Fab")
			(hide yes)
			(effects
				(font
					(size 1.016 1.016)
					(thickness 0.1524)
				)
				(justify mirror)
			)
		)
		(duplicate_pad_numbers_are_jumpers no)
		(fp_rect
			(start 0.2794 0.6477)
			(end -0.2794 -0.6477)
			(stroke
				(width 0)
				(type default)
			)
			(fill no)
			(layer "B.CrtYd")
		)
		(fp_rect
			(start 0.2794 0.6477)
			(end -0.2794 -0.6477)
			(stroke
				(width 0)
				(type default)
			)
			(fill no)
			(layer "B.Fab")
		)
		(pad "1" smd custom
			(at 0 -0.2794 90)
			(size 0.0762 0.0762)
			(layers "B.Cu" "B.Mask" "B.Paste")
			(net "GB_VDDA")
			(options
				(clearance outline)
				(anchor circle)
			)
			(primitives
				(gr_poly
					(pts
						(arc
							(start 0.1524 0.127)
							(mid 0.137521 0.162921)
							(end 0.1016 0.1778)
						)
						(arc
							(start -0.1016 0.1778)
							(mid -0.137521 0.162921)
							(end -0.1524 0.127)
						)
						(arc
							(start -0.1524 -0.127)
							(mid -0.137521 -0.162921)
							(end -0.1016 -0.1778)
						)
						(arc
							(start 0.1016 -0.1778)
							(mid 0.137521 -0.162921)
							(end 0.1524 -0.127)
						)
					)
					(width 0)
					(fill yes)
				)
			)
		)
		(pad "2" smd custom
			(at 0 0.2794 90)
			(size 0.0762 0.0762)
			(layers "B.Cu" "B.Mask" "B.Paste")
			(net "GND")
			(options
				(clearance outline)
				(anchor circle)
			)
			(primitives
				(gr_poly
					(pts
						(arc
							(start 0.1524 0.127)
							(mid 0.137521 0.162921)
							(end 0.1016 0.1778)
						)
						(arc
							(start -0.1016 0.1778)
							(mid -0.137521 0.162921)
							(end -0.1524 0.127)
						)
						(arc
							(start -0.1524 -0.127)
							(mid -0.137521 -0.162921)
							(end -0.1016 -0.1778)
						)
						(arc
							(start 0.1016 -0.1778)
							(mid 0.137521 -0.162921)
							(end 0.1524 -0.127)
						)
					)
					(width 0)
					(fill yes)
				)
			)
		)
	)
	(footprint ""
		(layer "B.Cu")
		(at 126.5174 -78.49108 -90)
		(property "Reference" "C151"
			(at 0 0 90)
			(layer "B.SilkS")
			(hide yes)
			(effects
				(font
					(size 1.27 1.27)
				)
				(justify mirror)
			)
		)
		(property "Value" "SCD1U6D3V1KX-GP"
			(at 2.8321 -1.7399 270)
			(unlocked yes)
			(layer "B.Fab")
			(hide yes)
			(effects
				(font
					(size 1.016 1.016)
					(thickness 0.1524)
				)
				(justify mirror)
			)
		)
		(property "Device Type" "C0201H13"
			(at 2.8321 -3.2639 270)
			(unlocked yes)
			(layer "B.Fab")
			(hide yes)
			(effects
				(font
					(size 1.016 1.016)
					(thickness 0.1524)
				)
				(justify mirror)
			)
		)
		(duplicate_pad_numbers_are_jumpers no)
		(fp_rect
			(start 0.2794 0.6477)
			(end -0.2794 -0.6477)
			(stroke
				(width 0)
				(type default)
			)
			(fill no)
			(layer "B.CrtYd")
		)
		(fp_rect
			(start 0.2794 0.6477)
			(end -0.2794 -0.6477)
			(stroke
				(width 0)
				(type default)
			)
			(fill no)
			(layer "B.Fab")
		)
		(pad "1" smd custom
			(at 0 -0.2794 90)
			(size 0.0762 0.0762)
			(layers "B.Cu" "B.Mask" "B.Paste")
			(net "P1V8_E")
			(options
				(clearance outline)
				(anchor circle)
			)
			(primitives
				(gr_poly
					(pts
						(arc
							(start 0.1524 0.127)
							(mid 0.137521 0.162921)
							(end 0.1016 0.1778)
						)
						(arc
							(start -0.1016 0.1778)
							(mid -0.137521 0.162921)
							(end -0.1524 0.127)
						)
						(arc
							(start -0.1524 -0.127)
							(mid -0.137521 -0.162921)
							(end -0.1016 -0.1778)
						)
						(arc
							(start 0.1016 -0.1778)
							(mid 0.137521 -0.162921)
							(end 0.1524 -0.127)
						)
					)
					(width 0)
					(fill yes)
				)
			)
		)
		(pad "2" smd custom
			(at 0 0.2794 90)
			(size 0.0762 0.0762)
			(layers "B.Cu" "B.Mask" "B.Paste")
			(net "GND")
			(options
				(clearance outline)
				(anchor circle)
			)
			(primitives
				(gr_poly
					(pts
						(arc
							(start 0.1524 0.127)
							(mid 0.137521 0.162921)
							(end 0.1016 0.1778)
						)
						(arc
							(start -0.1016 0.1778)
							(mid -0.137521 0.162921)
							(end -0.1524 0.127)
						)
						(arc
							(start -0.1524 -0.127)
							(mid -0.137521 -0.162921)
							(end -0.1016 -0.1778)
						)
						(arc
							(start 0.1016 -0.1778)
							(mid 0.137521 -0.162921)
							(end 0.1524 -0.127)
						)
					)
					(width 0)
					(fill yes)
				)
			)
		)
	)
	(footprint ""
		(layer "B.Cu")
		(at 71.882 -73.152)
		(property "Reference" "R246"
			(at 0 0 0)
			(layer "B.SilkS")
			(hide yes)
			(effects
				(font
					(size 1.27 1.27)
				)
				(justify mirror)
			)
		)
		(property "Value" "10KR2F-2-GP"
			(at -0.064008 -3.993896 0)
			(unlocked yes)
			(layer "B.Fab")
			(hide yes)
			(effects
				(font
					(size 1.016 1.016)
					(thickness 0.1524)
				)
				(justify mirror)
			)
		)
		(property "Device Type" "R402H16"
			(at -0.064008 -5.517896 0)
			(unlocked yes)
			(layer "B.Fab")
			(hide yes)
			(effects
				(font
					(size 1.016 1.016)
					(thickness 0.1524)
				)
				(justify mirror)
			)
		)
		(duplicate_pad_numbers_are_jumpers no)
		(fp_line
			(start -0.508 -0.9398)
			(end 0.508 -0.9398)
			(stroke
				(width 0.1524)
				(type default)
			)
			(layer "B.SilkS")
		)
		(fp_line
			(start 0.508 -0.9398)
			(end 0.508 0.9398)
			(stroke
				(width 0.1524)
				(type default)
			)
			(layer "B.SilkS")
		)
		(fp_rect
			(start 0.508 0.9398)
			(end -0.508 -0.9398)
			(stroke
				(width 0)
				(type default)
			)
			(fill no)
			(layer "B.CrtYd")
		)
		(fp_rect
			(start 0.508 0.9398)
			(end -0.508 -0.9398)
			(stroke
				(width 0)
				(type default)
			)
			(fill no)
			(layer "B.Fab")
		)
		(pad "1" smd custom
			(at 0 -0.4445 180)
			(size 0.1397 0.1397)
			(layers "B.Cu" "B.Mask" "B.Paste")
			(net "P1V8_E")
			(options
				(clearance outline)
				(anchor circle)
			)
			(primitives
				(gr_poly
					(pts
						(arc
							(start -0.1778 0.2794)
							(mid -0.249642 0.249642)
							(end -0.2794 0.1778)
						)
						(arc
							(start -0.2794 -0.1778)
							(mid -0.249642 -0.249642)
							(end -0.1778 -0.2794)
						)
						(arc
							(start 0.1778 -0.2794)
							(mid 0.249642 -0.249642)
							(end 0.2794 -0.1778)
						)
						(arc
							(start 0.2794 0.1778)
							(mid 0.249642 0.249642)
							(end 0.1778 0.2794)
						)
					)
					(width 0)
					(fill yes)
				)
			)
		)
		(pad "2" smd custom
			(at 0 0.4445 180)
			(size 0.1397 0.1397)
			(layers "B.Cu" "B.Mask" "B.Paste")
			(net "EXP_BYTE_N")
			(options
				(clearance outline)
				(anchor circle)
			)
			(primitives
				(gr_poly
					(pts
						(arc
							(start -0.1778 0.2794)
							(mid -0.249642 0.249642)
							(end -0.2794 0.1778)
						)
						(arc
							(start -0.2794 -0.1778)
							(mid -0.249642 -0.249642)
							(end -0.1778 -0.2794)
						)
						(arc
							(start 0.1778 -0.2794)
							(mid 0.249642 -0.249642)
							(end 0.2794 -0.1778)
						)
						(arc
							(start 0.2794 0.1778)
							(mid 0.249642 0.249642)
							(end 0.1778 0.2794)
						)
					)
					(width 0)
					(fill yes)
				)
			)
		)
	)
	(footprint ""
		(layer "B.Cu")
		(at 96.497394 -50.366168 90)
		(property "Reference" "C88"
			(at 0 0 90)
			(layer "B.SilkS")
			(hide yes)
			(effects
				(font
					(size 1.27 1.27)
				)
				(justify mirror)
			)
		)
		(property "Value" "SCD01U16V1KX-GP"
			(at 2.8321 -1.7399 90)
			(unlocked yes)
			(layer "B.Fab")
			(hide yes)
			(effects
				(font
					(size 1.016 1.016)
					(thickness 0.1524)
				)
				(justify mirror)
			)
		)
		(property "Device Type" "C0201H13"
			(at 2.8321 -3.2639 90)
			(unlocked yes)
			(layer "B.Fab")
			(hide yes)
			(effects
				(font
					(size 1.016 1.016)
					(thickness 0.1524)
				)
				(justify mirror)
			)
		)
		(duplicate_pad_numbers_are_jumpers no)
		(fp_rect
			(start 0.2794 0.6477)
			(end -0.2794 -0.6477)
			(stroke
				(width 0)
				(type default)
			)
			(fill no)
			(layer "B.CrtYd")
		)
		(fp_rect
			(start 0.2794 0.6477)
			(end -0.2794 -0.6477)
			(stroke
				(width 0)
				(type default)
			)
			(fill no)
			(layer "B.Fab")
		)
		(pad "1" smd custom
			(at 0 -0.2794 270)
			(size 0.0762 0.0762)
			(layers "B.Cu" "B.Mask" "B.Paste")
			(net "PHY_DPB_TO_SCC_15_DP")
			(options
				(clearance outline)
				(anchor circle)
			)
			(primitives
				(gr_poly
					(pts
						(arc
							(start 0.1524 0.127)
							(mid 0.137521 0.162921)
							(end 0.1016 0.1778)
						)
						(arc
							(start -0.1016 0.1778)
							(mid -0.137521 0.162921)
							(end -0.1524 0.127)
						)
						(arc
							(start -0.1524 -0.127)
							(mid -0.137521 -0.162921)
							(end -0.1016 -0.1778)
						)
						(arc
							(start 0.1016 -0.1778)
							(mid 0.137521 -0.162921)
							(end 0.1524 -0.127)
						)
					)
					(width 0)
					(fill yes)
				)
			)
		)
		(pad "2" smd custom
			(at 0 0.2794 270)
			(size 0.0762 0.0762)
			(layers "B.Cu" "B.Mask" "B.Paste")
			(net "PHY_DPB_TO_SCC_C_15_DP")
			(options
				(clearance outline)
				(anchor circle)
			)
			(primitives
				(gr_poly
					(pts
						(arc
							(start 0.1524 0.127)
							(mid 0.137521 0.162921)
							(end 0.1016 0.1778)
						)
						(arc
							(start -0.1016 0.1778)
							(mid -0.137521 0.162921)
							(end -0.1524 0.127)
						)
						(arc
							(start -0.1524 -0.127)
							(mid -0.137521 -0.162921)
							(end -0.1016 -0.1778)
						)
						(arc
							(start 0.1016 -0.1778)
							(mid 0.137521 -0.162921)
							(end 0.1524 -0.127)
						)
					)
					(width 0)
					(fill yes)
				)
			)
		)
	)
	(footprint ""
		(layer "B.Cu")
		(at 130.82397 -44.379388 180)
		(property "Reference" "C30"
			(at 0 0 0)
			(layer "B.SilkS")
			(hide yes)
			(effects
				(font
					(size 1.27 1.27)
				)
				(justify mirror)
			)
		)
		(property "Value" "SCD01U16V1KX-GP"
			(at 2.8321 -1.7399 180)
			(unlocked yes)
			(layer "B.Fab")
			(hide yes)
			(effects
				(font
					(size 1.016 1.016)
					(thickness 0.1524)
				)
				(justify mirror)
			)
		)
		(property "Device Type" "C0201H13"
			(at 2.8321 -3.2639 180)
			(unlocked yes)
			(layer "B.Fab")
			(hide yes)
			(effects
				(font
					(size 1.016 1.016)
					(thickness 0.1524)
				)
				(justify mirror)
			)
		)
		(duplicate_pad_numbers_are_jumpers no)
		(fp_rect
			(start 0.2794 0.6477)
			(end -0.2794 -0.6477)
			(stroke
				(width 0)
				(type default)
			)
			(fill no)
			(layer "B.CrtYd")
		)
		(fp_rect
			(start 0.2794 0.6477)
			(end -0.2794 -0.6477)
			(stroke
				(width 0)
				(type default)
			)
			(fill no)
			(layer "B.Fab")
		)
		(pad "1" smd custom
			(at 0 -0.2794)
			(size 0.0762 0.0762)
			(layers "B.Cu" "B.Mask" "B.Paste")
			(net "PHY_DPB_TO_SCC_29_DN")
			(options
				(clearance outline)
				(anchor circle)
			)
			(primitives
				(gr_poly
					(pts
						(arc
							(start 0.1524 0.127)
							(mid 0.137521 0.162921)
							(end 0.1016 0.1778)
						)
						(arc
							(start -0.1016 0.1778)
							(mid -0.137521 0.162921)
							(end -0.1524 0.127)
						)
						(arc
							(start -0.1524 -0.127)
							(mid -0.137521 -0.162921)
							(end -0.1016 -0.1778)
						)
						(arc
							(start 0.1016 -0.1778)
							(mid 0.137521 -0.162921)
							(end 0.1524 -0.127)
						)
					)
					(width 0)
					(fill yes)
				)
			)
		)
		(pad "2" smd custom
			(at 0 0.2794)
			(size 0.0762 0.0762)
			(layers "B.Cu" "B.Mask" "B.Paste")
			(net "PHY_DPB_TO_SCC_C_29_DN")
			(options
				(clearance outline)
				(anchor circle)
			)
			(primitives
				(gr_poly
					(pts
						(arc
							(start 0.1524 0.127)
							(mid 0.137521 0.162921)
							(end 0.1016 0.1778)
						)
						(arc
							(start -0.1016 0.1778)
							(mid -0.137521 0.162921)
							(end -0.1524 0.127)
						)
						(arc
							(start -0.1524 -0.127)
							(mid -0.137521 -0.162921)
							(end -0.1016 -0.1778)
						)
						(arc
							(start 0.1016 -0.1778)
							(mid 0.137521 -0.162921)
							(end 0.1524 -0.127)
						)
					)
					(width 0)
					(fill yes)
				)
			)
		)
	)
	(footprint ""
		(layer "B.Cu")
		(at 166.847012 -40.914066)
		(property "Reference" "TP81"
			(at 0 0 0)
			(layer "B.SilkS")
			(hide yes)
			(effects
				(font
					(size 1.27 1.27)
				)
				(justify mirror)
			)
		)
		(property "Value" "TPAD28-2-GP"
			(at 0.0127 -1.6637 0)
			(unlocked yes)
			(layer "B.Fab")
			(hide yes)
			(effects
				(font
					(size 1.016 1.016)
					(thickness 0.1524)
				)
				(justify mirror)
			)
		)
		(property "Device Type" "TPAD28"
			(at 0.0127 -3.1877 0)
			(unlocked yes)
			(layer "B.Fab")
			(hide yes)
			(effects
				(font
					(size 1.016 1.016)
					(thickness 0.1524)
				)
				(justify mirror)
			)
		)
		(duplicate_pad_numbers_are_jumpers no)
		(fp_poly
			(pts
				(arc
					(start 0.3556 0)
					(mid -0.3556 0)
					(end 0.3556 0)
				)
			)
			(stroke
				(width 0)
				(type default)
			)
			(fill no)
			(layer "B.CrtYd")
		)
		(fp_poly
			(pts
				(arc
					(start 0.6096 0)
					(mid -0.6096 0)
					(end 0.6096 0)
				)
			)
			(stroke
				(width 0)
				(type default)
			)
			(fill no)
			(layer "B.Fab")
		)
		(pad "1" smd circle
			(at 0 0 180)
			(size 0.7112 0.7112)
			(layers "B.Cu" "B.Mask" "B.Paste")
			(net "SIO_DIN_0")
		)
	)
	(footprint ""
		(layer "B.Cu")
		(at 137.4648 -70.8914 -90)
		(property "Reference" "C14"
			(at 0 0 90)
			(layer "B.SilkS")
			(hide yes)
			(effects
				(font
					(size 1.27 1.27)
				)
				(justify mirror)
			)
		)
		(property "Value" "SCD01U16V1KX-GP"
			(at 2.8321 -1.7399 270)
			(unlocked yes)
			(layer "B.Fab")
			(hide yes)
			(effects
				(font
					(size 1.016 1.016)
					(thickness 0.1524)
				)
				(justify mirror)
			)
		)
		(property "Device Type" "C0201H13"
			(at 2.8321 -3.2639 270)
			(unlocked yes)
			(layer "B.Fab")
			(hide yes)
			(effects
				(font
					(size 1.016 1.016)
					(thickness 0.1524)
				)
				(justify mirror)
			)
		)
		(duplicate_pad_numbers_are_jumpers no)
		(fp_rect
			(start 0.2794 0.6477)
			(end -0.2794 -0.6477)
			(stroke
				(width 0)
				(type default)
			)
			(fill no)
			(layer "B.CrtYd")
		)
		(fp_rect
			(start 0.2794 0.6477)
			(end -0.2794 -0.6477)
			(stroke
				(width 0)
				(type default)
			)
			(fill no)
			(layer "B.Fab")
		)
		(pad "1" smd custom
			(at 0 -0.2794 90)
			(size 0.0762 0.0762)
			(layers "B.Cu" "B.Mask" "B.Paste")
			(net "PHY_DPB_TO_SCC_5_DN")
			(options
				(clearance outline)
				(anchor circle)
			)
			(primitives
				(gr_poly
					(pts
						(arc
							(start 0.1524 0.127)
							(mid 0.137521 0.162921)
							(end 0.1016 0.1778)
						)
						(arc
							(start -0.1016 0.1778)
							(mid -0.137521 0.162921)
							(end -0.1524 0.127)
						)
						(arc
							(start -0.1524 -0.127)
							(mid -0.137521 -0.162921)
							(end -0.1016 -0.1778)
						)
						(arc
							(start 0.1016 -0.1778)
							(mid 0.137521 -0.162921)
							(end 0.1524 -0.127)
						)
					)
					(width 0)
					(fill yes)
				)
			)
		)
		(pad "2" smd custom
			(at 0 0.2794 90)
			(size 0.0762 0.0762)
			(layers "B.Cu" "B.Mask" "B.Paste")
			(net "PHY_DPB_TO_SCC_C_5_DN")
			(options
				(clearance outline)
				(anchor circle)
			)
			(primitives
				(gr_poly
					(pts
						(arc
							(start 0.1524 0.127)
							(mid 0.137521 0.162921)
							(end 0.1016 0.1778)
						)
						(arc
							(start -0.1016 0.1778)
							(mid -0.137521 0.162921)
							(end -0.1524 0.127)
						)
						(arc
							(start -0.1524 -0.127)
							(mid -0.137521 -0.162921)
							(end -0.1016 -0.1778)
						)
						(arc
							(start 0.1016 -0.1778)
							(mid 0.137521 -0.162921)
							(end 0.1524 -0.127)
						)
					)
					(width 0)
					(fill yes)
				)
			)
		)
	)
	(footprint ""
		(layer "B.Cu")
		(at 138.4808 -89.6874)
		(property "Reference" "R53"
			(at 0 0 0)
			(layer "B.SilkS")
			(hide yes)
			(effects
				(font
					(size 1.27 1.27)
				)
				(justify mirror)
			)
		)
		(property "Value" "4K7R2F-GP"
			(at -0.064008 -3.993896 0)
			(unlocked yes)
			(layer "B.Fab")
			(hide yes)
			(effects
				(font
					(size 1.016 1.016)
					(thickness 0.1524)
				)
				(justify mirror)
			)
		)
		(property "Device Type" "R402H16"
			(at -0.064008 -5.517896 0)
			(unlocked yes)
			(layer "B.Fab")
			(hide yes)
			(effects
				(font
					(size 1.016 1.016)
					(thickness 0.1524)
				)
				(justify mirror)
			)
		)
		(duplicate_pad_numbers_are_jumpers no)
		(fp_line
			(start -0.508 -0.9398)
			(end 0.508 -0.9398)
			(stroke
				(width 0.1524)
				(type default)
			)
			(layer "B.SilkS")
		)
		(fp_line
			(start 0.508 -0.9398)
			(end 0.508 0.9398)
			(stroke
				(width 0.1524)
				(type default)
			)
			(layer "B.SilkS")
		)
		(fp_rect
			(start 0.508 0.9398)
			(end -0.508 -0.9398)
			(stroke
				(width 0)
				(type default)
			)
			(fill no)
			(layer "B.CrtYd")
		)
		(fp_rect
			(start 0.508 0.9398)
			(end -0.508 -0.9398)
			(stroke
				(width 0)
				(type default)
			)
			(fill no)
			(layer "B.Fab")
		)
		(pad "1" smd custom
			(at 0 -0.4445 180)
			(size 0.1397 0.1397)
			(layers "B.Cu" "B.Mask" "B.Paste")
			(net "P1V8_E")
			(options
				(clearance outline)
				(anchor circle)
			)
			(primitives
				(gr_poly
					(pts
						(arc
							(start -0.1778 0.2794)
							(mid -0.249642 0.249642)
							(end -0.2794 0.1778)
						)
						(arc
							(start -0.2794 -0.1778)
							(mid -0.249642 -0.249642)
							(end -0.1778 -0.2794)
						)
						(arc
							(start 0.1778 -0.2794)
							(mid 0.249642 -0.249642)
							(end 0.2794 -0.1778)
						)
						(arc
							(start 0.2794 0.1778)
							(mid 0.249642 0.249642)
							(end 0.1778 0.2794)
						)
					)
					(width 0)
					(fill yes)
				)
			)
		)
		(pad "2" smd custom
			(at 0 0.4445 180)
			(size 0.1397 0.1397)
			(layers "B.Cu" "B.Mask" "B.Paste")
			(net "I2C_SCC_SDA2_LS")
			(options
				(clearance outline)
				(anchor circle)
			)
			(primitives
				(gr_poly
					(pts
						(arc
							(start -0.1778 0.2794)
							(mid -0.249642 0.249642)
							(end -0.2794 0.1778)
						)
						(arc
							(start -0.2794 -0.1778)
							(mid -0.249642 -0.249642)
							(end -0.1778 -0.2794)
						)
						(arc
							(start 0.1778 -0.2794)
							(mid 0.249642 -0.249642)
							(end 0.2794 -0.1778)
						)
						(arc
							(start 0.2794 0.1778)
							(mid 0.249642 0.249642)
							(end 0.1778 0.2794)
						)
					)
					(width 0)
					(fill yes)
				)
			)
		)
	)
	(footprint ""
		(layer "B.Cu")
		(at 125.998986 -51.995578)
		(property "Reference" "C289"
			(at 0 0 0)
			(layer "B.SilkS")
			(hide yes)
			(effects
				(font
					(size 1.27 1.27)
				)
				(justify mirror)
			)
		)
		(property "Value" "SCD1U6D3V1KX-GP"
			(at 2.8321 -1.7399 0)
			(unlocked yes)
			(layer "B.Fab")
			(hide yes)
			(effects
				(font
					(size 1.016 1.016)
					(thickness 0.1524)
				)
				(justify mirror)
			)
		)
		(property "Device Type" "C0201H13"
			(at 2.8321 -3.2639 0)
			(unlocked yes)
			(layer "B.Fab")
			(hide yes)
			(effects
				(font
					(size 1.016 1.016)
					(thickness 0.1524)
				)
				(justify mirror)
			)
		)
		(duplicate_pad_numbers_are_jumpers no)
		(fp_rect
			(start 0.2794 0.6477)
			(end -0.2794 -0.6477)
			(stroke
				(width 0)
				(type default)
			)
			(fill no)
			(layer "B.CrtYd")
		)
		(fp_rect
			(start 0.2794 0.6477)
			(end -0.2794 -0.6477)
			(stroke
				(width 0)
				(type default)
			)
			(fill no)
			(layer "B.Fab")
		)
		(pad "1" smd custom
			(at 0 -0.2794 180)
			(size 0.0762 0.0762)
			(layers "B.Cu" "B.Mask" "B.Paste")
			(net "GB_VDDA")
			(options
				(clearance outline)
				(anchor circle)
			)
			(primitives
				(gr_poly
					(pts
						(arc
							(start 0.1524 0.127)
							(mid 0.137521 0.162921)
							(end 0.1016 0.1778)
						)
						(arc
							(start -0.1016 0.1778)
							(mid -0.137521 0.162921)
							(end -0.1524 0.127)
						)
						(arc
							(start -0.1524 -0.127)
							(mid -0.137521 -0.162921)
							(end -0.1016 -0.1778)
						)
						(arc
							(start 0.1016 -0.1778)
							(mid 0.137521 -0.162921)
							(end 0.1524 -0.127)
						)
					)
					(width 0)
					(fill yes)
				)
			)
		)
		(pad "2" smd custom
			(at 0 0.2794 180)
			(size 0.0762 0.0762)
			(layers "B.Cu" "B.Mask" "B.Paste")
			(net "GND")
			(options
				(clearance outline)
				(anchor circle)
			)
			(primitives
				(gr_poly
					(pts
						(arc
							(start 0.1524 0.127)
							(mid 0.137521 0.162921)
							(end 0.1016 0.1778)
						)
						(arc
							(start -0.1016 0.1778)
							(mid -0.137521 0.162921)
							(end -0.1524 0.127)
						)
						(arc
							(start -0.1524 -0.127)
							(mid -0.137521 -0.162921)
							(end -0.1016 -0.1778)
						)
						(arc
							(start 0.1016 -0.1778)
							(mid 0.137521 -0.162921)
							(end 0.1524 -0.127)
						)
					)
					(width 0)
					(fill yes)
				)
			)
		)
	)
	(footprint ""
		(layer "B.Cu")
		(at 175.043846 -20.954492)
		(property "Reference" "C321"
			(at 0 0 0)
			(layer "B.SilkS")
			(hide yes)
			(effects
				(font
					(size 1.27 1.27)
				)
				(justify mirror)
			)
		)
		(property "Value" "SCD22U10V1KX-GP"
			(at 2.8321 -1.7399 0)
			(unlocked yes)
			(layer "B.Fab")
			(hide yes)
			(effects
				(font
					(size 1.016 1.016)
					(thickness 0.1524)
				)
				(justify mirror)
			)
		)
		(property "Device Type" "C0201H13"
			(at 2.8321 -3.2639 0)
			(unlocked yes)
			(layer "B.Fab")
			(hide yes)
			(effects
				(font
					(size 1.016 1.016)
					(thickness 0.1524)
				)
				(justify mirror)
			)
		)
		(duplicate_pad_numbers_are_jumpers no)
		(fp_rect
			(start 0.2794 0.6477)
			(end -0.2794 -0.6477)
			(stroke
				(width 0)
				(type default)
			)
			(fill no)
			(layer "B.CrtYd")
		)
		(fp_rect
			(start 0.2794 0.6477)
			(end -0.2794 -0.6477)
			(stroke
				(width 0)
				(type default)
			)
			(fill no)
			(layer "B.Fab")
		)
		(pad "1" smd custom
			(at 0 -0.2794 180)
			(size 0.0762 0.0762)
			(layers "B.Cu" "B.Mask" "B.Paste")
			(net "PCIE_SCC_TO_COMP_C_5_DP")
			(options
				(clearance outline)
				(anchor circle)
			)
			(primitives
				(gr_poly
					(pts
						(arc
							(start 0.1524 0.127)
							(mid 0.137521 0.162921)
							(end 0.1016 0.1778)
						)
						(arc
							(start -0.1016 0.1778)
							(mid -0.137521 0.162921)
							(end -0.1524 0.127)
						)
						(arc
							(start -0.1524 -0.127)
							(mid -0.137521 -0.162921)
							(end -0.1016 -0.1778)
						)
						(arc
							(start 0.1016 -0.1778)
							(mid 0.137521 -0.162921)
							(end 0.1524 -0.127)
						)
					)
					(width 0)
					(fill yes)
				)
			)
		)
		(pad "2" smd custom
			(at 0 0.2794 180)
			(size 0.0762 0.0762)
			(layers "B.Cu" "B.Mask" "B.Paste")
			(net "PCIE_SCC_TO_COMP_5_DP")
			(options
				(clearance outline)
				(anchor circle)
			)
			(primitives
				(gr_poly
					(pts
						(arc
							(start 0.1524 0.127)
							(mid 0.137521 0.162921)
							(end 0.1016 0.1778)
						)
						(arc
							(start -0.1016 0.1778)
							(mid -0.137521 0.162921)
							(end -0.1524 0.127)
						)
						(arc
							(start -0.1524 -0.127)
							(mid -0.137521 -0.162921)
							(end -0.1016 -0.1778)
						)
						(arc
							(start 0.1016 -0.1778)
							(mid 0.137521 -0.162921)
							(end 0.1524 -0.127)
						)
					)
					(width 0)
					(fill yes)
				)
			)
		)
	)
	(footprint ""
		(layer "B.Cu")
		(at 141.224 -117.16004 -90)
		(property "Reference" "C721"
			(at 0 0 90)
			(layer "B.SilkS")
			(hide yes)
			(effects
				(font
					(size 1.27 1.27)
				)
				(justify mirror)
			)
		)
		(property "Value" "SCD1U16V2KX-3GP"
			(at -1.1811 -2.7051 270)
			(unlocked yes)
			(layer "B.Fab")
			(hide yes)
			(effects
				(font
					(size 1.016 1.016)
					(thickness 0.1524)
				)
				(justify mirror)
			)
		)
		(property "Device Type" "C402H22"
			(at -1.1811 -4.2291 270)
			(unlocked yes)
			(layer "B.Fab")
			(hide yes)
			(effects
				(font
					(size 1.016 1.016)
					(thickness 0.1524)
				)
				(justify mirror)
			)
		)
		(duplicate_pad_numbers_are_jumpers no)
		(fp_rect
			(start 0.4318 0.9525)
			(end -0.4318 -0.9525)
			(stroke
				(width 0)
				(type default)
			)
			(fill no)
			(layer "B.CrtYd")
		)
		(fp_rect
			(start 0.4318 0.9525)
			(end -0.4318 -0.9525)
			(stroke
				(width 0)
				(type default)
			)
			(fill no)
			(layer "B.Fab")
		)
		(pad "1" smd custom
			(at 0 -0.4445 90)
			(size 0.1524 0.1524)
			(layers "B.Cu" "B.Mask" "B.Paste")
			(net "P1V5_C_S")
			(options
				(clearance outline)
				(anchor circle)
			)
			(primitives
				(gr_poly
					(pts
						(arc
							(start 0.3048 0.2032)
							(mid 0.275042 0.275042)
							(end 0.2032 0.3048)
						)
						(arc
							(start -0.2032 0.3048)
							(mid -0.275042 0.275042)
							(end -0.3048 0.2032)
						)
						(arc
							(start -0.3048 -0.2032)
							(mid -0.275042 -0.275042)
							(end -0.2032 -0.3048)
						)
						(arc
							(start 0.2032 -0.3048)
							(mid 0.275042 -0.275042)
							(end 0.3048 -0.2032)
						)
					)
					(width 0)
					(fill yes)
				)
			)
		)
		(pad "2" smd custom
			(at 0 0.4445 90)
			(size 0.1524 0.1524)
			(layers "B.Cu" "B.Mask" "B.Paste")
			(net "GND")
			(options
				(clearance outline)
				(anchor circle)
			)
			(primitives
				(gr_poly
					(pts
						(arc
							(start 0.3048 0.2032)
							(mid 0.275042 0.275042)
							(end 0.2032 0.3048)
						)
						(arc
							(start -0.2032 0.3048)
							(mid -0.275042 0.275042)
							(end -0.3048 0.2032)
						)
						(arc
							(start -0.3048 -0.2032)
							(mid -0.275042 -0.275042)
							(end -0.2032 -0.3048)
						)
						(arc
							(start 0.2032 -0.3048)
							(mid 0.275042 -0.275042)
							(end 0.3048 -0.2032)
						)
					)
					(width 0)
					(fill yes)
				)
			)
		)
	)
	(footprint ""
		(layer "B.Cu")
		(at 188.716412 -52.375308 -90)
		(property "Reference" "TP104"
			(at 0 0 90)
			(layer "B.SilkS")
			(hide yes)
			(effects
				(font
					(size 1.27 1.27)
				)
				(justify mirror)
			)
		)
		(property "Value" "TPAD28-2-GP"
			(at 0.0127 -1.6637 270)
			(unlocked yes)
			(layer "B.Fab")
			(hide yes)
			(effects
				(font
					(size 1.016 1.016)
					(thickness 0.1524)
				)
				(justify mirror)
			)
		)
		(property "Device Type" "TPAD28"
			(at 0.0127 -3.1877 270)
			(unlocked yes)
			(layer "B.Fab")
			(hide yes)
			(effects
				(font
					(size 1.016 1.016)
					(thickness 0.1524)
				)
				(justify mirror)
			)
		)
		(duplicate_pad_numbers_are_jumpers no)
		(fp_poly
			(pts
				(arc
					(start 0 -0.3556)
					(mid 0 0.3556)
					(end 0 -0.3556)
				)
			)
			(stroke
				(width 0)
				(type default)
			)
			(fill no)
			(layer "B.CrtYd")
		)
		(fp_poly
			(pts
				(arc
					(start 0 -0.6096)
					(mid 0 0.6096)
					(end 0 -0.6096)
				)
			)
			(stroke
				(width 0)
				(type default)
			)
			(fill no)
			(layer "B.Fab")
		)
		(pad "1" smd circle
			(at 0 0 90)
			(size 0.7112 0.7112)
			(layers "B.Cu" "B.Mask" "B.Paste")
			(net "XM_ADDR_17")
		)
	)
	(footprint ""
		(layer "B.Cu")
		(at 73.66 -62.23 180)
		(property "Reference" "C234"
			(at 0 0 0)
			(layer "B.SilkS")
			(hide yes)
			(effects
				(font
					(size 1.27 1.27)
				)
				(justify mirror)
			)
		)
		(property "Value" "SC100U6D3V6MX-GP"
			(at 0.0762 -5.1308 180)
			(unlocked yes)
			(layer "B.Fab")
			(hide yes)
			(effects
				(font
					(size 1.016 1.016)
					(thickness 0.1524)
				)
				(justify mirror)
			)
		)
		(property "Device Type" "C1206H71"
			(at 0.127 -6.6548 180)
			(unlocked yes)
			(layer "B.Fab")
			(hide yes)
			(effects
				(font
					(size 1.016 1.016)
					(thickness 0.1524)
				)
				(justify mirror)
			)
		)
		(duplicate_pad_numbers_are_jumpers no)
		(fp_line
			(start 1.016 2.2352)
			(end 1.016 0.8382)
			(stroke
				(width 0.1524)
				(type default)
			)
			(layer "B.SilkS")
		)
		(fp_line
			(start 1.016 -0.8382)
			(end 1.016 -2.2352)
			(stroke
				(width 0.1524)
				(type default)
			)
			(layer "B.SilkS")
		)
		(fp_line
			(start 1.016 -2.2352)
			(end -1.016 -2.2352)
			(stroke
				(width 0.1524)
				(type default)
			)
			(layer "B.SilkS")
		)
		(fp_line
			(start -1.016 2.2352)
			(end 1.016 2.2352)
			(stroke
				(width 0.1524)
				(type default)
			)
			(layer "B.SilkS")
		)
		(fp_line
			(start -1.016 0.8382)
			(end -1.016 2.2352)
			(stroke
				(width 0.1524)
				(type default)
			)
			(layer "B.SilkS")
		)
		(fp_line
			(start -1.016 -2.2352)
			(end -1.016 -0.8382)
			(stroke
				(width 0.1524)
				(type default)
			)
			(layer "B.SilkS")
		)
		(fp_rect
			(start 1.0922 2.3114)
			(end -1.0922 -2.3114)
			(stroke
				(width 0)
				(type default)
			)
			(fill no)
			(layer "B.CrtYd")
		)
		(fp_poly
			(pts
				(xy -1.0922 -2.3114) (xy -1.0922 2.3114) (xy 1.0922 2.3114) (xy 1.0922 -2.3114)
			)
			(stroke
				(width 0)
				(type default)
			)
			(fill no)
			(layer "B.Fab")
		)
		(pad "1" smd rect
			(at 0 -1.397)
			(size 1.651 1.27)
			(layers "B.Cu" "B.Mask" "B.Paste")
			(net "GB_VDDA")
		)
		(pad "2" smd rect
			(at 0 1.397)
			(size 1.651 1.27)
			(layers "B.Cu" "B.Mask" "B.Paste")
			(net "GND")
		)
	)
	(footprint ""
		(layer "B.Cu")
		(at 136.2456 -81.1276 -90)
		(property "Reference" "C2"
			(at 0 0 90)
			(layer "B.SilkS")
			(hide yes)
			(effects
				(font
					(size 1.27 1.27)
				)
				(justify mirror)
			)
		)
		(property "Value" "SCD01U16V1KX-GP"
			(at 2.8321 -1.7399 270)
			(unlocked yes)
			(layer "B.Fab")
			(hide yes)
			(effects
				(font
					(size 1.016 1.016)
					(thickness 0.1524)
				)
				(justify mirror)
			)
		)
		(property "Device Type" "C0201H13"
			(at 2.8321 -3.2639 270)
			(unlocked yes)
			(layer "B.Fab")
			(hide yes)
			(effects
				(font
					(size 1.016 1.016)
					(thickness 0.1524)
				)
				(justify mirror)
			)
		)
		(duplicate_pad_numbers_are_jumpers no)
		(fp_rect
			(start 0.2794 0.6477)
			(end -0.2794 -0.6477)
			(stroke
				(width 0)
				(type default)
			)
			(fill no)
			(layer "B.CrtYd")
		)
		(fp_rect
			(start 0.2794 0.6477)
			(end -0.2794 -0.6477)
			(stroke
				(width 0)
				(type default)
			)
			(fill no)
			(layer "B.Fab")
		)
		(pad "1" smd custom
			(at 0 -0.2794 90)
			(size 0.0762 0.0762)
			(layers "B.Cu" "B.Mask" "B.Paste")
			(net "PHY_CONN_TO_EXP_11_DN")
			(options
				(clearance outline)
				(anchor circle)
			)
			(primitives
				(gr_poly
					(pts
						(arc
							(start 0.1524 0.127)
							(mid 0.137521 0.162921)
							(end 0.1016 0.1778)
						)
						(arc
							(start -0.1016 0.1778)
							(mid -0.137521 0.162921)
							(end -0.1524 0.127)
						)
						(arc
							(start -0.1524 -0.127)
							(mid -0.137521 -0.162921)
							(end -0.1016 -0.1778)
						)
						(arc
							(start 0.1016 -0.1778)
							(mid 0.137521 -0.162921)
							(end 0.1524 -0.127)
						)
					)
					(width 0)
					(fill yes)
				)
			)
		)
		(pad "2" smd custom
			(at 0 0.2794 90)
			(size 0.0762 0.0762)
			(layers "B.Cu" "B.Mask" "B.Paste")
			(net "PHY_CONN_TO_EXP_C_11_DN")
			(options
				(clearance outline)
				(anchor circle)
			)
			(primitives
				(gr_poly
					(pts
						(arc
							(start 0.1524 0.127)
							(mid 0.137521 0.162921)
							(end 0.1016 0.1778)
						)
						(arc
							(start -0.1016 0.1778)
							(mid -0.137521 0.162921)
							(end -0.1524 0.127)
						)
						(arc
							(start -0.1524 -0.127)
							(mid -0.137521 -0.162921)
							(end -0.1016 -0.1778)
						)
						(arc
							(start 0.1016 -0.1778)
							(mid 0.137521 -0.162921)
							(end 0.1524 -0.127)
						)
					)
					(width 0)
					(fill yes)
				)
			)
		)
	)
	(footprint ""
		(layer "B.Cu")
		(at 115.3033 -64.4779)
		(property "Reference" "C164"
			(at 0 0 0)
			(layer "B.SilkS")
			(hide yes)
			(effects
				(font
					(size 1.27 1.27)
				)
				(justify mirror)
			)
		)
		(property "Value" "SCD1U6D3V1KX-GP"
			(at 2.8321 -1.7399 0)
			(unlocked yes)
			(layer "B.Fab")
			(hide yes)
			(effects
				(font
					(size 1.016 1.016)
					(thickness 0.1524)
				)
				(justify mirror)
			)
		)
		(property "Device Type" "C0201H13"
			(at 2.8321 -3.2639 0)
			(unlocked yes)
			(layer "B.Fab")
			(hide yes)
			(effects
				(font
					(size 1.016 1.016)
					(thickness 0.1524)
				)
				(justify mirror)
			)
		)
		(duplicate_pad_numbers_are_jumpers no)
		(fp_rect
			(start 0.2794 0.6477)
			(end -0.2794 -0.6477)
			(stroke
				(width 0)
				(type default)
			)
			(fill no)
			(layer "B.CrtYd")
		)
		(fp_rect
			(start 0.2794 0.6477)
			(end -0.2794 -0.6477)
			(stroke
				(width 0)
				(type default)
			)
			(fill no)
			(layer "B.Fab")
		)
		(pad "1" smd custom
			(at 0 -0.2794 180)
			(size 0.0762 0.0762)
			(layers "B.Cu" "B.Mask" "B.Paste")
			(net "P0V9")
			(options
				(clearance outline)
				(anchor circle)
			)
			(primitives
				(gr_poly
					(pts
						(arc
							(start 0.1524 0.127)
							(mid 0.137521 0.162921)
							(end 0.1016 0.1778)
						)
						(arc
							(start -0.1016 0.1778)
							(mid -0.137521 0.162921)
							(end -0.1524 0.127)
						)
						(arc
							(start -0.1524 -0.127)
							(mid -0.137521 -0.162921)
							(end -0.1016 -0.1778)
						)
						(arc
							(start 0.1016 -0.1778)
							(mid 0.137521 -0.162921)
							(end 0.1524 -0.127)
						)
					)
					(width 0)
					(fill yes)
				)
			)
		)
		(pad "2" smd custom
			(at 0 0.2794 180)
			(size 0.0762 0.0762)
			(layers "B.Cu" "B.Mask" "B.Paste")
			(net "GND")
			(options
				(clearance outline)
				(anchor circle)
			)
			(primitives
				(gr_poly
					(pts
						(arc
							(start 0.1524 0.127)
							(mid 0.137521 0.162921)
							(end 0.1016 0.1778)
						)
						(arc
							(start -0.1016 0.1778)
							(mid -0.137521 0.162921)
							(end -0.1524 0.127)
						)
						(arc
							(start -0.1524 -0.127)
							(mid -0.137521 -0.162921)
							(end -0.1016 -0.1778)
						)
						(arc
							(start 0.1016 -0.1778)
							(mid 0.137521 -0.162921)
							(end 0.1524 -0.127)
						)
					)
					(width 0)
					(fill yes)
				)
			)
		)
	)
	(footprint ""
		(layer "B.Cu")
		(at 118.872 -86.995 180)
		(property "Reference" "R210"
			(at 0 0 0)
			(layer "B.SilkS")
			(hide yes)
			(effects
				(font
					(size 1.27 1.27)
				)
				(justify mirror)
			)
		)
		(property "Value" "0R2J-2-GP"
			(at -0.064008 -3.993896 180)
			(unlocked yes)
			(layer "B.Fab")
			(hide yes)
			(effects
				(font
					(size 1.016 1.016)
					(thickness 0.1524)
				)
				(justify mirror)
			)
		)
		(property "Device Type" "R402H16"
			(at -0.064008 -5.517896 180)
			(unlocked yes)
			(layer "B.Fab")
			(hide yes)
			(effects
				(font
					(size 1.016 1.016)
					(thickness 0.1524)
				)
				(justify mirror)
			)
		)
		(duplicate_pad_numbers_are_jumpers no)
		(fp_line
			(start 0.508 -0.9398)
			(end 0.508 0.9398)
			(stroke
				(width 0.1524)
				(type default)
			)
			(layer "B.SilkS")
		)
		(fp_line
			(start -0.508 -0.9398)
			(end 0.508 -0.9398)
			(stroke
				(width 0.1524)
				(type default)
			)
			(layer "B.SilkS")
		)
		(fp_rect
			(start 0.508 0.9398)
			(end -0.508 -0.9398)
			(stroke
				(width 0)
				(type default)
			)
			(fill no)
			(layer "B.CrtYd")
		)
		(fp_rect
			(start 0.508 0.9398)
			(end -0.508 -0.9398)
			(stroke
				(width 0)
				(type default)
			)
			(fill no)
			(layer "B.Fab")
		)
		(pad "1" smd custom
			(at 0 -0.4445)
			(size 0.1397 0.1397)
			(layers "B.Cu" "B.Mask" "B.Paste")
			(net "COMP_EXP_SPARE_1_R_LS")
			(options
				(clearance outline)
				(anchor circle)
			)
			(primitives
				(gr_poly
					(pts
						(arc
							(start -0.1778 0.2794)
							(mid -0.249642 0.249642)
							(end -0.2794 0.1778)
						)
						(arc
							(start -0.2794 -0.1778)
							(mid -0.249642 -0.249642)
							(end -0.1778 -0.2794)
						)
						(arc
							(start 0.1778 -0.2794)
							(mid 0.249642 -0.249642)
							(end 0.2794 -0.1778)
						)
						(arc
							(start 0.2794 0.1778)
							(mid 0.249642 0.249642)
							(end 0.1778 0.2794)
						)
					)
					(width 0)
					(fill yes)
				)
			)
		)
		(pad "2" smd custom
			(at 0 0.4445)
			(size 0.1397 0.1397)
			(layers "B.Cu" "B.Mask" "B.Paste")
			(net "COMP_SPARE_0_LS")
			(options
				(clearance outline)
				(anchor circle)
			)
			(primitives
				(gr_poly
					(pts
						(arc
							(start -0.1778 0.2794)
							(mid -0.249642 0.249642)
							(end -0.2794 0.1778)
						)
						(arc
							(start -0.2794 -0.1778)
							(mid -0.249642 -0.249642)
							(end -0.1778 -0.2794)
						)
						(arc
							(start 0.1778 -0.2794)
							(mid 0.249642 -0.249642)
							(end 0.2794 -0.1778)
						)
						(arc
							(start 0.2794 0.1778)
							(mid 0.249642 0.249642)
							(end 0.1778 0.2794)
						)
					)
					(width 0)
					(fill yes)
				)
			)
		)
	)
	(footprint ""
		(layer "B.Cu")
		(at 89.464388 -74.610214 180)
		(property "Reference" "L4"
			(at 0 0 0)
			(layer "B.SilkS")
			(hide yes)
			(effects
				(font
					(size 1.27 1.27)
				)
				(justify mirror)
			)
		)
		(property "Value" "MPZ2012S601AT-GP"
			(at 0 -4.2418 180)
			(unlocked yes)
			(layer "B.Fab")
			(hide yes)
			(effects
				(font
					(size 1.016 1.016)
					(thickness 0.1524)
				)
				(justify mirror)
			)
		)
		(property "Device Type" "L805H42"
			(at 0 -5.7912 180)
			(unlocked yes)
			(layer "B.Fab")
			(hide yes)
			(effects
				(font
					(size 1.016 1.016)
					(thickness 0.1524)
				)
				(justify mirror)
			)
		)
		(duplicate_pad_numbers_are_jumpers no)
		(fp_line
			(start 0.889 1.7018)
			(end 0.889 -1.7018)
			(stroke
				(width 0.1524)
				(type default)
			)
			(layer "B.SilkS")
		)
		(fp_line
			(start 0.889 -1.7018)
			(end -0.889 -1.7018)
			(stroke
				(width 0.1524)
				(type default)
			)
			(layer "B.SilkS")
		)
		(fp_line
			(start -0.889 1.7018)
			(end 0.889 1.7018)
			(stroke
				(width 0.1524)
				(type default)
			)
			(layer "B.SilkS")
		)
		(fp_line
			(start -0.889 -1.7018)
			(end -0.889 1.7018)
			(stroke
				(width 0.1524)
				(type default)
			)
			(layer "B.SilkS")
		)
		(fp_rect
			(start 0.9652 1.778)
			(end -0.9652 -1.778)
			(stroke
				(width 0)
				(type default)
			)
			(fill no)
			(layer "B.CrtYd")
		)
		(fp_rect
			(start 0.9652 1.778)
			(end -0.9652 -1.778)
			(stroke
				(width 0)
				(type default)
			)
			(fill no)
			(layer "B.Fab")
		)
		(pad "1" smd rect
			(at 0 -0.9652)
			(size 1.397 1.143)
			(layers "B.Cu" "B.Mask" "B.Paste")
			(net "XTAL_VDDA09")
		)
		(pad "2" smd rect
			(at 0 0.9652)
			(size 1.397 1.143)
			(layers "B.Cu" "B.Mask" "B.Paste")
			(net "P0V9")
		)
	)
	(footprint ""
		(layer "B.Cu")
		(at 101.843332 -66.789808 90)
		(property "Reference" "R380"
			(at 0 0 90)
			(layer "B.SilkS")
			(hide yes)
			(effects
				(font
					(size 1.27 1.27)
				)
				(justify mirror)
			)
		)
		(property "Value" "1KR2F-3-GP"
			(at -0.064008 -3.993896 90)
			(unlocked yes)
			(layer "B.Fab")
			(hide yes)
			(effects
				(font
					(size 1.016 1.016)
					(thickness 0.1524)
				)
				(justify mirror)
			)
		)
		(property "Device Type" "R402H16"
			(at -0.064008 -5.517896 90)
			(unlocked yes)
			(layer "B.Fab")
			(hide yes)
			(effects
				(font
					(size 1.016 1.016)
					(thickness 0.1524)
				)
				(justify mirror)
			)
		)
		(duplicate_pad_numbers_are_jumpers no)
		(fp_line
			(start 0.508 -0.9398)
			(end 0.508 0.9398)
			(stroke
				(width 0.1524)
				(type default)
			)
			(layer "B.SilkS")
		)
		(fp_line
			(start -0.508 -0.9398)
			(end 0.508 -0.9398)
			(stroke
				(width 0.1524)
				(type default)
			)
			(layer "B.SilkS")
		)
		(fp_rect
			(start 0.508 0.9398)
			(end -0.508 -0.9398)
			(stroke
				(width 0)
				(type default)
			)
			(fill no)
			(layer "B.CrtYd")
		)
		(fp_rect
			(start 0.508 0.9398)
			(end -0.508 -0.9398)
			(stroke
				(width 0)
				(type default)
			)
			(fill no)
			(layer "B.Fab")
		)
		(pad "1" smd custom
			(at 0 -0.4445 270)
			(size 0.1397 0.1397)
			(layers "B.Cu" "B.Mask" "B.Paste")
			(net "GND")
			(options
				(clearance outline)
				(anchor circle)
			)
			(primitives
				(gr_poly
					(pts
						(arc
							(start -0.1778 0.2794)
							(mid -0.249642 0.249642)
							(end -0.2794 0.1778)
						)
						(arc
							(start -0.2794 -0.1778)
							(mid -0.249642 -0.249642)
							(end -0.1778 -0.2794)
						)
						(arc
							(start 0.1778 -0.2794)
							(mid 0.249642 -0.249642)
							(end 0.2794 -0.1778)
						)
						(arc
							(start 0.2794 0.1778)
							(mid 0.249642 0.249642)
							(end 0.1778 0.2794)
						)
					)
					(width 0)
					(fill yes)
				)
			)
		)
		(pad "2" smd custom
			(at 0 0.4445 270)
			(size 0.1397 0.1397)
			(layers "B.Cu" "B.Mask" "B.Paste")
			(net "DDR_BZ")
			(options
				(clearance outline)
				(anchor circle)
			)
			(primitives
				(gr_poly
					(pts
						(arc
							(start -0.1778 0.2794)
							(mid -0.249642 0.249642)
							(end -0.2794 0.1778)
						)
						(arc
							(start -0.2794 -0.1778)
							(mid -0.249642 -0.249642)
							(end -0.1778 -0.2794)
						)
						(arc
							(start 0.1778 -0.2794)
							(mid 0.249642 -0.249642)
							(end 0.2794 -0.1778)
						)
						(arc
							(start 0.2794 0.1778)
							(mid 0.249642 0.249642)
							(end 0.1778 0.2794)
						)
					)
					(width 0)
					(fill yes)
				)
			)
		)
	)
	(footprint ""
		(layer "B.Cu")
		(at 166.863776 -45.314616)
		(property "Reference" "C455"
			(at 0 0 0)
			(layer "B.SilkS")
			(hide yes)
			(effects
				(font
					(size 1.27 1.27)
				)
				(justify mirror)
			)
		)
		(property "Value" "SCD1U6D3V1KX-GP"
			(at 2.8321 -1.7399 0)
			(unlocked yes)
			(layer "B.Fab")
			(hide yes)
			(effects
				(font
					(size 1.016 1.016)
					(thickness 0.1524)
				)
				(justify mirror)
			)
		)
		(property "Device Type" "C0201H13"
			(at 2.8321 -3.2639 0)
			(unlocked yes)
			(layer "B.Fab")
			(hide yes)
			(effects
				(font
					(size 1.016 1.016)
					(thickness 0.1524)
				)
				(justify mirror)
			)
		)
		(duplicate_pad_numbers_are_jumpers no)
		(fp_rect
			(start 0.2794 0.6477)
			(end -0.2794 -0.6477)
			(stroke
				(width 0)
				(type default)
			)
			(fill no)
			(layer "B.CrtYd")
		)
		(fp_rect
			(start 0.2794 0.6477)
			(end -0.2794 -0.6477)
			(stroke
				(width 0)
				(type default)
			)
			(fill no)
			(layer "B.Fab")
		)
		(pad "1" smd custom
			(at 0 -0.2794 180)
			(size 0.0762 0.0762)
			(layers "B.Cu" "B.Mask" "B.Paste")
			(net "P1V8_C")
			(options
				(clearance outline)
				(anchor circle)
			)
			(primitives
				(gr_poly
					(pts
						(arc
							(start 0.1524 0.127)
							(mid 0.137521 0.162921)
							(end 0.1016 0.1778)
						)
						(arc
							(start -0.1016 0.1778)
							(mid -0.137521 0.162921)
							(end -0.1524 0.127)
						)
						(arc
							(start -0.1524 -0.127)
							(mid -0.137521 -0.162921)
							(end -0.1016 -0.1778)
						)
						(arc
							(start 0.1016 -0.1778)
							(mid 0.137521 -0.162921)
							(end 0.1524 -0.127)
						)
					)
					(width 0)
					(fill yes)
				)
			)
		)
		(pad "2" smd custom
			(at 0 0.2794 180)
			(size 0.0762 0.0762)
			(layers "B.Cu" "B.Mask" "B.Paste")
			(net "GND")
			(options
				(clearance outline)
				(anchor circle)
			)
			(primitives
				(gr_poly
					(pts
						(arc
							(start 0.1524 0.127)
							(mid 0.137521 0.162921)
							(end 0.1016 0.1778)
						)
						(arc
							(start -0.1016 0.1778)
							(mid -0.137521 0.162921)
							(end -0.1524 0.127)
						)
						(arc
							(start -0.1524 -0.127)
							(mid -0.137521 -0.162921)
							(end -0.1016 -0.1778)
						)
						(arc
							(start 0.1016 -0.1778)
							(mid 0.137521 -0.162921)
							(end 0.1524 -0.127)
						)
					)
					(width 0)
					(fill yes)
				)
			)
		)
	)
	(footprint ""
		(layer "B.Cu")
		(at 137.4648 -68.3514 -90)
		(property "Reference" "C17"
			(at 0 0 90)
			(layer "B.SilkS")
			(hide yes)
			(effects
				(font
					(size 1.27 1.27)
				)
				(justify mirror)
			)
		)
		(property "Value" "SCD01U16V1KX-GP"
			(at 2.8321 -1.7399 270)
			(unlocked yes)
			(layer "B.Fab")
			(hide yes)
			(effects
				(font
					(size 1.016 1.016)
					(thickness 0.1524)
				)
				(justify mirror)
			)
		)
		(property "Device Type" "C0201H13"
			(at 2.8321 -3.2639 270)
			(unlocked yes)
			(layer "B.Fab")
			(hide yes)
			(effects
				(font
					(size 1.016 1.016)
					(thickness 0.1524)
				)
				(justify mirror)
			)
		)
		(duplicate_pad_numbers_are_jumpers no)
		(fp_rect
			(start 0.2794 0.6477)
			(end -0.2794 -0.6477)
			(stroke
				(width 0)
				(type default)
			)
			(fill no)
			(layer "B.CrtYd")
		)
		(fp_rect
			(start 0.2794 0.6477)
			(end -0.2794 -0.6477)
			(stroke
				(width 0)
				(type default)
			)
			(fill no)
			(layer "B.Fab")
		)
		(pad "1" smd custom
			(at 0 -0.2794 90)
			(size 0.0762 0.0762)
			(layers "B.Cu" "B.Mask" "B.Paste")
			(net "PHY_DPB_TO_SCC_3_DP")
			(options
				(clearance outline)
				(anchor circle)
			)
			(primitives
				(gr_poly
					(pts
						(arc
							(start 0.1524 0.127)
							(mid 0.137521 0.162921)
							(end 0.1016 0.1778)
						)
						(arc
							(start -0.1016 0.1778)
							(mid -0.137521 0.162921)
							(end -0.1524 0.127)
						)
						(arc
							(start -0.1524 -0.127)
							(mid -0.137521 -0.162921)
							(end -0.1016 -0.1778)
						)
						(arc
							(start 0.1016 -0.1778)
							(mid 0.137521 -0.162921)
							(end 0.1524 -0.127)
						)
					)
					(width 0)
					(fill yes)
				)
			)
		)
		(pad "2" smd custom
			(at 0 0.2794 90)
			(size 0.0762 0.0762)
			(layers "B.Cu" "B.Mask" "B.Paste")
			(net "PHY_DPB_TO_SCC_C_3_DP")
			(options
				(clearance outline)
				(anchor circle)
			)
			(primitives
				(gr_poly
					(pts
						(arc
							(start 0.1524 0.127)
							(mid 0.137521 0.162921)
							(end 0.1016 0.1778)
						)
						(arc
							(start -0.1016 0.1778)
							(mid -0.137521 0.162921)
							(end -0.1524 0.127)
						)
						(arc
							(start -0.1524 -0.127)
							(mid -0.137521 -0.162921)
							(end -0.1016 -0.1778)
						)
						(arc
							(start 0.1016 -0.1778)
							(mid 0.137521 -0.162921)
							(end 0.1524 -0.127)
						)
					)
					(width 0)
					(fill yes)
				)
			)
		)
	)
	(footprint ""
		(layer "B.Cu")
		(at 96.258634 -84.53374 -90)
		(property "Reference" "C114"
			(at 0 0 90)
			(layer "B.SilkS")
			(hide yes)
			(effects
				(font
					(size 1.27 1.27)
				)
				(justify mirror)
			)
		)
		(property "Value" "SCD1U16V2KX-3GP"
			(at -1.1811 -2.7051 270)
			(unlocked yes)
			(layer "B.Fab")
			(hide yes)
			(effects
				(font
					(size 1.016 1.016)
					(thickness 0.1524)
				)
				(justify mirror)
			)
		)
		(property "Device Type" "C402H22"
			(at -1.1811 -4.2291 270)
			(unlocked yes)
			(layer "B.Fab")
			(hide yes)
			(effects
				(font
					(size 1.016 1.016)
					(thickness 0.1524)
				)
				(justify mirror)
			)
		)
		(duplicate_pad_numbers_are_jumpers no)
		(fp_rect
			(start 0.4318 0.9525)
			(end -0.4318 -0.9525)
			(stroke
				(width 0)
				(type default)
			)
			(fill no)
			(layer "B.CrtYd")
		)
		(fp_rect
			(start 0.4318 0.9525)
			(end -0.4318 -0.9525)
			(stroke
				(width 0)
				(type default)
			)
			(fill no)
			(layer "B.Fab")
		)
		(pad "1" smd custom
			(at 0 -0.4445 90)
			(size 0.1524 0.1524)
			(layers "B.Cu" "B.Mask" "B.Paste")
			(net "P1V8_E")
			(options
				(clearance outline)
				(anchor circle)
			)
			(primitives
				(gr_poly
					(pts
						(arc
							(start 0.3048 0.2032)
							(mid 0.275042 0.275042)
							(end 0.2032 0.3048)
						)
						(arc
							(start -0.2032 0.3048)
							(mid -0.275042 0.275042)
							(end -0.3048 0.2032)
						)
						(arc
							(start -0.3048 -0.2032)
							(mid -0.275042 -0.275042)
							(end -0.2032 -0.3048)
						)
						(arc
							(start 0.2032 -0.3048)
							(mid 0.275042 -0.275042)
							(end 0.3048 -0.2032)
						)
					)
					(width 0)
					(fill yes)
				)
			)
		)
		(pad "2" smd custom
			(at 0 0.4445 90)
			(size 0.1524 0.1524)
			(layers "B.Cu" "B.Mask" "B.Paste")
			(net "GND")
			(options
				(clearance outline)
				(anchor circle)
			)
			(primitives
				(gr_poly
					(pts
						(arc
							(start 0.3048 0.2032)
							(mid 0.275042 0.275042)
							(end 0.2032 0.3048)
						)
						(arc
							(start -0.2032 0.3048)
							(mid -0.275042 0.275042)
							(end -0.3048 0.2032)
						)
						(arc
							(start -0.3048 -0.2032)
							(mid -0.275042 -0.275042)
							(end -0.2032 -0.3048)
						)
						(arc
							(start 0.2032 -0.3048)
							(mid 0.275042 -0.275042)
							(end 0.3048 -0.2032)
						)
					)
					(width 0)
					(fill yes)
				)
			)
		)
	)
	(footprint ""
		(layer "B.Cu")
		(at 165.558978 -20.583144)
		(property "Reference" "C312"
			(at 0 0 0)
			(layer "B.SilkS")
			(hide yes)
			(effects
				(font
					(size 1.27 1.27)
				)
				(justify mirror)
			)
		)
		(property "Value" "SCD22U10V1KX-GP"
			(at 2.8321 -1.7399 0)
			(unlocked yes)
			(layer "B.Fab")
			(hide yes)
			(effects
				(font
					(size 1.016 1.016)
					(thickness 0.1524)
				)
				(justify mirror)
			)
		)
		(property "Device Type" "C0201H13"
			(at 2.8321 -3.2639 0)
			(unlocked yes)
			(layer "B.Fab")
			(hide yes)
			(effects
				(font
					(size 1.016 1.016)
					(thickness 0.1524)
				)
				(justify mirror)
			)
		)
		(duplicate_pad_numbers_are_jumpers no)
		(fp_rect
			(start 0.2794 0.6477)
			(end -0.2794 -0.6477)
			(stroke
				(width 0)
				(type default)
			)
			(fill no)
			(layer "B.CrtYd")
		)
		(fp_rect
			(start 0.2794 0.6477)
			(end -0.2794 -0.6477)
			(stroke
				(width 0)
				(type default)
			)
			(fill no)
			(layer "B.Fab")
		)
		(pad "1" smd custom
			(at 0 -0.2794 180)
			(size 0.0762 0.0762)
			(layers "B.Cu" "B.Mask" "B.Paste")
			(net "PCIE_SCC_TO_COMP_C_0_DN")
			(options
				(clearance outline)
				(anchor circle)
			)
			(primitives
				(gr_poly
					(pts
						(arc
							(start 0.1524 0.127)
							(mid 0.137521 0.162921)
							(end 0.1016 0.1778)
						)
						(arc
							(start -0.1016 0.1778)
							(mid -0.137521 0.162921)
							(end -0.1524 0.127)
						)
						(arc
							(start -0.1524 -0.127)
							(mid -0.137521 -0.162921)
							(end -0.1016 -0.1778)
						)
						(arc
							(start 0.1016 -0.1778)
							(mid 0.137521 -0.162921)
							(end 0.1524 -0.127)
						)
					)
					(width 0)
					(fill yes)
				)
			)
		)
		(pad "2" smd custom
			(at 0 0.2794 180)
			(size 0.0762 0.0762)
			(layers "B.Cu" "B.Mask" "B.Paste")
			(net "PCIE_SCC_TO_COMP_0_DN")
			(options
				(clearance outline)
				(anchor circle)
			)
			(primitives
				(gr_poly
					(pts
						(arc
							(start 0.1524 0.127)
							(mid 0.137521 0.162921)
							(end 0.1016 0.1778)
						)
						(arc
							(start -0.1016 0.1778)
							(mid -0.137521 0.162921)
							(end -0.1524 0.127)
						)
						(arc
							(start -0.1524 -0.127)
							(mid -0.137521 -0.162921)
							(end -0.1016 -0.1778)
						)
						(arc
							(start 0.1016 -0.1778)
							(mid 0.137521 -0.162921)
							(end 0.1524 -0.127)
						)
					)
					(width 0)
					(fill yes)
				)
			)
		)
	)
	(footprint ""
		(layer "B.Cu")
		(at 120.542558 -86.65591 180)
		(property "Reference" "R404"
			(at 0 0 0)
			(layer "B.SilkS")
			(hide yes)
			(effects
				(font
					(size 1.27 1.27)
				)
				(justify mirror)
			)
		)
		(property "Value" "10KR2F-2-GP"
			(at -0.064008 -3.993896 180)
			(unlocked yes)
			(layer "B.Fab")
			(hide yes)
			(effects
				(font
					(size 1.016 1.016)
					(thickness 0.1524)
				)
				(justify mirror)
			)
		)
		(property "Device Type" "R402H16"
			(at -0.064008 -5.517896 180)
			(unlocked yes)
			(layer "B.Fab")
			(hide yes)
			(effects
				(font
					(size 1.016 1.016)
					(thickness 0.1524)
				)
				(justify mirror)
			)
		)
		(duplicate_pad_numbers_are_jumpers no)
		(fp_line
			(start 0.508 -0.9398)
			(end 0.508 0.9398)
			(stroke
				(width 0.1524)
				(type default)
			)
			(layer "B.SilkS")
		)
		(fp_line
			(start -0.508 -0.9398)
			(end 0.508 -0.9398)
			(stroke
				(width 0.1524)
				(type default)
			)
			(layer "B.SilkS")
		)
		(fp_rect
			(start 0.508 0.9398)
			(end -0.508 -0.9398)
			(stroke
				(width 0)
				(type default)
			)
			(fill no)
			(layer "B.CrtYd")
		)
		(fp_rect
			(start 0.508 0.9398)
			(end -0.508 -0.9398)
			(stroke
				(width 0)
				(type default)
			)
			(fill no)
			(layer "B.Fab")
		)
		(pad "1" smd custom
			(at 0 -0.4445)
			(size 0.1397 0.1397)
			(layers "B.Cu" "B.Mask" "B.Paste")
			(net "SLOT_ID_1")
			(options
				(clearance outline)
				(anchor circle)
			)
			(primitives
				(gr_poly
					(pts
						(arc
							(start -0.1778 0.2794)
							(mid -0.249642 0.249642)
							(end -0.2794 0.1778)
						)
						(arc
							(start -0.2794 -0.1778)
							(mid -0.249642 -0.249642)
							(end -0.1778 -0.2794)
						)
						(arc
							(start 0.1778 -0.2794)
							(mid 0.249642 -0.249642)
							(end 0.2794 -0.1778)
						)
						(arc
							(start 0.2794 0.1778)
							(mid 0.249642 0.249642)
							(end 0.1778 0.2794)
						)
					)
					(width 0)
					(fill yes)
				)
			)
		)
		(pad "2" smd custom
			(at 0 0.4445)
			(size 0.1397 0.1397)
			(layers "B.Cu" "B.Mask" "B.Paste")
			(net "P1V8_E")
			(options
				(clearance outline)
				(anchor circle)
			)
			(primitives
				(gr_poly
					(pts
						(arc
							(start -0.1778 0.2794)
							(mid -0.249642 0.249642)
							(end -0.2794 0.1778)
						)
						(arc
							(start -0.2794 -0.1778)
							(mid -0.249642 -0.249642)
							(end -0.1778 -0.2794)
						)
						(arc
							(start 0.1778 -0.2794)
							(mid 0.249642 -0.249642)
							(end 0.2794 -0.1778)
						)
						(arc
							(start 0.2794 0.1778)
							(mid 0.249642 0.249642)
							(end 0.1778 0.2794)
						)
					)
					(width 0)
					(fill yes)
				)
			)
		)
	)
	(footprint ""
		(layer "B.Cu")
		(at 123.7996 -39.4716 180)
		(property "Reference" "C53"
			(at 0 0 0)
			(layer "B.SilkS")
			(hide yes)
			(effects
				(font
					(size 1.27 1.27)
				)
				(justify mirror)
			)
		)
		(property "Value" "SCD01U16V1KX-GP"
			(at 2.8321 -1.7399 180)
			(unlocked yes)
			(layer "B.Fab")
			(hide yes)
			(effects
				(font
					(size 1.016 1.016)
					(thickness 0.1524)
				)
				(justify mirror)
			)
		)
		(property "Device Type" "C0201H13"
			(at 2.8321 -3.2639 180)
			(unlocked yes)
			(layer "B.Fab")
			(hide yes)
			(effects
				(font
					(size 1.016 1.016)
					(thickness 0.1524)
				)
				(justify mirror)
			)
		)
		(duplicate_pad_numbers_are_jumpers no)
		(fp_rect
			(start 0.2794 0.6477)
			(end -0.2794 -0.6477)
			(stroke
				(width 0)
				(type default)
			)
			(fill no)
			(layer "B.CrtYd")
		)
		(fp_rect
			(start 0.2794 0.6477)
			(end -0.2794 -0.6477)
			(stroke
				(width 0)
				(type default)
			)
			(fill no)
			(layer "B.Fab")
		)
		(pad "1" smd custom
			(at 0 -0.2794)
			(size 0.0762 0.0762)
			(layers "B.Cu" "B.Mask" "B.Paste")
			(net "PHY_DPB_TO_SCC_37_DP")
			(options
				(clearance outline)
				(anchor circle)
			)
			(primitives
				(gr_poly
					(pts
						(arc
							(start 0.1524 0.127)
							(mid 0.137521 0.162921)
							(end 0.1016 0.1778)
						)
						(arc
							(start -0.1016 0.1778)
							(mid -0.137521 0.162921)
							(end -0.1524 0.127)
						)
						(arc
							(start -0.1524 -0.127)
							(mid -0.137521 -0.162921)
							(end -0.1016 -0.1778)
						)
						(arc
							(start 0.1016 -0.1778)
							(mid 0.137521 -0.162921)
							(end 0.1524 -0.127)
						)
					)
					(width 0)
					(fill yes)
				)
			)
		)
		(pad "2" smd custom
			(at 0 0.2794)
			(size 0.0762 0.0762)
			(layers "B.Cu" "B.Mask" "B.Paste")
			(net "PHY_DPB_TO_SCC_C_37_DP")
			(options
				(clearance outline)
				(anchor circle)
			)
			(primitives
				(gr_poly
					(pts
						(arc
							(start 0.1524 0.127)
							(mid 0.137521 0.162921)
							(end 0.1016 0.1778)
						)
						(arc
							(start -0.1016 0.1778)
							(mid -0.137521 0.162921)
							(end -0.1524 0.127)
						)
						(arc
							(start -0.1524 -0.127)
							(mid -0.137521 -0.162921)
							(end -0.1016 -0.1778)
						)
						(arc
							(start 0.1016 -0.1778)
							(mid 0.137521 -0.162921)
							(end 0.1524 -0.127)
						)
					)
					(width 0)
					(fill yes)
				)
			)
		)
	)
	(footprint ""
		(layer "B.Cu")
		(at 42.910252 -106.13898 -90)
		(property "Reference" "C709"
			(at 0 0 90)
			(layer "B.SilkS")
			(hide yes)
			(effects
				(font
					(size 1.27 1.27)
				)
				(justify mirror)
			)
		)
		(property "Value" "SC10U16V5KX-7-GP-U"
			(at 0.0762 -6.1214 270)
			(unlocked yes)
			(layer "B.Fab")
			(hide yes)
			(effects
				(font
					(size 1.016 1.016)
					(thickness 0.1524)
				)
				(justify mirror)
			)
		)
		(property "Device Type" "C805H58"
			(at 0.0762 -8.1534 270)
			(unlocked yes)
			(layer "B.Fab")
			(hide yes)
			(effects
				(font
					(size 1.016 1.016)
					(thickness 0.1524)
				)
				(justify mirror)
			)
		)
		(duplicate_pad_numbers_are_jumpers no)
		(fp_line
			(start -0.635 0)
			(end 0.635 0)
			(stroke
				(width 0.508)
				(type default)
			)
			(layer "B.SilkS")
		)
		(fp_rect
			(start 0.9652 1.778)
			(end -0.9652 -1.778)
			(stroke
				(width 0)
				(type default)
			)
			(fill no)
			(layer "B.CrtYd")
		)
		(fp_poly
			(pts
				(xy 0.9652 -1.778) (xy -0.9652 -1.778) (xy -0.9652 1.778) (xy 0.9652 1.778)
			)
			(stroke
				(width 0)
				(type default)
			)
			(fill no)
			(layer "B.Fab")
		)
		(pad "1" smd rect
			(at 0 -0.9652 90)
			(size 1.397 1.143)
			(layers "B.Cu" "B.Mask" "B.Paste")
			(net "P12V_STBY_SCC")
		)
		(pad "2" smd rect
			(at 0 0.9652 90)
			(size 1.397 1.143)
			(layers "B.Cu" "B.Mask" "B.Paste")
			(net "GND")
		)
	)
	(footprint ""
		(layer "B.Cu")
		(at 94.843092 -86.63178 -90)
		(property "Reference" "R135"
			(at 0 0 90)
			(layer "B.SilkS")
			(hide yes)
			(effects
				(font
					(size 1.27 1.27)
				)
				(justify mirror)
			)
		)
		(property "Value" "4K7R2F-GP"
			(at -0.064008 -3.993896 270)
			(unlocked yes)
			(layer "B.Fab")
			(hide yes)
			(effects
				(font
					(size 1.016 1.016)
					(thickness 0.1524)
				)
				(justify mirror)
			)
		)
		(property "Device Type" "R402H16"
			(at -0.064008 -5.517896 270)
			(unlocked yes)
			(layer "B.Fab")
			(hide yes)
			(effects
				(font
					(size 1.016 1.016)
					(thickness 0.1524)
				)
				(justify mirror)
			)
		)
		(duplicate_pad_numbers_are_jumpers no)
		(fp_line
			(start -0.508 -0.9398)
			(end 0.508 -0.9398)
			(stroke
				(width 0.1524)
				(type default)
			)
			(layer "B.SilkS")
		)
		(fp_line
			(start 0.508 -0.9398)
			(end 0.508 0.9398)
			(stroke
				(width 0.1524)
				(type default)
			)
			(layer "B.SilkS")
		)
		(fp_rect
			(start 0.508 0.9398)
			(end -0.508 -0.9398)
			(stroke
				(width 0)
				(type default)
			)
			(fill no)
			(layer "B.CrtYd")
		)
		(fp_rect
			(start 0.508 0.9398)
			(end -0.508 -0.9398)
			(stroke
				(width 0)
				(type default)
			)
			(fill no)
			(layer "B.Fab")
		)
		(pad "1" smd custom
			(at 0 -0.4445 90)
			(size 0.1397 0.1397)
			(layers "B.Cu" "B.Mask" "B.Paste")
			(net "P1V8_E")
			(options
				(clearance outline)
				(anchor circle)
			)
			(primitives
				(gr_poly
					(pts
						(arc
							(start -0.1778 0.2794)
							(mid -0.249642 0.249642)
							(end -0.2794 0.1778)
						)
						(arc
							(start -0.2794 -0.1778)
							(mid -0.249642 -0.249642)
							(end -0.1778 -0.2794)
						)
						(arc
							(start 0.1778 -0.2794)
							(mid 0.249642 -0.249642)
							(end 0.2794 -0.1778)
						)
						(arc
							(start 0.2794 0.1778)
							(mid 0.249642 0.249642)
							(end 0.1778 0.2794)
						)
					)
					(width 0)
					(fill yes)
				)
			)
		)
		(pad "2" smd custom
			(at 0 0.4445 90)
			(size 0.1397 0.1397)
			(layers "B.Cu" "B.Mask" "B.Paste")
			(net "ICE_RESET_N")
			(options
				(clearance outline)
				(anchor circle)
			)
			(primitives
				(gr_poly
					(pts
						(arc
							(start -0.1778 0.2794)
							(mid -0.249642 0.249642)
							(end -0.2794 0.1778)
						)
						(arc
							(start -0.2794 -0.1778)
							(mid -0.249642 -0.249642)
							(end -0.1778 -0.2794)
						)
						(arc
							(start 0.1778 -0.2794)
							(mid 0.249642 -0.249642)
							(end 0.2794 -0.1778)
						)
						(arc
							(start 0.2794 0.1778)
							(mid 0.249642 0.249642)
							(end 0.1778 0.2794)
						)
					)
					(width 0)
					(fill yes)
				)
			)
		)
	)
	(footprint ""
		(layer "B.Cu")
		(at 113.411 -44.2214 180)
		(property "Reference" "C66"
			(at 0 0 0)
			(layer "B.SilkS")
			(hide yes)
			(effects
				(font
					(size 1.27 1.27)
				)
				(justify mirror)
			)
		)
		(property "Value" "SCD01U16V1KX-GP"
			(at 2.8321 -1.7399 180)
			(unlocked yes)
			(layer "B.Fab")
			(hide yes)
			(effects
				(font
					(size 1.016 1.016)
					(thickness 0.1524)
				)
				(justify mirror)
			)
		)
		(property "Device Type" "C0201H13"
			(at 2.8321 -3.2639 180)
			(unlocked yes)
			(layer "B.Fab")
			(hide yes)
			(effects
				(font
					(size 1.016 1.016)
					(thickness 0.1524)
				)
				(justify mirror)
			)
		)
		(duplicate_pad_numbers_are_jumpers no)
		(fp_rect
			(start 0.2794 0.6477)
			(end -0.2794 -0.6477)
			(stroke
				(width 0)
				(type default)
			)
			(fill no)
			(layer "B.CrtYd")
		)
		(fp_rect
			(start 0.2794 0.6477)
			(end -0.2794 -0.6477)
			(stroke
				(width 0)
				(type default)
			)
			(fill no)
			(layer "B.Fab")
		)
		(pad "1" smd custom
			(at 0 -0.2794)
			(size 0.0762 0.0762)
			(layers "B.Cu" "B.Mask" "B.Paste")
			(net "PHY_DPB_TO_SCC_27_DN")
			(options
				(clearance outline)
				(anchor circle)
			)
			(primitives
				(gr_poly
					(pts
						(arc
							(start 0.1524 0.127)
							(mid 0.137521 0.162921)
							(end 0.1016 0.1778)
						)
						(arc
							(start -0.1016 0.1778)
							(mid -0.137521 0.162921)
							(end -0.1524 0.127)
						)
						(arc
							(start -0.1524 -0.127)
							(mid -0.137521 -0.162921)
							(end -0.1016 -0.1778)
						)
						(arc
							(start 0.1016 -0.1778)
							(mid 0.137521 -0.162921)
							(end 0.1524 -0.127)
						)
					)
					(width 0)
					(fill yes)
				)
			)
		)
		(pad "2" smd custom
			(at 0 0.2794)
			(size 0.0762 0.0762)
			(layers "B.Cu" "B.Mask" "B.Paste")
			(net "PHY_DPB_TO_SCC_C_27_DN")
			(options
				(clearance outline)
				(anchor circle)
			)
			(primitives
				(gr_poly
					(pts
						(arc
							(start 0.1524 0.127)
							(mid 0.137521 0.162921)
							(end 0.1016 0.1778)
						)
						(arc
							(start -0.1016 0.1778)
							(mid -0.137521 0.162921)
							(end -0.1524 0.127)
						)
						(arc
							(start -0.1524 -0.127)
							(mid -0.137521 -0.162921)
							(end -0.1016 -0.1778)
						)
						(arc
							(start 0.1016 -0.1778)
							(mid 0.137521 -0.162921)
							(end 0.1524 -0.127)
						)
					)
					(width 0)
					(fill yes)
				)
			)
		)
	)
	(footprint ""
		(layer "B.Cu")
		(at 183.144668 -46.42993 -90)
		(property "Reference" "C480"
			(at 0 0 90)
			(layer "B.SilkS")
			(hide yes)
			(effects
				(font
					(size 1.27 1.27)
				)
				(justify mirror)
			)
		)
		(property "Value" "SCD1U6D3V1KX-GP"
			(at 2.8321 -1.7399 270)
			(unlocked yes)
			(layer "B.Fab")
			(hide yes)
			(effects
				(font
					(size 1.016 1.016)
					(thickness 0.1524)
				)
				(justify mirror)
			)
		)
		(property "Device Type" "C0201H13"
			(at 2.8321 -3.2639 270)
			(unlocked yes)
			(layer "B.Fab")
			(hide yes)
			(effects
				(font
					(size 1.016 1.016)
					(thickness 0.1524)
				)
				(justify mirror)
			)
		)
		(duplicate_pad_numbers_are_jumpers no)
		(fp_rect
			(start 0.2794 0.6477)
			(end -0.2794 -0.6477)
			(stroke
				(width 0)
				(type default)
			)
			(fill no)
			(layer "B.CrtYd")
		)
		(fp_rect
			(start 0.2794 0.6477)
			(end -0.2794 -0.6477)
			(stroke
				(width 0)
				(type default)
			)
			(fill no)
			(layer "B.Fab")
		)
		(pad "1" smd custom
			(at 0 -0.2794 90)
			(size 0.0762 0.0762)
			(layers "B.Cu" "B.Mask" "B.Paste")
			(net "P1V8_C")
			(options
				(clearance outline)
				(anchor circle)
			)
			(primitives
				(gr_poly
					(pts
						(arc
							(start 0.1524 0.127)
							(mid 0.137521 0.162921)
							(end 0.1016 0.1778)
						)
						(arc
							(start -0.1016 0.1778)
							(mid -0.137521 0.162921)
							(end -0.1524 0.127)
						)
						(arc
							(start -0.1524 -0.127)
							(mid -0.137521 -0.162921)
							(end -0.1016 -0.1778)
						)
						(arc
							(start 0.1016 -0.1778)
							(mid 0.137521 -0.162921)
							(end 0.1524 -0.127)
						)
					)
					(width 0)
					(fill yes)
				)
			)
		)
		(pad "2" smd custom
			(at 0 0.2794 90)
			(size 0.0762 0.0762)
			(layers "B.Cu" "B.Mask" "B.Paste")
			(net "GND")
			(options
				(clearance outline)
				(anchor circle)
			)
			(primitives
				(gr_poly
					(pts
						(arc
							(start 0.1524 0.127)
							(mid 0.137521 0.162921)
							(end 0.1016 0.1778)
						)
						(arc
							(start -0.1016 0.1778)
							(mid -0.137521 0.162921)
							(end -0.1524 0.127)
						)
						(arc
							(start -0.1524 -0.127)
							(mid -0.137521 -0.162921)
							(end -0.1016 -0.1778)
						)
						(arc
							(start 0.1016 -0.1778)
							(mid 0.137521 -0.162921)
							(end 0.1524 -0.127)
						)
					)
					(width 0)
					(fill yes)
				)
			)
		)
	)
	(footprint ""
		(layer "B.Cu")
		(at 164.973 -31.9659 -90)
		(property "Reference" "C396"
			(at 0 0 90)
			(layer "B.SilkS")
			(hide yes)
			(effects
				(font
					(size 1.27 1.27)
				)
				(justify mirror)
			)
		)
		(property "Value" "SC1U16V2KX-7-GP"
			(at -1.7526 -1.6002 270)
			(unlocked yes)
			(layer "B.Fab")
			(hide yes)
			(effects
				(font
					(size 1.016 1.016)
					(thickness 0.1524)
				)
				(justify mirror)
			)
		)
		(property "Device Type" "C402-TO0D2H24"
			(at -1.7526 -3.1242 270)
			(unlocked yes)
			(layer "B.Fab")
			(hide yes)
			(effects
				(font
					(size 1.016 1.016)
					(thickness 0.1524)
				)
				(justify mirror)
			)
		)
		(duplicate_pad_numbers_are_jumpers no)
		(fp_rect
			(start 0.4826 0.889)
			(end -0.4826 -0.889)
			(stroke
				(width 0)
				(type default)
			)
			(fill no)
			(layer "B.CrtYd")
		)
		(fp_rect
			(start 0.4826 0.889)
			(end -0.4826 -0.889)
			(stroke
				(width 0)
				(type default)
			)
			(fill no)
			(layer "B.Fab")
		)
		(pad "1" smd custom
			(at 0 -0.4572 90)
			(size 0.1524 0.1524)
			(layers "B.Cu" "B.Mask" "B.Paste")
			(net "SAS0_AVDD")
			(options
				(clearance outline)
				(anchor circle)
			)
			(primitives
				(gr_poly
					(pts
						(arc
							(start -0.254 -0.3048)
							(mid -0.325842 -0.275042)
							(end -0.3556 -0.2032)
						)
						(arc
							(start -0.3556 0.2032)
							(mid -0.325842 0.275042)
							(end -0.254 0.3048)
						)
						(arc
							(start 0.254 0.3048)
							(mid 0.325842 0.275042)
							(end 0.3556 0.2032)
						)
						(arc
							(start 0.3556 -0.2032)
							(mid 0.325842 -0.275042)
							(end 0.254 -0.3048)
						)
					)
					(width 0)
					(fill yes)
				)
			)
		)
		(pad "2" smd custom
			(at 0 0.4572 90)
			(size 0.1524 0.1524)
			(layers "B.Cu" "B.Mask" "B.Paste")
			(net "GND")
			(options
				(clearance outline)
				(anchor circle)
			)
			(primitives
				(gr_poly
					(pts
						(arc
							(start -0.254 -0.3048)
							(mid -0.325842 -0.275042)
							(end -0.3556 -0.2032)
						)
						(arc
							(start -0.3556 0.2032)
							(mid -0.325842 0.275042)
							(end -0.254 0.3048)
						)
						(arc
							(start 0.254 0.3048)
							(mid 0.325842 0.275042)
							(end 0.3556 0.2032)
						)
						(arc
							(start 0.3556 -0.2032)
							(mid 0.325842 -0.275042)
							(end 0.254 -0.3048)
						)
					)
					(width 0)
					(fill yes)
				)
			)
		)
	)
	(footprint ""
		(layer "B.Cu")
		(at 103.505 -64.77 180)
		(property "Reference" "C198"
			(at 0 0 0)
			(layer "B.SilkS")
			(hide yes)
			(effects
				(font
					(size 1.27 1.27)
				)
				(justify mirror)
			)
		)
		(property "Value" "SC1U6D3V1MX-GP"
			(at -1.9177 2.0193 180)
			(unlocked yes)
			(layer "B.Fab")
			(hide yes)
			(effects
				(font
					(size 1.016 1.016)
					(thickness 0.1524)
				)
				(justify mirror)
			)
		)
		(property "Device Type" "C0201H14"
			(at -1.9177 0.4953 180)
			(unlocked yes)
			(layer "B.Fab")
			(hide yes)
			(effects
				(font
					(size 1.016 1.016)
					(thickness 0.1524)
				)
				(justify mirror)
			)
		)
		(duplicate_pad_numbers_are_jumpers no)
		(fp_rect
			(start 0.1524 0.3048)
			(end -0.1524 -0.3048)
			(stroke
				(width 0)
				(type default)
			)
			(fill no)
			(layer "B.CrtYd")
		)
		(fp_poly
			(pts
				(xy 0.2794 0.6477) (xy 0.2794 -0.6477) (xy -0.2794 -0.6477) (xy -0.2794 -0.1905) (xy -0.1524 -0.1905)
				(xy -0.1524 -0.3048) (xy 0.1524 -0.3048) (xy 0.1524 0.3048) (xy -0.1524 0.3048) (xy -0.1524 -0.1778)
				(xy -0.2794 -0.1778) (xy -0.2794 0.6477)
			)
			(stroke
				(width 0)
				(type default)
			)
			(fill no)
			(layer "B.CrtYd")
		)
		(fp_rect
			(start 0.2794 0.6477)
			(end -0.2794 -0.6477)
			(stroke
				(width 0)
				(type default)
			)
			(fill no)
			(layer "B.Fab")
		)
		(pad "1" smd custom
			(at 0 -0.2794)
			(size 0.0762 0.0762)
			(layers "B.Cu" "B.Mask" "B.Paste")
			(net "SYSPLL_VDDA18")
			(options
				(clearance outline)
				(anchor circle)
			)
			(primitives
				(gr_poly
					(pts
						(arc
							(start 0.1524 0.127)
							(mid 0.137521 0.162921)
							(end 0.1016 0.1778)
						)
						(arc
							(start -0.1016 0.1778)
							(mid -0.137521 0.162921)
							(end -0.1524 0.127)
						)
						(arc
							(start -0.1524 -0.127)
							(mid -0.137521 -0.162921)
							(end -0.1016 -0.1778)
						)
						(arc
							(start 0.1016 -0.1778)
							(mid 0.137521 -0.162921)
							(end 0.1524 -0.127)
						)
					)
					(width 0)
					(fill yes)
				)
			)
		)
		(pad "2" smd custom
			(at 0 0.2794)
			(size 0.0762 0.0762)
			(layers "B.Cu" "B.Mask" "B.Paste")
			(net "GND")
			(options
				(clearance outline)
				(anchor circle)
			)
			(primitives
				(gr_poly
					(pts
						(arc
							(start 0.1524 0.127)
							(mid 0.137521 0.162921)
							(end 0.1016 0.1778)
						)
						(arc
							(start -0.1016 0.1778)
							(mid -0.137521 0.162921)
							(end -0.1524 0.127)
						)
						(arc
							(start -0.1524 -0.127)
							(mid -0.137521 -0.162921)
							(end -0.1016 -0.1778)
						)
						(arc
							(start 0.1016 -0.1778)
							(mid 0.137521 -0.162921)
							(end 0.1524 -0.127)
						)
					)
					(width 0)
					(fill yes)
				)
			)
		)
	)
	(footprint ""
		(layer "B.Cu")
		(at 127.970788 -58.493914 -90)
		(property "Reference" "C309"
			(at 0 0 90)
			(layer "B.SilkS")
			(hide yes)
			(effects
				(font
					(size 1.27 1.27)
				)
				(justify mirror)
			)
		)
		(property "Value" "SC1U6D3V1MX-GP"
			(at -1.9177 2.0193 270)
			(unlocked yes)
			(layer "B.Fab")
			(hide yes)
			(effects
				(font
					(size 1.016 1.016)
					(thickness 0.1524)
				)
				(justify mirror)
			)
		)
		(property "Device Type" "C0201H14"
			(at -1.9177 0.4953 270)
			(unlocked yes)
			(layer "B.Fab")
			(hide yes)
			(effects
				(font
					(size 1.016 1.016)
					(thickness 0.1524)
				)
				(justify mirror)
			)
		)
		(duplicate_pad_numbers_are_jumpers no)
		(fp_rect
			(start 0.1524 0.3048)
			(end -0.1524 -0.3048)
			(stroke
				(width 0)
				(type default)
			)
			(fill no)
			(layer "B.CrtYd")
		)
		(fp_poly
			(pts
				(xy 0.2794 0.6477) (xy 0.2794 -0.6477) (xy -0.2794 -0.6477) (xy -0.2794 -0.1905) (xy -0.1524 -0.1905)
				(xy -0.1524 -0.3048) (xy 0.1524 -0.3048) (xy 0.1524 0.3048) (xy -0.1524 0.3048) (xy -0.1524 -0.1778)
				(xy -0.2794 -0.1778) (xy -0.2794 0.6477)
			)
			(stroke
				(width 0)
				(type default)
			)
			(fill no)
			(layer "B.CrtYd")
		)
		(fp_rect
			(start 0.2794 0.6477)
			(end -0.2794 -0.6477)
			(stroke
				(width 0)
				(type default)
			)
			(fill no)
			(layer "B.Fab")
		)
		(pad "1" smd custom
			(at 0 -0.2794 90)
			(size 0.0762 0.0762)
			(layers "B.Cu" "B.Mask" "B.Paste")
			(net "GB_VDDA")
			(options
				(clearance outline)
				(anchor circle)
			)
			(primitives
				(gr_poly
					(pts
						(arc
							(start 0.1524 0.127)
							(mid 0.137521 0.162921)
							(end 0.1016 0.1778)
						)
						(arc
							(start -0.1016 0.1778)
							(mid -0.137521 0.162921)
							(end -0.1524 0.127)
						)
						(arc
							(start -0.1524 -0.127)
							(mid -0.137521 -0.162921)
							(end -0.1016 -0.1778)
						)
						(arc
							(start 0.1016 -0.1778)
							(mid 0.137521 -0.162921)
							(end 0.1524 -0.127)
						)
					)
					(width 0)
					(fill yes)
				)
			)
		)
		(pad "2" smd custom
			(at 0 0.2794 90)
			(size 0.0762 0.0762)
			(layers "B.Cu" "B.Mask" "B.Paste")
			(net "GND")
			(options
				(clearance outline)
				(anchor circle)
			)
			(primitives
				(gr_poly
					(pts
						(arc
							(start 0.1524 0.127)
							(mid 0.137521 0.162921)
							(end 0.1016 0.1778)
						)
						(arc
							(start -0.1016 0.1778)
							(mid -0.137521 0.162921)
							(end -0.1524 0.127)
						)
						(arc
							(start -0.1524 -0.127)
							(mid -0.137521 -0.162921)
							(end -0.1016 -0.1778)
						)
						(arc
							(start 0.1016 -0.1778)
							(mid 0.137521 -0.162921)
							(end 0.1524 -0.127)
						)
					)
					(width 0)
					(fill yes)
				)
			)
		)
	)
	(footprint ""
		(layer "B.Cu")
		(at 114.8207 -66.3575)
		(property "Reference" "C162"
			(at 0 0 0)
			(layer "B.SilkS")
			(hide yes)
			(effects
				(font
					(size 1.27 1.27)
				)
				(justify mirror)
			)
		)
		(property "Value" "SCD1U6D3V1KX-GP"
			(at 2.8321 -1.7399 0)
			(unlocked yes)
			(layer "B.Fab")
			(hide yes)
			(effects
				(font
					(size 1.016 1.016)
					(thickness 0.1524)
				)
				(justify mirror)
			)
		)
		(property "Device Type" "C0201H13"
			(at 2.8321 -3.2639 0)
			(unlocked yes)
			(layer "B.Fab")
			(hide yes)
			(effects
				(font
					(size 1.016 1.016)
					(thickness 0.1524)
				)
				(justify mirror)
			)
		)
		(duplicate_pad_numbers_are_jumpers no)
		(fp_rect
			(start 0.2794 0.6477)
			(end -0.2794 -0.6477)
			(stroke
				(width 0)
				(type default)
			)
			(fill no)
			(layer "B.CrtYd")
		)
		(fp_rect
			(start 0.2794 0.6477)
			(end -0.2794 -0.6477)
			(stroke
				(width 0)
				(type default)
			)
			(fill no)
			(layer "B.Fab")
		)
		(pad "1" smd custom
			(at 0 -0.2794 180)
			(size 0.0762 0.0762)
			(layers "B.Cu" "B.Mask" "B.Paste")
			(net "P0V9")
			(options
				(clearance outline)
				(anchor circle)
			)
			(primitives
				(gr_poly
					(pts
						(arc
							(start 0.1524 0.127)
							(mid 0.137521 0.162921)
							(end 0.1016 0.1778)
						)
						(arc
							(start -0.1016 0.1778)
							(mid -0.137521 0.162921)
							(end -0.1524 0.127)
						)
						(arc
							(start -0.1524 -0.127)
							(mid -0.137521 -0.162921)
							(end -0.1016 -0.1778)
						)
						(arc
							(start 0.1016 -0.1778)
							(mid 0.137521 -0.162921)
							(end 0.1524 -0.127)
						)
					)
					(width 0)
					(fill yes)
				)
			)
		)
		(pad "2" smd custom
			(at 0 0.2794 180)
			(size 0.0762 0.0762)
			(layers "B.Cu" "B.Mask" "B.Paste")
			(net "GND")
			(options
				(clearance outline)
				(anchor circle)
			)
			(primitives
				(gr_poly
					(pts
						(arc
							(start 0.1524 0.127)
							(mid 0.137521 0.162921)
							(end 0.1016 0.1778)
						)
						(arc
							(start -0.1016 0.1778)
							(mid -0.137521 0.162921)
							(end -0.1524 0.127)
						)
						(arc
							(start -0.1524 -0.127)
							(mid -0.137521 -0.162921)
							(end -0.1016 -0.1778)
						)
						(arc
							(start 0.1016 -0.1778)
							(mid 0.137521 -0.162921)
							(end 0.1524 -0.127)
						)
					)
					(width 0)
					(fill yes)
				)
			)
		)
	)
	(footprint ""
		(layer "B.Cu")
		(at 118.7704 -59.4487)
		(property "Reference" "C513"
			(at 0 0 0)
			(layer "B.SilkS")
			(hide yes)
			(effects
				(font
					(size 1.27 1.27)
				)
				(justify mirror)
			)
		)
		(property "Value" "SCD1U6D3V1KX-GP"
			(at 2.8321 -1.7399 0)
			(unlocked yes)
			(layer "B.Fab")
			(hide yes)
			(effects
				(font
					(size 1.016 1.016)
					(thickness 0.1524)
				)
				(justify mirror)
			)
		)
		(property "Device Type" "C0201H13"
			(at 2.8321 -3.2639 0)
			(unlocked yes)
			(layer "B.Fab")
			(hide yes)
			(effects
				(font
					(size 1.016 1.016)
					(thickness 0.1524)
				)
				(justify mirror)
			)
		)
		(duplicate_pad_numbers_are_jumpers no)
		(fp_rect
			(start 0.2794 0.6477)
			(end -0.2794 -0.6477)
			(stroke
				(width 0)
				(type default)
			)
			(fill no)
			(layer "B.CrtYd")
		)
		(fp_rect
			(start 0.2794 0.6477)
			(end -0.2794 -0.6477)
			(stroke
				(width 0)
				(type default)
			)
			(fill no)
			(layer "B.Fab")
		)
		(pad "1" smd custom
			(at 0 -0.2794 180)
			(size 0.0762 0.0762)
			(layers "B.Cu" "B.Mask" "B.Paste")
			(net "GB_VDDA")
			(options
				(clearance outline)
				(anchor circle)
			)
			(primitives
				(gr_poly
					(pts
						(arc
							(start 0.1524 0.127)
							(mid 0.137521 0.162921)
							(end 0.1016 0.1778)
						)
						(arc
							(start -0.1016 0.1778)
							(mid -0.137521 0.162921)
							(end -0.1524 0.127)
						)
						(arc
							(start -0.1524 -0.127)
							(mid -0.137521 -0.162921)
							(end -0.1016 -0.1778)
						)
						(arc
							(start 0.1016 -0.1778)
							(mid 0.137521 -0.162921)
							(end 0.1524 -0.127)
						)
					)
					(width 0)
					(fill yes)
				)
			)
		)
		(pad "2" smd custom
			(at 0 0.2794 180)
			(size 0.0762 0.0762)
			(layers "B.Cu" "B.Mask" "B.Paste")
			(net "GND")
			(options
				(clearance outline)
				(anchor circle)
			)
			(primitives
				(gr_poly
					(pts
						(arc
							(start 0.1524 0.127)
							(mid 0.137521 0.162921)
							(end 0.1016 0.1778)
						)
						(arc
							(start -0.1016 0.1778)
							(mid -0.137521 0.162921)
							(end -0.1524 0.127)
						)
						(arc
							(start -0.1524 -0.127)
							(mid -0.137521 -0.162921)
							(end -0.1016 -0.1778)
						)
						(arc
							(start 0.1016 -0.1778)
							(mid 0.137521 -0.162921)
							(end 0.1524 -0.127)
						)
					)
					(width 0)
					(fill yes)
				)
			)
		)
	)
	(footprint ""
		(layer "B.Cu")
		(at 163.2966 -33.2994 90)
		(property "Reference" "C373"
			(at 0 0 90)
			(layer "B.SilkS")
			(hide yes)
			(effects
				(font
					(size 1.27 1.27)
				)
				(justify mirror)
			)
		)
		(property "Value" "SC1U16V2KX-7-GP"
			(at -1.7526 -1.6002 90)
			(unlocked yes)
			(layer "B.Fab")
			(hide yes)
			(effects
				(font
					(size 1.016 1.016)
					(thickness 0.1524)
				)
				(justify mirror)
			)
		)
		(property "Device Type" "C402-TO0D2H24"
			(at -1.7526 -3.1242 90)
			(unlocked yes)
			(layer "B.Fab")
			(hide yes)
			(effects
				(font
					(size 1.016 1.016)
					(thickness 0.1524)
				)
				(justify mirror)
			)
		)
		(duplicate_pad_numbers_are_jumpers no)
		(fp_rect
			(start 0.4826 0.889)
			(end -0.4826 -0.889)
			(stroke
				(width 0)
				(type default)
			)
			(fill no)
			(layer "B.CrtYd")
		)
		(fp_rect
			(start 0.4826 0.889)
			(end -0.4826 -0.889)
			(stroke
				(width 0)
				(type default)
			)
			(fill no)
			(layer "B.Fab")
		)
		(pad "1" smd custom
			(at 0 -0.4572 270)
			(size 0.1524 0.1524)
			(layers "B.Cu" "B.Mask" "B.Paste")
			(net "SAS0_VDDH")
			(options
				(clearance outline)
				(anchor circle)
			)
			(primitives
				(gr_poly
					(pts
						(arc
							(start -0.254 -0.3048)
							(mid -0.325842 -0.275042)
							(end -0.3556 -0.2032)
						)
						(arc
							(start -0.3556 0.2032)
							(mid -0.325842 0.275042)
							(end -0.254 0.3048)
						)
						(arc
							(start 0.254 0.3048)
							(mid 0.325842 0.275042)
							(end 0.3556 0.2032)
						)
						(arc
							(start 0.3556 -0.2032)
							(mid 0.325842 -0.275042)
							(end 0.254 -0.3048)
						)
					)
					(width 0)
					(fill yes)
				)
			)
		)
		(pad "2" smd custom
			(at 0 0.4572 270)
			(size 0.1524 0.1524)
			(layers "B.Cu" "B.Mask" "B.Paste")
			(net "GND")
			(options
				(clearance outline)
				(anchor circle)
			)
			(primitives
				(gr_poly
					(pts
						(arc
							(start -0.254 -0.3048)
							(mid -0.325842 -0.275042)
							(end -0.3556 -0.2032)
						)
						(arc
							(start -0.3556 0.2032)
							(mid -0.325842 0.275042)
							(end -0.254 0.3048)
						)
						(arc
							(start 0.254 0.3048)
							(mid 0.325842 0.275042)
							(end 0.3556 0.2032)
						)
						(arc
							(start 0.3556 -0.2032)
							(mid 0.325842 -0.275042)
							(end 0.254 -0.3048)
						)
					)
					(width 0)
					(fill yes)
				)
			)
		)
	)
	(footprint ""
		(layer "B.Cu")
		(at 159.1056 -50.419)
		(property "Reference" "TP79"
			(at 0 0 0)
			(layer "B.SilkS")
			(hide yes)
			(effects
				(font
					(size 1.27 1.27)
				)
				(justify mirror)
			)
		)
		(property "Value" "TPAD28-2-GP"
			(at 0.0127 -1.6637 0)
			(unlocked yes)
			(layer "B.Fab")
			(hide yes)
			(effects
				(font
					(size 1.016 1.016)
					(thickness 0.1524)
				)
				(justify mirror)
			)
		)
		(property "Device Type" "TPAD28"
			(at 0.0127 -3.1877 0)
			(unlocked yes)
			(layer "B.Fab")
			(hide yes)
			(effects
				(font
					(size 1.016 1.016)
					(thickness 0.1524)
				)
				(justify mirror)
			)
		)
		(duplicate_pad_numbers_are_jumpers no)
		(fp_poly
			(pts
				(arc
					(start 0.3556 0)
					(mid -0.3556 0)
					(end 0.3556 0)
				)
			)
			(stroke
				(width 0)
				(type default)
			)
			(fill no)
			(layer "B.CrtYd")
		)
		(fp_poly
			(pts
				(arc
					(start 0.6096 0)
					(mid -0.6096 0)
					(end 0.6096 0)
				)
			)
			(stroke
				(width 0)
				(type default)
			)
			(fill no)
			(layer "B.Fab")
		)
		(pad "1" smd circle
			(at 0 0 180)
			(size 0.7112 0.7112)
			(layers "B.Cu" "B.Mask" "B.Paste")
			(net "SIO_CLK_0")
		)
	)
	(footprint ""
		(layer "B.Cu")
		(at 160.401 -27.178 180)
		(property "Reference" "R282"
			(at 0 0 0)
			(layer "B.SilkS")
			(hide yes)
			(effects
				(font
					(size 1.27 1.27)
				)
				(justify mirror)
			)
		)
		(property "Value" "10R2F-L-GP"
			(at -0.064008 -3.993896 180)
			(unlocked yes)
			(layer "B.Fab")
			(hide yes)
			(effects
				(font
					(size 1.016 1.016)
					(thickness 0.1524)
				)
				(justify mirror)
			)
		)
		(property "Device Type" "R402H14"
			(at -0.064008 -5.517896 180)
			(unlocked yes)
			(layer "B.Fab")
			(hide yes)
			(effects
				(font
					(size 1.016 1.016)
					(thickness 0.1524)
				)
				(justify mirror)
			)
		)
		(duplicate_pad_numbers_are_jumpers no)
		(fp_line
			(start 0.508 -0.9398)
			(end 0.508 0.9398)
			(stroke
				(width 0.1524)
				(type default)
			)
			(layer "B.SilkS")
		)
		(fp_line
			(start -0.508 -0.9398)
			(end 0.508 -0.9398)
			(stroke
				(width 0.1524)
				(type default)
			)
			(layer "B.SilkS")
		)
		(fp_rect
			(start 0.508 0.9398)
			(end -0.508 -0.9398)
			(stroke
				(width 0)
				(type default)
			)
			(fill no)
			(layer "B.CrtYd")
		)
		(fp_rect
			(start 0.508 0.9398)
			(end -0.508 -0.9398)
			(stroke
				(width 0)
				(type default)
			)
			(fill no)
			(layer "B.Fab")
		)
		(pad "1" smd custom
			(at 0 -0.4445)
			(size 0.1397 0.1397)
			(layers "B.Cu" "B.Mask" "B.Paste")
			(net "P1V8_C")
			(options
				(clearance outline)
				(anchor circle)
			)
			(primitives
				(gr_poly
					(pts
						(arc
							(start -0.1778 0.2794)
							(mid -0.249642 0.249642)
							(end -0.2794 0.1778)
						)
						(arc
							(start -0.2794 -0.1778)
							(mid -0.249642 -0.249642)
							(end -0.1778 -0.2794)
						)
						(arc
							(start 0.1778 -0.2794)
							(mid 0.249642 -0.249642)
							(end 0.2794 -0.1778)
						)
						(arc
							(start 0.2794 0.1778)
							(mid 0.249642 0.249642)
							(end 0.1778 0.2794)
						)
					)
					(width 0)
					(fill yes)
				)
			)
		)
		(pad "2" smd custom
			(at 0 0.4445)
			(size 0.1397 0.1397)
			(layers "B.Cu" "B.Mask" "B.Paste")
			(net "SAS0_VDDH")
			(options
				(clearance outline)
				(anchor circle)
			)
			(primitives
				(gr_poly
					(pts
						(arc
							(start -0.1778 0.2794)
							(mid -0.249642 0.249642)
							(end -0.2794 0.1778)
						)
						(arc
							(start -0.2794 -0.1778)
							(mid -0.249642 -0.249642)
							(end -0.1778 -0.2794)
						)
						(arc
							(start 0.1778 -0.2794)
							(mid 0.249642 -0.249642)
							(end 0.2794 -0.1778)
						)
						(arc
							(start 0.2794 0.1778)
							(mid 0.249642 0.249642)
							(end 0.1778 0.2794)
						)
					)
					(width 0)
					(fill yes)
				)
			)
		)
	)
	(footprint ""
		(layer "B.Cu")
		(at 179.187348 -49.62271 -90)
		(property "Reference" "C498"
			(at 0 0 90)
			(layer "B.SilkS")
			(hide yes)
			(effects
				(font
					(size 1.27 1.27)
				)
				(justify mirror)
			)
		)
		(property "Value" "SC1KP50V2KX-1GP"
			(at -1.1811 -2.7051 270)
			(unlocked yes)
			(layer "B.Fab")
			(hide yes)
			(effects
				(font
					(size 1.016 1.016)
					(thickness 0.1524)
				)
				(justify mirror)
			)
		)
		(property "Device Type" "C402H22"
			(at -1.1811 -4.2291 270)
			(unlocked yes)
			(layer "B.Fab")
			(hide yes)
			(effects
				(font
					(size 1.016 1.016)
					(thickness 0.1524)
				)
				(justify mirror)
			)
		)
		(duplicate_pad_numbers_are_jumpers no)
		(fp_rect
			(start 0.4318 0.9525)
			(end -0.4318 -0.9525)
			(stroke
				(width 0)
				(type default)
			)
			(fill no)
			(layer "B.CrtYd")
		)
		(fp_rect
			(start 0.4318 0.9525)
			(end -0.4318 -0.9525)
			(stroke
				(width 0)
				(type default)
			)
			(fill no)
			(layer "B.Fab")
		)
		(pad "1" smd custom
			(at 0 -0.4445 90)
			(size 0.1524 0.1524)
			(layers "B.Cu" "B.Mask" "B.Paste")
			(net "P1V8_C")
			(options
				(clearance outline)
				(anchor circle)
			)
			(primitives
				(gr_poly
					(pts
						(arc
							(start 0.3048 0.2032)
							(mid 0.275042 0.275042)
							(end 0.2032 0.3048)
						)
						(arc
							(start -0.2032 0.3048)
							(mid -0.275042 0.275042)
							(end -0.3048 0.2032)
						)
						(arc
							(start -0.3048 -0.2032)
							(mid -0.275042 -0.275042)
							(end -0.2032 -0.3048)
						)
						(arc
							(start 0.2032 -0.3048)
							(mid 0.275042 -0.275042)
							(end 0.3048 -0.2032)
						)
					)
					(width 0)
					(fill yes)
				)
			)
		)
		(pad "2" smd custom
			(at 0 0.4445 90)
			(size 0.1524 0.1524)
			(layers "B.Cu" "B.Mask" "B.Paste")
			(net "GND")
			(options
				(clearance outline)
				(anchor circle)
			)
			(primitives
				(gr_poly
					(pts
						(arc
							(start 0.3048 0.2032)
							(mid 0.275042 0.275042)
							(end 0.2032 0.3048)
						)
						(arc
							(start -0.2032 0.3048)
							(mid -0.275042 0.275042)
							(end -0.3048 0.2032)
						)
						(arc
							(start -0.3048 -0.2032)
							(mid -0.275042 -0.275042)
							(end -0.2032 -0.3048)
						)
						(arc
							(start 0.2032 -0.3048)
							(mid 0.275042 -0.275042)
							(end 0.3048 -0.2032)
						)
					)
					(width 0)
					(fill yes)
				)
			)
		)
	)
	(footprint ""
		(layer "B.Cu")
		(at 103.505 -60.5028)
		(property "Reference" "C155"
			(at 0 0 0)
			(layer "B.SilkS")
			(hide yes)
			(effects
				(font
					(size 1.27 1.27)
				)
				(justify mirror)
			)
		)
		(property "Value" "SCD1U6D3V1KX-GP"
			(at 2.8321 -1.7399 0)
			(unlocked yes)
			(layer "B.Fab")
			(hide yes)
			(effects
				(font
					(size 1.016 1.016)
					(thickness 0.1524)
				)
				(justify mirror)
			)
		)
		(property "Device Type" "C0201H13"
			(at 2.8321 -3.2639 0)
			(unlocked yes)
			(layer "B.Fab")
			(hide yes)
			(effects
				(font
					(size 1.016 1.016)
					(thickness 0.1524)
				)
				(justify mirror)
			)
		)
		(duplicate_pad_numbers_are_jumpers no)
		(fp_rect
			(start 0.2794 0.6477)
			(end -0.2794 -0.6477)
			(stroke
				(width 0)
				(type default)
			)
			(fill no)
			(layer "B.CrtYd")
		)
		(fp_rect
			(start 0.2794 0.6477)
			(end -0.2794 -0.6477)
			(stroke
				(width 0)
				(type default)
			)
			(fill no)
			(layer "B.Fab")
		)
		(pad "1" smd custom
			(at 0 -0.2794 180)
			(size 0.0762 0.0762)
			(layers "B.Cu" "B.Mask" "B.Paste")
			(net "P1V8_E")
			(options
				(clearance outline)
				(anchor circle)
			)
			(primitives
				(gr_poly
					(pts
						(arc
							(start 0.1524 0.127)
							(mid 0.137521 0.162921)
							(end 0.1016 0.1778)
						)
						(arc
							(start -0.1016 0.1778)
							(mid -0.137521 0.162921)
							(end -0.1524 0.127)
						)
						(arc
							(start -0.1524 -0.127)
							(mid -0.137521 -0.162921)
							(end -0.1016 -0.1778)
						)
						(arc
							(start 0.1016 -0.1778)
							(mid 0.137521 -0.162921)
							(end 0.1524 -0.127)
						)
					)
					(width 0)
					(fill yes)
				)
			)
		)
		(pad "2" smd custom
			(at 0 0.2794 180)
			(size 0.0762 0.0762)
			(layers "B.Cu" "B.Mask" "B.Paste")
			(net "GND")
			(options
				(clearance outline)
				(anchor circle)
			)
			(primitives
				(gr_poly
					(pts
						(arc
							(start 0.1524 0.127)
							(mid 0.137521 0.162921)
							(end 0.1016 0.1778)
						)
						(arc
							(start -0.1016 0.1778)
							(mid -0.137521 0.162921)
							(end -0.1524 0.127)
						)
						(arc
							(start -0.1524 -0.127)
							(mid -0.137521 -0.162921)
							(end -0.1016 -0.1778)
						)
						(arc
							(start 0.1016 -0.1778)
							(mid 0.137521 -0.162921)
							(end 0.1524 -0.127)
						)
					)
					(width 0)
					(fill yes)
				)
			)
		)
	)
	(footprint ""
		(layer "B.Cu")
		(at 76.327 -35.941)
		(property "Reference" "C228"
			(at 0 0 0)
			(layer "B.SilkS")
			(hide yes)
			(effects
				(font
					(size 1.27 1.27)
				)
				(justify mirror)
			)
		)
		(property "Value" "SC22U6D3V3MX-9-GP-U"
			(at 0 -2.8194 0)
			(unlocked yes)
			(layer "B.Fab")
			(hide yes)
			(effects
				(font
					(size 1.016 1.016)
					(thickness 0.1524)
				)
				(justify mirror)
			)
		)
		(property "Device Type" "C603H40"
			(at 0 -4.3434 0)
			(unlocked yes)
			(layer "B.Fab")
			(hide yes)
			(effects
				(font
					(size 1.016 1.016)
					(thickness 0.1524)
				)
				(justify mirror)
			)
		)
		(duplicate_pad_numbers_are_jumpers no)
		(fp_line
			(start -0.508 0)
			(end 0.508 0)
			(stroke
				(width 0.2032)
				(type default)
			)
			(layer "B.SilkS")
		)
		(fp_rect
			(start 0.5842 1.3335)
			(end -0.5842 -1.3335)
			(stroke
				(width 0)
				(type default)
			)
			(fill no)
			(layer "B.CrtYd")
		)
		(fp_rect
			(start 0.5842 1.3335)
			(end -0.5842 -1.3335)
			(stroke
				(width 0)
				(type default)
			)
			(fill no)
			(layer "B.Fab")
		)
		(pad "1" smd custom
			(at 0 -0.762 180)
			(size 0.2159 0.2159)
			(layers "B.Cu" "B.Mask" "B.Paste")
			(net "GB_VDDA")
			(options
				(clearance outline)
				(anchor circle)
			)
			(primitives
				(gr_poly
					(pts
						(arc
							(start -0.3302 0.4318)
							(mid -0.402042 0.402042)
							(end -0.4318 0.3302)
						)
						(arc
							(start -0.4318 -0.3302)
							(mid -0.402042 -0.402042)
							(end -0.3302 -0.4318)
						)
						(arc
							(start 0.3302 -0.4318)
							(mid 0.402042 -0.402042)
							(end 0.4318 -0.3302)
						)
						(arc
							(start 0.4318 0.3302)
							(mid 0.402042 0.402042)
							(end 0.3302 0.4318)
						)
					)
					(width 0)
					(fill yes)
				)
			)
		)
		(pad "2" smd custom
			(at 0 0.762 180)
			(size 0.2159 0.2159)
			(layers "B.Cu" "B.Mask" "B.Paste")
			(net "GND")
			(options
				(clearance outline)
				(anchor circle)
			)
			(primitives
				(gr_poly
					(pts
						(arc
							(start -0.3302 0.4318)
							(mid -0.402042 0.402042)
							(end -0.4318 0.3302)
						)
						(arc
							(start -0.4318 -0.3302)
							(mid -0.402042 -0.402042)
							(end -0.3302 -0.4318)
						)
						(arc
							(start 0.3302 -0.4318)
							(mid 0.402042 -0.402042)
							(end 0.4318 -0.3302)
						)
						(arc
							(start 0.4318 0.3302)
							(mid 0.402042 0.402042)
							(end 0.3302 0.4318)
						)
					)
					(width 0)
					(fill yes)
				)
			)
		)
	)
	(footprint ""
		(layer "B.Cu")
		(at 86.4616 -70.55358 -90)
		(property "Reference" "C517"
			(at 0 0 90)
			(layer "B.SilkS")
			(hide yes)
			(effects
				(font
					(size 1.27 1.27)
				)
				(justify mirror)
			)
		)
		(property "Value" "SCD1U16V2KX-3GP"
			(at -1.1811 -2.7051 270)
			(unlocked yes)
			(layer "B.Fab")
			(hide yes)
			(effects
				(font
					(size 1.016 1.016)
					(thickness 0.1524)
				)
				(justify mirror)
			)
		)
		(property "Device Type" "C402H22"
			(at -1.1811 -4.2291 270)
			(unlocked yes)
			(layer "B.Fab")
			(hide yes)
			(effects
				(font
					(size 1.016 1.016)
					(thickness 0.1524)
				)
				(justify mirror)
			)
		)
		(duplicate_pad_numbers_are_jumpers no)
		(fp_rect
			(start 0.4318 0.9525)
			(end -0.4318 -0.9525)
			(stroke
				(width 0)
				(type default)
			)
			(fill no)
			(layer "B.CrtYd")
		)
		(fp_rect
			(start 0.4318 0.9525)
			(end -0.4318 -0.9525)
			(stroke
				(width 0)
				(type default)
			)
			(fill no)
			(layer "B.Fab")
		)
		(pad "1" smd custom
			(at 0 -0.4445 90)
			(size 0.1524 0.1524)
			(layers "B.Cu" "B.Mask" "B.Paste")
			(net "P1V8_E")
			(options
				(clearance outline)
				(anchor circle)
			)
			(primitives
				(gr_poly
					(pts
						(arc
							(start 0.3048 0.2032)
							(mid 0.275042 0.275042)
							(end 0.2032 0.3048)
						)
						(arc
							(start -0.2032 0.3048)
							(mid -0.275042 0.275042)
							(end -0.3048 0.2032)
						)
						(arc
							(start -0.3048 -0.2032)
							(mid -0.275042 -0.275042)
							(end -0.2032 -0.3048)
						)
						(arc
							(start 0.2032 -0.3048)
							(mid 0.275042 -0.275042)
							(end 0.3048 -0.2032)
						)
					)
					(width 0)
					(fill yes)
				)
			)
		)
		(pad "2" smd custom
			(at 0 0.4445 90)
			(size 0.1524 0.1524)
			(layers "B.Cu" "B.Mask" "B.Paste")
			(net "GND")
			(options
				(clearance outline)
				(anchor circle)
			)
			(primitives
				(gr_poly
					(pts
						(arc
							(start 0.3048 0.2032)
							(mid 0.275042 0.275042)
							(end 0.2032 0.3048)
						)
						(arc
							(start -0.2032 0.3048)
							(mid -0.275042 0.275042)
							(end -0.3048 0.2032)
						)
						(arc
							(start -0.3048 -0.2032)
							(mid -0.275042 -0.275042)
							(end -0.2032 -0.3048)
						)
						(arc
							(start 0.2032 -0.3048)
							(mid 0.275042 -0.275042)
							(end 0.3048 -0.2032)
						)
					)
					(width 0)
					(fill yes)
				)
			)
		)
	)
	(footprint ""
		(layer "B.Cu")
		(at 111.94796 -87.107776 180)
		(property "Reference" "R138"
			(at 0 0 0)
			(layer "B.SilkS")
			(hide yes)
			(effects
				(font
					(size 1.27 1.27)
				)
				(justify mirror)
			)
		)
		(property "Value" "4K75R2F-1-GP"
			(at -0.064008 -3.993896 180)
			(unlocked yes)
			(layer "B.Fab")
			(hide yes)
			(effects
				(font
					(size 1.016 1.016)
					(thickness 0.1524)
				)
				(justify mirror)
			)
		)
		(property "Device Type" "R402H16"
			(at -0.064008 -5.517896 180)
			(unlocked yes)
			(layer "B.Fab")
			(hide yes)
			(effects
				(font
					(size 1.016 1.016)
					(thickness 0.1524)
				)
				(justify mirror)
			)
		)
		(duplicate_pad_numbers_are_jumpers no)
		(fp_line
			(start 0.508 -0.9398)
			(end 0.508 0.9398)
			(stroke
				(width 0.1524)
				(type default)
			)
			(layer "B.SilkS")
		)
		(fp_line
			(start -0.508 -0.9398)
			(end 0.508 -0.9398)
			(stroke
				(width 0.1524)
				(type default)
			)
			(layer "B.SilkS")
		)
		(fp_rect
			(start 0.508 0.9398)
			(end -0.508 -0.9398)
			(stroke
				(width 0)
				(type default)
			)
			(fill no)
			(layer "B.CrtYd")
		)
		(fp_rect
			(start 0.508 0.9398)
			(end -0.508 -0.9398)
			(stroke
				(width 0)
				(type default)
			)
			(fill no)
			(layer "B.Fab")
		)
		(pad "1" smd custom
			(at 0 -0.4445)
			(size 0.1397 0.1397)
			(layers "B.Cu" "B.Mask" "B.Paste")
			(net "EXP_XM_NOR_CS_N")
			(options
				(clearance outline)
				(anchor circle)
			)
			(primitives
				(gr_poly
					(pts
						(arc
							(start -0.1778 0.2794)
							(mid -0.249642 0.249642)
							(end -0.2794 0.1778)
						)
						(arc
							(start -0.2794 -0.1778)
							(mid -0.249642 -0.249642)
							(end -0.1778 -0.2794)
						)
						(arc
							(start 0.1778 -0.2794)
							(mid 0.249642 -0.249642)
							(end 0.2794 -0.1778)
						)
						(arc
							(start 0.2794 0.1778)
							(mid 0.249642 0.249642)
							(end 0.1778 0.2794)
						)
					)
					(width 0)
					(fill yes)
				)
			)
		)
		(pad "2" smd custom
			(at 0 0.4445)
			(size 0.1397 0.1397)
			(layers "B.Cu" "B.Mask" "B.Paste")
			(net "P1V8_E")
			(options
				(clearance outline)
				(anchor circle)
			)
			(primitives
				(gr_poly
					(pts
						(arc
							(start -0.1778 0.2794)
							(mid -0.249642 0.249642)
							(end -0.2794 0.1778)
						)
						(arc
							(start -0.2794 -0.1778)
							(mid -0.249642 -0.249642)
							(end -0.1778 -0.2794)
						)
						(arc
							(start 0.1778 -0.2794)
							(mid 0.249642 -0.249642)
							(end 0.2794 -0.1778)
						)
						(arc
							(start 0.2794 0.1778)
							(mid 0.249642 0.249642)
							(end 0.1778 0.2794)
						)
					)
					(width 0)
					(fill yes)
				)
			)
		)
	)
	(footprint ""
		(layer "B.Cu")
		(at 90.986356 -78.323948 180)
		(property "Reference" "R155"
			(at 0 0 0)
			(layer "B.SilkS")
			(hide yes)
			(effects
				(font
					(size 1.27 1.27)
				)
				(justify mirror)
			)
		)
		(property "Value" "10R2F-L-GP"
			(at -0.064008 -3.993896 180)
			(unlocked yes)
			(layer "B.Fab")
			(hide yes)
			(effects
				(font
					(size 1.016 1.016)
					(thickness 0.1524)
				)
				(justify mirror)
			)
		)
		(property "Device Type" "R402H14"
			(at -0.064008 -5.517896 180)
			(unlocked yes)
			(layer "B.Fab")
			(hide yes)
			(effects
				(font
					(size 1.016 1.016)
					(thickness 0.1524)
				)
				(justify mirror)
			)
		)
		(duplicate_pad_numbers_are_jumpers no)
		(fp_line
			(start 0.508 -0.9398)
			(end 0.508 0.9398)
			(stroke
				(width 0.1524)
				(type default)
			)
			(layer "B.SilkS")
		)
		(fp_line
			(start -0.508 -0.9398)
			(end 0.508 -0.9398)
			(stroke
				(width 0.1524)
				(type default)
			)
			(layer "B.SilkS")
		)
		(fp_rect
			(start 0.508 0.9398)
			(end -0.508 -0.9398)
			(stroke
				(width 0)
				(type default)
			)
			(fill no)
			(layer "B.CrtYd")
		)
		(fp_rect
			(start 0.508 0.9398)
			(end -0.508 -0.9398)
			(stroke
				(width 0)
				(type default)
			)
			(fill no)
			(layer "B.Fab")
		)
		(pad "1" smd custom
			(at 0 -0.4445)
			(size 0.1397 0.1397)
			(layers "B.Cu" "B.Mask" "B.Paste")
			(net "P0V9")
			(options
				(clearance outline)
				(anchor circle)
			)
			(primitives
				(gr_poly
					(pts
						(arc
							(start -0.1778 0.2794)
							(mid -0.249642 0.249642)
							(end -0.2794 0.1778)
						)
						(arc
							(start -0.2794 -0.1778)
							(mid -0.249642 -0.249642)
							(end -0.1778 -0.2794)
						)
						(arc
							(start 0.1778 -0.2794)
							(mid 0.249642 -0.249642)
							(end 0.2794 -0.1778)
						)
						(arc
							(start 0.2794 0.1778)
							(mid 0.249642 0.249642)
							(end 0.1778 0.2794)
						)
					)
					(width 0)
					(fill yes)
				)
			)
		)
		(pad "2" smd custom
			(at 0 0.4445)
			(size 0.1397 0.1397)
			(layers "B.Cu" "B.Mask" "B.Paste")
			(net "SYSPLL_VDDA09")
			(options
				(clearance outline)
				(anchor circle)
			)
			(primitives
				(gr_poly
					(pts
						(arc
							(start -0.1778 0.2794)
							(mid -0.249642 0.249642)
							(end -0.2794 0.1778)
						)
						(arc
							(start -0.2794 -0.1778)
							(mid -0.249642 -0.249642)
							(end -0.1778 -0.2794)
						)
						(arc
							(start 0.1778 -0.2794)
							(mid 0.249642 -0.249642)
							(end 0.2794 -0.1778)
						)
						(arc
							(start 0.2794 0.1778)
							(mid 0.249642 0.249642)
							(end 0.1778 0.2794)
						)
					)
					(width 0)
					(fill yes)
				)
			)
		)
	)
	(footprint ""
		(layer "B.Cu")
		(at 179.68214 -43.139868 90)
		(property "Reference" "C449"
			(at 0 0 90)
			(layer "B.SilkS")
			(hide yes)
			(effects
				(font
					(size 1.27 1.27)
				)
				(justify mirror)
			)
		)
		(property "Value" "SC1KP50V2KX-1GP"
			(at -1.1811 -2.7051 90)
			(unlocked yes)
			(layer "B.Fab")
			(hide yes)
			(effects
				(font
					(size 1.016 1.016)
					(thickness 0.1524)
				)
				(justify mirror)
			)
		)
		(property "Device Type" "C402H22"
			(at -1.1811 -4.2291 90)
			(unlocked yes)
			(layer "B.Fab")
			(hide yes)
			(effects
				(font
					(size 1.016 1.016)
					(thickness 0.1524)
				)
				(justify mirror)
			)
		)
		(duplicate_pad_numbers_are_jumpers no)
		(fp_rect
			(start 0.4318 0.9525)
			(end -0.4318 -0.9525)
			(stroke
				(width 0)
				(type default)
			)
			(fill no)
			(layer "B.CrtYd")
		)
		(fp_rect
			(start 0.4318 0.9525)
			(end -0.4318 -0.9525)
			(stroke
				(width 0)
				(type default)
			)
			(fill no)
			(layer "B.Fab")
		)
		(pad "1" smd custom
			(at 0 -0.4445 270)
			(size 0.1524 0.1524)
			(layers "B.Cu" "B.Mask" "B.Paste")
			(net "P0V975")
			(options
				(clearance outline)
				(anchor circle)
			)
			(primitives
				(gr_poly
					(pts
						(arc
							(start 0.3048 0.2032)
							(mid 0.275042 0.275042)
							(end 0.2032 0.3048)
						)
						(arc
							(start -0.2032 0.3048)
							(mid -0.275042 0.275042)
							(end -0.3048 0.2032)
						)
						(arc
							(start -0.3048 -0.2032)
							(mid -0.275042 -0.275042)
							(end -0.2032 -0.3048)
						)
						(arc
							(start 0.2032 -0.3048)
							(mid 0.275042 -0.275042)
							(end 0.3048 -0.2032)
						)
					)
					(width 0)
					(fill yes)
				)
			)
		)
		(pad "2" smd custom
			(at 0 0.4445 270)
			(size 0.1524 0.1524)
			(layers "B.Cu" "B.Mask" "B.Paste")
			(net "GND")
			(options
				(clearance outline)
				(anchor circle)
			)
			(primitives
				(gr_poly
					(pts
						(arc
							(start 0.3048 0.2032)
							(mid 0.275042 0.275042)
							(end 0.2032 0.3048)
						)
						(arc
							(start -0.2032 0.3048)
							(mid -0.275042 0.275042)
							(end -0.3048 0.2032)
						)
						(arc
							(start -0.3048 -0.2032)
							(mid -0.275042 -0.275042)
							(end -0.2032 -0.3048)
						)
						(arc
							(start 0.2032 -0.3048)
							(mid 0.275042 -0.275042)
							(end 0.3048 -0.2032)
						)
					)
					(width 0)
					(fill yes)
				)
			)
		)
	)
	(gr_line
		(start 99.000056 -55.000144)
		(end 99.499928 -55.500016)
		(stroke
			(width 0.052324)
			(type default)
		)
		(layer "F.Cu")
	)
	(gr_line
		(start 99.000056 -54.000146)
		(end 99.499928 -54.500018)
		(stroke
			(width 0.052324)
			(type default)
		)
		(layer "F.Cu")
	)
	(gr_line
		(start 100.000054 -52.00015)
		(end 100.499926 -52.500022)
		(stroke
			(width 0.052324)
			(type default)
		)
		(layer "F.Cu")
	)
	(gr_line
		(start 100.000054 -51.000152)
		(end 100.499926 -51.500024)
		(stroke
			(width 0.052324)
			(type default)
		)
		(layer "F.Cu")
	)
	(gr_line
		(start 101.000052 -56.000142)
		(end 101.499924 -56.500014)
		(stroke
			(width 0.052324)
			(type default)
		)
		(layer "F.Cu")
	)
	(gr_line
		(start 101.000052 -55.000144)
		(end 101.499924 -55.500016)
		(stroke
			(width 0.052324)
			(type default)
		)
		(layer "F.Cu")
	)
	(gr_line
		(start 101.000052 -53.000148)
		(end 101.499924 -53.50002)
		(stroke
			(width 0.052324)
			(type default)
		)
		(layer "F.Cu")
	)
	(gr_line
		(start 101.000052 -52.00015)
		(end 101.499924 -52.500022)
		(stroke
			(width 0.052324)
			(type default)
		)
		(layer "F.Cu")
	)
	(gr_line
		(start 102.00005 -56.000142)
		(end 102.499922 -56.500014)
		(stroke
			(width 0.052324)
			(type default)
		)
		(layer "F.Cu")
	)
	(gr_line
		(start 102.00005 -55.000144)
		(end 102.499922 -55.500016)
		(stroke
			(width 0.052324)
			(type default)
		)
		(layer "F.Cu")
	)
	(gr_line
		(start 102.00005 -52.00015)
		(end 102.499922 -52.500022)
		(stroke
			(width 0.052324)
			(type default)
		)
		(layer "F.Cu")
	)
	(gr_line
		(start 102.00005 -51.000152)
		(end 102.499922 -51.500024)
		(stroke
			(width 0.052324)
			(type default)
		)
		(layer "F.Cu")
	)
	(gr_line
		(start 103.000048 -56.000142)
		(end 103.49992 -56.500014)
		(stroke
			(width 0.052324)
			(type default)
		)
		(layer "F.Cu")
	)
	(gr_line
		(start 103.000048 -55.000144)
		(end 103.49992 -55.500016)
		(stroke
			(width 0.052324)
			(type default)
		)
		(layer "F.Cu")
	)
	(gr_line
		(start 103.000048 -53.000148)
		(end 103.49992 -53.50002)
		(stroke
			(width 0.052324)
			(type default)
		)
		(layer "F.Cu")
	)
	(gr_line
		(start 103.000048 -52.00015)
		(end 103.49992 -52.500022)
		(stroke
			(width 0.052324)
			(type default)
		)
		(layer "F.Cu")
	)
	(gr_line
		(start 104.000046 -56.000142)
		(end 104.499918 -56.500014)
		(stroke
			(width 0.052324)
			(type default)
		)
		(layer "F.Cu")
	)
	(gr_line
		(start 104.000046 -55.000144)
		(end 104.499918 -55.500016)
		(stroke
			(width 0.052324)
			(type default)
		)
		(layer "F.Cu")
	)
	(gr_line
		(start 104.000046 -52.00015)
		(end 104.499918 -52.500022)
		(stroke
			(width 0.052324)
			(type default)
		)
		(layer "F.Cu")
	)
	(gr_line
		(start 104.000046 -51.000152)
		(end 104.499918 -51.500024)
		(stroke
			(width 0.052324)
			(type default)
		)
		(layer "F.Cu")
	)
	(gr_line
		(start 105.000044 -56.000142)
		(end 105.499916 -56.500014)
		(stroke
			(width 0.052324)
			(type default)
		)
		(layer "F.Cu")
	)
	(gr_line
		(start 105.000044 -55.000144)
		(end 105.499916 -55.500016)
		(stroke
			(width 0.052324)
			(type default)
		)
		(layer "F.Cu")
	)
	(gr_line
		(start 105.000044 -53.000148)
		(end 105.499916 -53.50002)
		(stroke
			(width 0.052324)
			(type default)
		)
		(layer "F.Cu")
	)
	(gr_line
		(start 105.000044 -52.00015)
		(end 105.499916 -52.500022)
		(stroke
			(width 0.052324)
			(type default)
		)
		(layer "F.Cu")
	)
	(gr_line
		(start 106.000042 -56.000142)
		(end 106.499914 -56.500014)
		(stroke
			(width 0.052324)
			(type default)
		)
		(layer "F.Cu")
	)
	(gr_line
		(start 106.000042 -55.000144)
		(end 106.499914 -55.500016)
		(stroke
			(width 0.052324)
			(type default)
		)
		(layer "F.Cu")
	)
	(gr_line
		(start 106.000042 -52.00015)
		(end 106.499914 -52.500022)
		(stroke
			(width 0.052324)
			(type default)
		)
		(layer "F.Cu")
	)
	(gr_line
		(start 106.000042 -51.000152)
		(end 106.499914 -51.500024)
		(stroke
			(width 0.052324)
			(type default)
		)
		(layer "F.Cu")
	)
	(gr_line
		(start 107.00004 -56.000142)
		(end 107.499912 -56.500014)
		(stroke
			(width 0.052324)
			(type default)
		)
		(layer "F.Cu")
	)
	(gr_line
		(start 107.00004 -55.000144)
		(end 107.499912 -55.500016)
		(stroke
			(width 0.052324)
			(type default)
		)
		(layer "F.Cu")
	)
	(gr_line
		(start 107.00004 -53.000148)
		(end 107.499912 -53.50002)
		(stroke
			(width 0.052324)
			(type default)
		)
		(layer "F.Cu")
	)
	(gr_line
		(start 107.00004 -52.00015)
		(end 107.499912 -52.500022)
		(stroke
			(width 0.052324)
			(type default)
		)
		(layer "F.Cu")
	)
	(gr_line
		(start 108.000038 -56.000142)
		(end 108.49991 -56.500014)
		(stroke
			(width 0.052324)
			(type default)
		)
		(layer "F.Cu")
	)
	(gr_line
		(start 108.000038 -55.000144)
		(end 108.49991 -55.500016)
		(stroke
			(width 0.052324)
			(type default)
		)
		(layer "F.Cu")
	)
	(gr_line
		(start 108.000038 -52.00015)
		(end 108.49991 -52.500022)
		(stroke
			(width 0.052324)
			(type default)
		)
		(layer "F.Cu")
	)
	(gr_line
		(start 108.000038 -51.000152)
		(end 108.49991 -51.500024)
		(stroke
			(width 0.052324)
			(type default)
		)
		(layer "F.Cu")
	)
	(gr_line
		(start 109.000036 -56.000142)
		(end 109.499908 -56.500014)
		(stroke
			(width 0.052324)
			(type default)
		)
		(layer "F.Cu")
	)
	(gr_line
		(start 109.000036 -55.000144)
		(end 109.499908 -55.500016)
		(stroke
			(width 0.052324)
			(type default)
		)
		(layer "F.Cu")
	)
	(gr_line
		(start 109.000036 -53.000148)
		(end 109.499908 -53.50002)
		(stroke
			(width 0.052324)
			(type default)
		)
		(layer "F.Cu")
	)
	(gr_line
		(start 109.000036 -52.00015)
		(end 109.499908 -52.500022)
		(stroke
			(width 0.052324)
			(type default)
		)
		(layer "F.Cu")
	)
	(gr_line
		(start 110.000034 -56.000142)
		(end 110.499906 -56.500014)
		(stroke
			(width 0.052324)
			(type default)
		)
		(layer "F.Cu")
	)
	(gr_line
		(start 110.000034 -55.000144)
		(end 110.499906 -55.500016)
		(stroke
			(width 0.052324)
			(type default)
		)
		(layer "F.Cu")
	)
	(gr_line
		(start 110.000034 -52.00015)
		(end 110.499906 -52.500022)
		(stroke
			(width 0.052324)
			(type default)
		)
		(layer "F.Cu")
	)
	(gr_line
		(start 110.000034 -51.000152)
		(end 110.499906 -51.500024)
		(stroke
			(width 0.052324)
			(type default)
		)
		(layer "F.Cu")
	)
	(gr_line
		(start 111.000032 -56.000142)
		(end 111.499904 -56.500014)
		(stroke
			(width 0.052324)
			(type default)
		)
		(layer "F.Cu")
	)
	(gr_line
		(start 111.000032 -55.000144)
		(end 111.499904 -55.500016)
		(stroke
			(width 0.052324)
			(type default)
		)
		(layer "F.Cu")
	)
	(gr_line
		(start 111.000032 -53.000148)
		(end 111.499904 -53.50002)
		(stroke
			(width 0.052324)
			(type default)
		)
		(layer "F.Cu")
	)
	(gr_line
		(start 111.000032 -52.00015)
		(end 111.499904 -52.500022)
		(stroke
			(width 0.052324)
			(type default)
		)
		(layer "F.Cu")
	)
	(gr_line
		(start 112.00003 -56.000142)
		(end 112.499902 -56.500014)
		(stroke
			(width 0.052324)
			(type default)
		)
		(layer "F.Cu")
	)
	(gr_line
		(start 112.00003 -55.000144)
		(end 112.499902 -55.500016)
		(stroke
			(width 0.052324)
			(type default)
		)
		(layer "F.Cu")
	)
	(gr_line
		(start 112.00003 -52.00015)
		(end 112.499902 -52.500022)
		(stroke
			(width 0.052324)
			(type default)
		)
		(layer "F.Cu")
	)
	(gr_line
		(start 112.00003 -51.000152)
		(end 112.499902 -51.500024)
		(stroke
			(width 0.052324)
			(type default)
		)
		(layer "F.Cu")
	)
	(gr_line
		(start 113.000028 -56.000142)
		(end 113.4999 -56.500014)
		(stroke
			(width 0.052324)
			(type default)
		)
		(layer "F.Cu")
	)
	(gr_line
		(start 113.000028 -55.000144)
		(end 113.4999 -55.500016)
		(stroke
			(width 0.052324)
			(type default)
		)
		(layer "F.Cu")
	)
	(gr_line
		(start 113.000028 -53.000148)
		(end 113.4999 -53.50002)
		(stroke
			(width 0.052324)
			(type default)
		)
		(layer "F.Cu")
	)
	(gr_line
		(start 113.000028 -52.00015)
		(end 113.4999 -52.500022)
		(stroke
			(width 0.052324)
			(type default)
		)
		(layer "F.Cu")
	)
	(gr_line
		(start 114.000026 -56.000142)
		(end 114.499898 -56.500014)
		(stroke
			(width 0.052324)
			(type default)
		)
		(layer "F.Cu")
	)
	(gr_line
		(start 114.000026 -55.000144)
		(end 114.499898 -55.500016)
		(stroke
			(width 0.052324)
			(type default)
		)
		(layer "F.Cu")
	)
	(gr_line
		(start 114.000026 -52.00015)
		(end 114.499898 -52.500022)
		(stroke
			(width 0.052324)
			(type default)
		)
		(layer "F.Cu")
	)
	(gr_line
		(start 114.000026 -51.000152)
		(end 114.499898 -51.500024)
		(stroke
			(width 0.052324)
			(type default)
		)
		(layer "F.Cu")
	)
	(gr_line
		(start 115.50015 -56.500014)
		(end 116.000022 -56.000142)
		(stroke
			(width 0.052324)
			(type default)
		)
		(layer "F.Cu")
	)
	(gr_line
		(start 115.50015 -55.500016)
		(end 116.000022 -55.000144)
		(stroke
			(width 0.052324)
			(type default)
		)
		(layer "F.Cu")
	)
	(gr_line
		(start 115.50015 -53.50002)
		(end 116.000022 -53.000148)
		(stroke
			(width 0.052324)
			(type default)
		)
		(layer "F.Cu")
	)
	(gr_line
		(start 115.50015 -52.500022)
		(end 116.000022 -52.00015)
		(stroke
			(width 0.052324)
			(type default)
		)
		(layer "F.Cu")
	)
	(gr_line
		(start 116.500148 -56.500014)
		(end 117.00002 -56.000142)
		(stroke
			(width 0.052324)
			(type default)
		)
		(layer "F.Cu")
	)
	(gr_line
		(start 116.500148 -55.500016)
		(end 117.00002 -55.000144)
		(stroke
			(width 0.052324)
			(type default)
		)
		(layer "F.Cu")
	)
	(gr_line
		(start 116.500148 -52.500022)
		(end 117.00002 -52.00015)
		(stroke
			(width 0.052324)
			(type default)
		)
		(layer "F.Cu")
	)
	(gr_line
		(start 116.500148 -51.500024)
		(end 117.00002 -51.000152)
		(stroke
			(width 0.052324)
			(type default)
		)
		(layer "F.Cu")
	)
	(gr_line
		(start 117.500146 -56.500014)
		(end 118.000018 -56.000142)
		(stroke
			(width 0.052324)
			(type default)
		)
		(layer "F.Cu")
	)
	(gr_line
		(start 117.500146 -55.500016)
		(end 118.000018 -55.000144)
		(stroke
			(width 0.052324)
			(type default)
		)
		(layer "F.Cu")
	)
	(gr_line
		(start 117.500146 -53.50002)
		(end 118.000018 -53.000148)
		(stroke
			(width 0.052324)
			(type default)
		)
		(layer "F.Cu")
	)
	(gr_line
		(start 117.500146 -52.500022)
		(end 118.000018 -52.00015)
		(stroke
			(width 0.052324)
			(type default)
		)
		(layer "F.Cu")
	)
	(gr_line
		(start 118.500144 -56.500014)
		(end 119.000016 -56.000142)
		(stroke
			(width 0.052324)
			(type default)
		)
		(layer "F.Cu")
	)
	(gr_line
		(start 118.500144 -55.500016)
		(end 119.000016 -55.000144)
		(stroke
			(width 0.052324)
			(type default)
		)
		(layer "F.Cu")
	)
	(gr_line
		(start 118.500144 -52.500022)
		(end 119.000016 -52.00015)
		(stroke
			(width 0.052324)
			(type default)
		)
		(layer "F.Cu")
	)
	(gr_line
		(start 118.500144 -51.500024)
		(end 119.000016 -51.000152)
		(stroke
			(width 0.052324)
			(type default)
		)
		(layer "F.Cu")
	)
	(gr_line
		(start 119.500142 -56.500014)
		(end 120.000014 -56.000142)
		(stroke
			(width 0.052324)
			(type default)
		)
		(layer "F.Cu")
	)
	(gr_line
		(start 119.500142 -55.500016)
		(end 120.000014 -55.000144)
		(stroke
			(width 0.052324)
			(type default)
		)
		(layer "F.Cu")
	)
	(gr_line
		(start 119.500142 -53.50002)
		(end 120.000014 -53.000148)
		(stroke
			(width 0.052324)
			(type default)
		)
		(layer "F.Cu")
	)
	(gr_line
		(start 119.500142 -52.500022)
		(end 120.000014 -52.00015)
		(stroke
			(width 0.052324)
			(type default)
		)
		(layer "F.Cu")
	)
	(gr_line
		(start 120.50014 -56.500014)
		(end 121.000012 -56.000142)
		(stroke
			(width 0.052324)
			(type default)
		)
		(layer "F.Cu")
	)
	(gr_line
		(start 120.50014 -55.500016)
		(end 121.000012 -55.000144)
		(stroke
			(width 0.052324)
			(type default)
		)
		(layer "F.Cu")
	)
	(gr_line
		(start 120.50014 -52.500022)
		(end 121.000012 -52.00015)
		(stroke
			(width 0.052324)
			(type default)
		)
		(layer "F.Cu")
	)
	(gr_line
		(start 120.50014 -51.500024)
		(end 121.000012 -51.000152)
		(stroke
			(width 0.052324)
			(type default)
		)
		(layer "F.Cu")
	)
	(gr_line
		(start 121.500138 -56.500014)
		(end 122.00001 -56.000142)
		(stroke
			(width 0.052324)
			(type default)
		)
		(layer "F.Cu")
	)
	(gr_line
		(start 121.500138 -55.500016)
		(end 122.00001 -55.000144)
		(stroke
			(width 0.052324)
			(type default)
		)
		(layer "F.Cu")
	)
	(gr_line
		(start 121.500138 -53.50002)
		(end 122.00001 -53.000148)
		(stroke
			(width 0.052324)
			(type default)
		)
		(layer "F.Cu")
	)
	(gr_line
		(start 121.500138 -52.500022)
		(end 122.00001 -52.00015)
		(stroke
			(width 0.052324)
			(type default)
		)
		(layer "F.Cu")
	)
	(gr_line
		(start 122.500136 -56.500014)
		(end 123.000008 -56.000142)
		(stroke
			(width 0.052324)
			(type default)
		)
		(layer "F.Cu")
	)
	(gr_line
		(start 122.500136 -55.500016)
		(end 123.000008 -55.000144)
		(stroke
			(width 0.052324)
			(type default)
		)
		(layer "F.Cu")
	)
	(gr_line
		(start 122.500136 -52.500022)
		(end 123.000008 -52.00015)
		(stroke
			(width 0.052324)
			(type default)
		)
		(layer "F.Cu")
	)
	(gr_line
		(start 122.500136 -51.500024)
		(end 123.000008 -51.000152)
		(stroke
			(width 0.052324)
			(type default)
		)
		(layer "F.Cu")
	)
	(gr_line
		(start 123.500134 -56.500014)
		(end 124.000006 -56.000142)
		(stroke
			(width 0.052324)
			(type default)
		)
		(layer "F.Cu")
	)
	(gr_line
		(start 123.500134 -55.500016)
		(end 124.000006 -55.000144)
		(stroke
			(width 0.052324)
			(type default)
		)
		(layer "F.Cu")
	)
	(gr_line
		(start 123.500134 -53.50002)
		(end 124.000006 -53.000148)
		(stroke
			(width 0.052324)
			(type default)
		)
		(layer "F.Cu")
	)
	(gr_line
		(start 123.500134 -52.500022)
		(end 124.000006 -52.00015)
		(stroke
			(width 0.052324)
			(type default)
		)
		(layer "F.Cu")
	)
	(gr_line
		(start 124.682758 -46.744636)
		(end 124.682758 -47.001938)
		(stroke
			(width 0.06223)
			(type default)
		)
		(layer "F.Cu")
	)
	(gr_arc
		(start 124.682758 -46.11624)
		(mid 124.691207 -46.158717)
		(end 124.71527 -46.194726)
		(stroke
			(width 0.06223)
			(type default)
		)
		(layer "F.Cu")
	)
	(gr_line
		(start 124.682758 -45.858938)
		(end 124.682758 -46.11624)
		(stroke
			(width 0.06223)
			(type default)
		)
		(layer "F.Cu")
	)
	(gr_arc
		(start 124.71527 -46.66615)
		(mid 124.691209 -46.702159)
		(end 124.682758 -46.744636)
		(stroke
			(width 0.06223)
			(type default)
		)
		(layer "F.Cu")
	)
	(gr_arc
		(start 124.71527 -46.194726)
		(mid 124.75128 -46.218787)
		(end 124.793756 -46.227238)
		(stroke
			(width 0.06223)
			(type default)
		)
		(layer "F.Cu")
	)
	(gr_arc
		(start 124.793756 -46.633638)
		(mid 124.75129 -46.642104)
		(end 124.71527 -46.66615)
		(stroke
			(width 0.06223)
			(type default)
		)
		(layer "F.Cu")
	)
	(gr_line
		(start 125.50013 -76.500228)
		(end 126.000002 -77.0001)
		(stroke
			(width 0.052324)
			(type default)
		)
		(layer "F.Cu")
	)
	(gr_line
		(start 125.50013 -75.50023)
		(end 126.000002 -76.000102)
		(stroke
			(width 0.052324)
			(type default)
		)
		(layer "F.Cu")
	)
	(gr_line
		(start 125.50013 -74.500232)
		(end 126.000002 -75.000104)
		(stroke
			(width 0.052324)
			(type default)
		)
		(layer "F.Cu")
	)
	(gr_line
		(start 125.50013 -73.500234)
		(end 126.000002 -74.000106)
		(stroke
			(width 0.052324)
			(type default)
		)
		(layer "F.Cu")
	)
	(gr_line
		(start 125.50013 -72.500236)
		(end 126.000002 -73.000108)
		(stroke
			(width 0.052324)
			(type default)
		)
		(layer "F.Cu")
	)
	(gr_line
		(start 125.50013 -71.500238)
		(end 126.000002 -72.00011)
		(stroke
			(width 0.052324)
			(type default)
		)
		(layer "F.Cu")
	)
	(gr_line
		(start 125.50013 -70.50024)
		(end 126.000002 -71.000112)
		(stroke
			(width 0.052324)
			(type default)
		)
		(layer "F.Cu")
	)
	(gr_line
		(start 125.50013 -69.500242)
		(end 126.000002 -70.000114)
		(stroke
			(width 0.052324)
			(type default)
		)
		(layer "F.Cu")
	)
	(gr_line
		(start 125.50013 -68.500244)
		(end 126.000002 -69.000116)
		(stroke
			(width 0.052324)
			(type default)
		)
		(layer "F.Cu")
	)
	(gr_line
		(start 125.50013 -67.500246)
		(end 126.000002 -68.000118)
		(stroke
			(width 0.052324)
			(type default)
		)
		(layer "F.Cu")
	)
	(gr_line
		(start 125.50013 -66.499994)
		(end 126.000002 -66.000122)
		(stroke
			(width 0.052324)
			(type default)
		)
		(layer "F.Cu")
	)
	(gr_line
		(start 125.50013 -65.499996)
		(end 126.000002 -65.000124)
		(stroke
			(width 0.052324)
			(type default)
		)
		(layer "F.Cu")
	)
	(gr_line
		(start 125.50013 -64.499998)
		(end 126.000002 -64.000126)
		(stroke
			(width 0.052324)
			(type default)
		)
		(layer "F.Cu")
	)
	(gr_line
		(start 125.50013 -63.5)
		(end 126.000002 -63.000128)
		(stroke
			(width 0.052324)
			(type default)
		)
		(layer "F.Cu")
	)
	(gr_line
		(start 125.50013 -62.500002)
		(end 126.000002 -62.00013)
		(stroke
			(width 0.052324)
			(type default)
		)
		(layer "F.Cu")
	)
	(gr_line
		(start 125.50013 -61.500004)
		(end 126.000002 -61.000132)
		(stroke
			(width 0.052324)
			(type default)
		)
		(layer "F.Cu")
	)
	(gr_line
		(start 125.50013 -60.500006)
		(end 126.000002 -60.000134)
		(stroke
			(width 0.052324)
			(type default)
		)
		(layer "F.Cu")
	)
	(gr_line
		(start 125.50013 -59.500008)
		(end 126.000002 -59.000136)
		(stroke
			(width 0.052324)
			(type default)
		)
		(layer "F.Cu")
	)
	(gr_line
		(start 125.50013 -58.50001)
		(end 126.000002 -58.000138)
		(stroke
			(width 0.052324)
			(type default)
		)
		(layer "F.Cu")
	)
	(gr_line
		(start 125.50013 -57.500012)
		(end 126.000002 -57.00014)
		(stroke
			(width 0.052324)
			(type default)
		)
		(layer "F.Cu")
	)
	(gr_line
		(start 125.50013 -56.500014)
		(end 126.000002 -56.000142)
		(stroke
			(width 0.052324)
			(type default)
		)
		(layer "F.Cu")
	)
	(gr_line
		(start 125.50013 -55.500016)
		(end 126.000002 -55.000144)
		(stroke
			(width 0.052324)
			(type default)
		)
		(layer "F.Cu")
	)
	(gr_line
		(start 125.50013 -54.500018)
		(end 126.000002 -54.000146)
		(stroke
			(width 0.052324)
			(type default)
		)
		(layer "F.Cu")
	)
	(gr_line
		(start 125.526546 -45.392848)
		(end 125.529594 -45.395896)
		(stroke
			(width 0.06223)
			(type default)
		)
		(layer "F.Cu")
	)
	(gr_line
		(start 125.526546 -45.02658)
		(end 125.526546 -45.392848)
		(stroke
			(width 0.06223)
			(type default)
		)
		(layer "F.Cu")
	)
	(gr_line
		(start 125.526546 -44.101512)
		(end 125.526546 -44.46778)
		(stroke
			(width 0.06223)
			(type default)
		)
		(layer "F.Cu")
	)
	(gr_line
		(start 125.526546 -44.101512)
		(end 125.53696 -44.091098)
		(stroke
			(width 0.06223)
			(type default)
		)
		(layer "F.Cu")
	)
	(gr_line
		(start 125.65634 -43.668696)
		(end 125.697234 -43.605704)
		(stroke
			(width 0.06223)
			(type default)
		)
		(layer "F.Cu")
	)
	(gr_line
		(start 126.107698 -45.395896)
		(end 126.110746 -45.392848)
		(stroke
			(width 0.06223)
			(type default)
		)
		(layer "F.Cu")
	)
	(gr_line
		(start 126.110746 -45.02658)
		(end 126.110746 -45.392848)
		(stroke
			(width 0.06223)
			(type default)
		)
		(layer "F.Cu")
	)
	(gr_line
		(start 126.110746 -44.08678)
		(end 126.110746 -44.46778)
		(stroke
			(width 0.06223)
			(type default)
		)
		(layer "F.Cu")
	)
	(gr_line
		(start 126.500128 -76.500228)
		(end 127 -77.0001)
		(stroke
			(width 0.052324)
			(type default)
		)
		(layer "F.Cu")
	)
	(gr_line
		(start 126.500128 -75.50023)
		(end 127 -76.000102)
		(stroke
			(width 0.052324)
			(type default)
		)
		(layer "F.Cu")
	)
	(gr_line
		(start 126.500128 -74.500232)
		(end 127 -75.000104)
		(stroke
			(width 0.052324)
			(type default)
		)
		(layer "F.Cu")
	)
	(gr_line
		(start 126.500128 -73.500234)
		(end 127 -74.000106)
		(stroke
			(width 0.052324)
			(type default)
		)
		(layer "F.Cu")
	)
	(gr_line
		(start 126.500128 -72.500236)
		(end 127 -73.000108)
		(stroke
			(width 0.052324)
			(type default)
		)
		(layer "F.Cu")
	)
	(gr_line
		(start 126.500128 -71.500238)
		(end 127 -72.00011)
		(stroke
			(width 0.052324)
			(type default)
		)
		(layer "F.Cu")
	)
	(gr_line
		(start 126.500128 -70.50024)
		(end 127 -71.000112)
		(stroke
			(width 0.052324)
			(type default)
		)
		(layer "F.Cu")
	)
	(gr_line
		(start 126.500128 -69.500242)
		(end 127 -70.000114)
		(stroke
			(width 0.052324)
			(type default)
		)
		(layer "F.Cu")
	)
	(gr_line
		(start 126.500128 -68.500244)
		(end 127 -69.000116)
		(stroke
			(width 0.052324)
			(type default)
		)
		(layer "F.Cu")
	)
	(gr_line
		(start 126.500128 -67.500246)
		(end 127 -68.000118)
		(stroke
			(width 0.052324)
			(type default)
		)
		(layer "F.Cu")
	)
	(gr_line
		(start 126.500128 -66.499994)
		(end 127 -66.000122)
		(stroke
			(width 0.052324)
			(type default)
		)
		(layer "F.Cu")
	)
	(gr_line
		(start 126.500128 -65.499996)
		(end 127 -65.000124)
		(stroke
			(width 0.052324)
			(type default)
		)
		(layer "F.Cu")
	)
	(gr_line
		(start 126.500128 -64.499998)
		(end 127 -64.000126)
		(stroke
			(width 0.052324)
			(type default)
		)
		(layer "F.Cu")
	)
	(gr_line
		(start 126.500128 -63.5)
		(end 127 -63.000128)
		(stroke
			(width 0.052324)
			(type default)
		)
		(layer "F.Cu")
	)
	(gr_line
		(start 126.500128 -62.500002)
		(end 127 -62.00013)
		(stroke
			(width 0.052324)
			(type default)
		)
		(layer "F.Cu")
	)
	(gr_line
		(start 126.500128 -61.500004)
		(end 127 -61.000132)
		(stroke
			(width 0.052324)
			(type default)
		)
		(layer "F.Cu")
	)
	(gr_line
		(start 126.500128 -60.500006)
		(end 127 -60.000134)
		(stroke
			(width 0.052324)
			(type default)
		)
		(layer "F.Cu")
	)
	(gr_line
		(start 126.500128 -59.500008)
		(end 127 -59.000136)
		(stroke
			(width 0.052324)
			(type default)
		)
		(layer "F.Cu")
	)
	(gr_line
		(start 126.500128 -58.50001)
		(end 127 -58.000138)
		(stroke
			(width 0.052324)
			(type default)
		)
		(layer "F.Cu")
	)
	(gr_line
		(start 126.500128 -57.500012)
		(end 127 -57.00014)
		(stroke
			(width 0.052324)
			(type default)
		)
		(layer "F.Cu")
	)
	(gr_line
		(start 126.500128 -56.500014)
		(end 127 -56.000142)
		(stroke
			(width 0.052324)
			(type default)
		)
		(layer "F.Cu")
	)
	(gr_line
		(start 126.500128 -55.500016)
		(end 127 -55.000144)
		(stroke
			(width 0.052324)
			(type default)
		)
		(layer "F.Cu")
	)
	(gr_line
		(start 126.500128 -54.500018)
		(end 127 -54.000146)
		(stroke
			(width 0.052324)
			(type default)
		)
		(layer "F.Cu")
	)
	(gr_line
		(start 126.500128 -53.50002)
		(end 127 -53.000148)
		(stroke
			(width 0.052324)
			(type default)
		)
		(layer "F.Cu")
	)
	(gr_line
		(start 127.076708 -46.729904)
		(end 127.076708 -46.987206)
		(stroke
			(width 0.06223)
			(type default)
		)
		(layer "F.Cu")
	)
	(gr_arc
		(start 127.076708 -46.101508)
		(mid 127.085157 -46.143985)
		(end 127.10922 -46.179994)
		(stroke
			(width 0.06223)
			(type default)
		)
		(layer "F.Cu")
	)
	(gr_line
		(start 127.076708 -45.844206)
		(end 127.076708 -46.101508)
		(stroke
			(width 0.06223)
			(type default)
		)
		(layer "F.Cu")
	)
	(gr_arc
		(start 127.10922 -46.651418)
		(mid 127.085159 -46.687428)
		(end 127.076708 -46.729904)
		(stroke
			(width 0.06223)
			(type default)
		)
		(layer "F.Cu")
	)
	(gr_arc
		(start 127.10922 -46.179994)
		(mid 127.14523 -46.204055)
		(end 127.187706 -46.212506)
		(stroke
			(width 0.06223)
			(type default)
		)
		(layer "F.Cu")
	)
	(gr_arc
		(start 127.187706 -46.618906)
		(mid 127.145228 -46.627353)
		(end 127.10922 -46.651418)
		(stroke
			(width 0.06223)
			(type default)
		)
		(layer "F.Cu")
	)
	(gr_line
		(start 127.500126 -53.50002)
		(end 127.999998 -53.000148)
		(stroke
			(width 0.052324)
			(type default)
		)
		(layer "F.Cu")
	)
	(gr_line
		(start 127.931418 -40.16248)
		(end 127.954024 -40.127428)
		(stroke
			(width 0.06223)
			(type default)
		)
		(layer "F.Cu")
	)
	(gr_line
		(start 127.954024 -40.127428)
		(end 127.988568 -40.105076)
		(stroke
			(width 0.06223)
			(type default)
		)
		(layer "F.Cu")
	)
	(gr_line
		(start 128.00203 -45.378116)
		(end 128.005078 -45.381164)
		(stroke
			(width 0.06223)
			(type default)
		)
		(layer "F.Cu")
	)
	(gr_line
		(start 128.00203 -45.011848)
		(end 128.00203 -45.378116)
		(stroke
			(width 0.06223)
			(type default)
		)
		(layer "F.Cu")
	)
	(gr_line
		(start 128.00203 -44.11218)
		(end 128.00203 -44.453048)
		(stroke
			(width 0.06223)
			(type default)
		)
		(layer "F.Cu")
	)
	(gr_line
		(start 128.00203 -44.11218)
		(end 128.030478 -44.083732)
		(stroke
			(width 0.06223)
			(type default)
		)
		(layer "F.Cu")
	)
	(gr_line
		(start 128.097026 -43.614594)
		(end 128.13792 -43.551602)
		(stroke
			(width 0.06223)
			(type default)
		)
		(layer "F.Cu")
	)
	(gr_line
		(start 128.500124 -75.50023)
		(end 128.815846 -75.50023)
		(stroke
			(width 0.04445)
			(type default)
		)
		(layer "F.Cu")
	)
	(gr_line
		(start 128.500124 -73.500234)
		(end 128.815846 -73.500234)
		(stroke
			(width 0.04445)
			(type default)
		)
		(layer "F.Cu")
	)
	(gr_line
		(start 128.500124 -71.500238)
		(end 128.999996 -72.00011)
		(stroke
			(width 0.052324)
			(type default)
		)
		(layer "F.Cu")
	)
	(gr_line
		(start 128.500124 -69.500242)
		(end 128.999996 -70.000114)
		(stroke
			(width 0.052324)
			(type default)
		)
		(layer "F.Cu")
	)
	(gr_line
		(start 128.500124 -67.500246)
		(end 128.999996 -68.000118)
		(stroke
			(width 0.052324)
			(type default)
		)
		(layer "F.Cu")
	)
	(gr_line
		(start 128.500124 -65.499996)
		(end 128.999996 -65.000124)
		(stroke
			(width 0.052324)
			(type default)
		)
		(layer "F.Cu")
	)
	(gr_line
		(start 128.500124 -63.5)
		(end 128.999996 -63.000128)
		(stroke
			(width 0.052324)
			(type default)
		)
		(layer "F.Cu")
	)
	(gr_line
		(start 128.500124 -61.500004)
		(end 128.999996 -61.000132)
		(stroke
			(width 0.052324)
			(type default)
		)
		(layer "F.Cu")
	)
	(gr_line
		(start 128.500124 -59.500008)
		(end 128.790446 -59.500008)
		(stroke
			(width 0.04445)
			(type default)
		)
		(layer "F.Cu")
	)
	(gr_line
		(start 128.500124 -57.500012)
		(end 128.790446 -57.500012)
		(stroke
			(width 0.04445)
			(type default)
		)
		(layer "F.Cu")
	)
	(gr_line
		(start 128.500124 -55.500016)
		(end 128.790446 -55.500016)
		(stroke
			(width 0.04445)
			(type default)
		)
		(layer "F.Cu")
	)
	(gr_line
		(start 128.583182 -45.381164)
		(end 128.58623 -45.378116)
		(stroke
			(width 0.06223)
			(type default)
		)
		(layer "F.Cu")
	)
	(gr_line
		(start 128.58623 -45.011848)
		(end 128.58623 -45.378116)
		(stroke
			(width 0.06223)
			(type default)
		)
		(layer "F.Cu")
	)
	(gr_line
		(start 128.58623 -44.06138)
		(end 128.58623 -44.453048)
		(stroke
			(width 0.06223)
			(type default)
		)
		(layer "F.Cu")
	)
	(gr_arc
		(start 128.790446 -59.500008)
		(mid 128.871241 -59.466515)
		(end 128.904746 -59.385708)
		(stroke
			(width 0.04445)
			(type default)
		)
		(layer "F.Cu")
	)
	(gr_arc
		(start 128.790446 -57.500012)
		(mid 128.871268 -57.466534)
		(end 128.904746 -57.385712)
		(stroke
			(width 0.04445)
			(type default)
		)
		(layer "F.Cu")
	)
	(gr_arc
		(start 128.790446 -55.500016)
		(mid 128.871268 -55.466538)
		(end 128.904746 -55.385716)
		(stroke
			(width 0.04445)
			(type default)
		)
		(layer "F.Cu")
	)
	(gr_arc
		(start 128.904746 -75.58913)
		(mid 128.878721 -75.526233)
		(end 128.815846 -75.50023)
		(stroke
			(width 0.04445)
			(type default)
		)
		(layer "F.Cu")
	)
	(gr_arc
		(start 128.904746 -73.589134)
		(mid 128.878723 -73.526234)
		(end 128.815846 -73.500234)
		(stroke
			(width 0.04445)
			(type default)
		)
		(layer "F.Cu")
	)
	(gr_arc
		(start 129.095246 -59.385708)
		(mid 129.128724 -59.46653)
		(end 129.209546 -59.500008)
		(stroke
			(width 0.04445)
			(type default)
		)
		(layer "F.Cu")
	)
	(gr_arc
		(start 129.095246 -57.385712)
		(mid 129.128731 -57.46651)
		(end 129.209546 -57.500012)
		(stroke
			(width 0.04445)
			(type default)
		)
		(layer "F.Cu")
	)
	(gr_arc
		(start 129.095246 -55.385716)
		(mid 129.128732 -55.466512)
		(end 129.209546 -55.500016)
		(stroke
			(width 0.04445)
			(type default)
		)
		(layer "F.Cu")
	)
	(gr_arc
		(start 129.184146 -75.50023)
		(mid 129.121284 -75.526268)
		(end 129.095246 -75.58913)
		(stroke
			(width 0.04445)
			(type default)
		)
		(layer "F.Cu")
	)
	(gr_line
		(start 129.184146 -75.50023)
		(end 129.500122 -75.50023)
		(stroke
			(width 0.04445)
			(type default)
		)
		(layer "F.Cu")
	)
	(gr_arc
		(start 129.184146 -73.500234)
		(mid 129.121284 -73.526272)
		(end 129.095246 -73.589134)
		(stroke
			(width 0.04445)
			(type default)
		)
		(layer "F.Cu")
	)
	(gr_line
		(start 129.184146 -73.500234)
		(end 129.500122 -73.500234)
		(stroke
			(width 0.04445)
			(type default)
		)
		(layer "F.Cu")
	)
	(gr_line
		(start 129.209546 -59.500008)
		(end 129.500122 -59.500008)
		(stroke
			(width 0.04445)
			(type default)
		)
		(layer "F.Cu")
	)
	(gr_line
		(start 129.209546 -57.500012)
		(end 129.500122 -57.500012)
		(stroke
			(width 0.04445)
			(type default)
		)
		(layer "F.Cu")
	)
	(gr_line
		(start 129.209546 -55.500016)
		(end 129.500122 -55.500016)
		(stroke
			(width 0.04445)
			(type default)
		)
		(layer "F.Cu")
	)
	(gr_line
		(start 129.500122 -76.500228)
		(end 129.815844 -76.500228)
		(stroke
			(width 0.04445)
			(type default)
		)
		(layer "F.Cu")
	)
	(gr_line
		(start 129.500122 -74.500232)
		(end 129.815844 -74.500232)
		(stroke
			(width 0.04445)
			(type default)
		)
		(layer "F.Cu")
	)
	(gr_line
		(start 129.500122 -72.500236)
		(end 129.999994 -73.000108)
		(stroke
			(width 0.052324)
			(type default)
		)
		(layer "F.Cu")
	)
	(gr_line
		(start 129.500122 -71.500238)
		(end 129.999994 -72.00011)
		(stroke
			(width 0.052324)
			(type default)
		)
		(layer "F.Cu")
	)
	(gr_line
		(start 129.500122 -70.50024)
		(end 129.999994 -71.000112)
		(stroke
			(width 0.052324)
			(type default)
		)
		(layer "F.Cu")
	)
	(gr_line
		(start 129.500122 -69.500242)
		(end 129.999994 -70.000114)
		(stroke
			(width 0.052324)
			(type default)
		)
		(layer "F.Cu")
	)
	(gr_line
		(start 129.500122 -68.500244)
		(end 129.999994 -69.000116)
		(stroke
			(width 0.052324)
			(type default)
		)
		(layer "F.Cu")
	)
	(gr_line
		(start 129.500122 -67.500246)
		(end 129.999994 -68.000118)
		(stroke
			(width 0.052324)
			(type default)
		)
		(layer "F.Cu")
	)
	(gr_line
		(start 129.500122 -66.499994)
		(end 129.999994 -66.000122)
		(stroke
			(width 0.052324)
			(type default)
		)
		(layer "F.Cu")
	)
	(gr_line
		(start 129.500122 -65.499996)
		(end 129.999994 -65.000124)
		(stroke
			(width 0.052324)
			(type default)
		)
		(layer "F.Cu")
	)
	(gr_line
		(start 129.500122 -64.499998)
		(end 129.999994 -64.000126)
		(stroke
			(width 0.052324)
			(type default)
		)
		(layer "F.Cu")
	)
	(gr_line
		(start 129.500122 -63.5)
		(end 129.999994 -63.000128)
		(stroke
			(width 0.052324)
			(type default)
		)
		(layer "F.Cu")
	)
	(gr_line
		(start 129.500122 -62.500002)
		(end 129.999994 -62.00013)
		(stroke
			(width 0.052324)
			(type default)
		)
		(layer "F.Cu")
	)
	(gr_line
		(start 129.500122 -61.500004)
		(end 129.999994 -61.000132)
		(stroke
			(width 0.052324)
			(type default)
		)
		(layer "F.Cu")
	)
	(gr_line
		(start 129.500122 -60.500006)
		(end 129.790444 -60.500006)
		(stroke
			(width 0.04445)
			(type default)
		)
		(layer "F.Cu")
	)
	(gr_line
		(start 129.500122 -58.50001)
		(end 129.790444 -58.50001)
		(stroke
			(width 0.04445)
			(type default)
		)
		(layer "F.Cu")
	)
	(gr_line
		(start 129.500122 -56.500014)
		(end 129.790444 -56.500014)
		(stroke
			(width 0.04445)
			(type default)
		)
		(layer "F.Cu")
	)
	(gr_line
		(start 129.500122 -54.500018)
		(end 129.790444 -54.500018)
		(stroke
			(width 0.04445)
			(type default)
		)
		(layer "F.Cu")
	)
	(gr_line
		(start 129.500122 -52.500022)
		(end 129.642362 -52.500022)
		(stroke
			(width 0.06223)
			(type default)
		)
		(layer "F.Cu")
	)
	(gr_arc
		(start 129.642362 -52.500022)
		(mid 129.701484 -52.488305)
		(end 129.751582 -52.45481)
		(stroke
			(width 0.06223)
			(type default)
		)
		(layer "F.Cu")
	)
	(gr_line
		(start 129.648458 -46.715172)
		(end 129.648458 -46.972474)
		(stroke
			(width 0.06223)
			(type default)
		)
		(layer "F.Cu")
	)
	(gr_arc
		(start 129.648458 -46.086776)
		(mid 129.656897 -46.129261)
		(end 129.68097 -46.165262)
		(stroke
			(width 0.06223)
			(type default)
		)
		(layer "F.Cu")
	)
	(gr_line
		(start 129.648458 -45.829474)
		(end 129.648458 -46.086776)
		(stroke
			(width 0.06223)
			(type default)
		)
		(layer "F.Cu")
	)
	(gr_arc
		(start 129.68097 -46.636686)
		(mid 129.656909 -46.672696)
		(end 129.648458 -46.715172)
		(stroke
			(width 0.06223)
			(type default)
		)
		(layer "F.Cu")
	)
	(gr_arc
		(start 129.68097 -46.165262)
		(mid 129.716976 -46.189342)
		(end 129.759456 -46.197774)
		(stroke
			(width 0.06223)
			(type default)
		)
		(layer "F.Cu")
	)
	(gr_arc
		(start 129.751582 -52.45481)
		(mid 129.785027 -52.40469)
		(end 129.796794 -52.34559)
		(stroke
			(width 0.06223)
			(type default)
		)
		(layer "F.Cu")
	)
	(gr_arc
		(start 129.759456 -46.604174)
		(mid 129.716979 -46.612623)
		(end 129.68097 -46.636686)
		(stroke
			(width 0.06223)
			(type default)
		)
		(layer "F.Cu")
	)
	(gr_arc
		(start 129.790444 -60.500006)
		(mid 129.87124 -60.466513)
		(end 129.904744 -60.385706)
		(stroke
			(width 0.04445)
			(type default)
		)
		(layer "F.Cu")
	)
	(gr_arc
		(start 129.790444 -58.50001)
		(mid 129.853306 -58.473972)
		(end 129.879344 -58.41111)
		(stroke
			(width 0.04445)
			(type default)
		)
		(layer "F.Cu")
	)
	(gr_arc
		(start 129.790444 -56.500014)
		(mid 129.871243 -56.466522)
		(end 129.904744 -56.385714)
		(stroke
			(width 0.04445)
			(type default)
		)
		(layer "F.Cu")
	)
	(gr_arc
		(start 129.790444 -54.500018)
		(mid 129.871266 -54.46654)
		(end 129.904744 -54.385718)
		(stroke
			(width 0.04445)
			(type default)
		)
		(layer "F.Cu")
	)
	(gr_arc
		(start 129.904744 -76.589128)
		(mid 129.878706 -76.526266)
		(end 129.815844 -76.500228)
		(stroke
			(width 0.04445)
			(type default)
		)
		(layer "F.Cu")
	)
	(gr_arc
		(start 129.904744 -74.589132)
		(mid 129.878706 -74.52627)
		(end 129.815844 -74.500232)
		(stroke
			(width 0.04445)
			(type default)
		)
		(layer "F.Cu")
	)
	(gr_line
		(start 129.991358 -40.696896)
		(end 130.013964 -40.662098)
		(stroke
			(width 0.06223)
			(type default)
		)
		(layer "F.Cu")
	)
	(gr_line
		(start 130.013964 -40.662098)
		(end 130.048762 -40.639492)
		(stroke
			(width 0.06223)
			(type default)
		)
		(layer "F.Cu")
	)
	(gr_arc
		(start 130.069844 -58.36031)
		(mid 130.110767 -58.459071)
		(end 130.209544 -58.50001)
		(stroke
			(width 0.04445)
			(type default)
		)
		(layer "F.Cu")
	)
	(gr_arc
		(start 130.095244 -54.385718)
		(mid 130.128731 -54.466513)
		(end 130.209544 -54.500018)
		(stroke
			(width 0.04445)
			(type default)
		)
		(layer "F.Cu")
	)
	(gr_arc
		(start 130.184144 -76.500228)
		(mid 130.121264 -76.526252)
		(end 130.095244 -76.589128)
		(stroke
			(width 0.04445)
			(type default)
		)
		(layer "F.Cu")
	)
	(gr_line
		(start 130.184144 -76.500228)
		(end 130.50012 -76.500228)
		(stroke
			(width 0.04445)
			(type default)
		)
		(layer "F.Cu")
	)
	(gr_arc
		(start 130.184144 -74.500232)
		(mid 130.121265 -74.526257)
		(end 130.095244 -74.589132)
		(stroke
			(width 0.04445)
			(type default)
		)
		(layer "F.Cu")
	)
	(gr_line
		(start 130.184144 -74.500232)
		(end 130.50012 -74.500232)
		(stroke
			(width 0.04445)
			(type default)
		)
		(layer "F.Cu")
	)
	(gr_arc
		(start 130.203194 -52.370736)
		(mid 130.213035 -52.420212)
		(end 130.24104 -52.462176)
		(stroke
			(width 0.06223)
			(type default)
		)
		(layer "F.Cu")
	)
	(gr_line
		(start 130.209544 -60.500006)
		(end 130.50012 -60.500006)
		(stroke
			(width 0.04445)
			(type default)
		)
		(layer "F.Cu")
	)
	(gr_line
		(start 130.209544 -58.50001)
		(end 130.50012 -58.50001)
		(stroke
			(width 0.04445)
			(type default)
		)
		(layer "F.Cu")
	)
	(gr_line
		(start 130.209544 -56.500014)
		(end 130.50012 -56.500014)
		(stroke
			(width 0.04445)
			(type default)
		)
		(layer "F.Cu")
	)
	(gr_line
		(start 130.209544 -54.500018)
		(end 130.50012 -54.500018)
		(stroke
			(width 0.04445)
			(type default)
		)
		(layer "F.Cu")
	)
	(gr_line
		(start 130.214624 -40.529002)
		(end 130.29311 -40.15994)
		(stroke
			(width 0.06223)
			(type default)
		)
		(layer "F.Cu")
	)
	(gr_arc
		(start 130.24104 -52.462176)
		(mid 130.282993 -52.490208)
		(end 130.33248 -52.500022)
		(stroke
			(width 0.06223)
			(type default)
		)
		(layer "F.Cu")
	)
	(gr_line
		(start 130.29311 -40.15994)
		(end 130.606292 -39.95674)
		(stroke
			(width 0.06223)
			(type default)
		)
		(layer "F.Cu")
	)
	(gr_line
		(start 130.33248 -52.500022)
		(end 130.50012 -52.500022)
		(stroke
			(width 0.06223)
			(type default)
		)
		(layer "F.Cu")
	)
	(gr_line
		(start 130.471672 -40.849804)
		(end 130.576574 -40.781732)
		(stroke
			(width 0.06223)
			(type default)
		)
		(layer "F.Cu")
	)
	(gr_line
		(start 130.50012 -72.500236)
		(end 130.999992 -73.000108)
		(stroke
			(width 0.052324)
			(type default)
		)
		(layer "F.Cu")
	)
	(gr_line
		(start 130.50012 -70.50024)
		(end 130.999992 -71.000112)
		(stroke
			(width 0.052324)
			(type default)
		)
		(layer "F.Cu")
	)
	(gr_line
		(start 130.50012 -68.500244)
		(end 130.999992 -69.000116)
		(stroke
			(width 0.052324)
			(type default)
		)
		(layer "F.Cu")
	)
	(gr_line
		(start 130.50012 -66.499994)
		(end 130.999992 -66.000122)
		(stroke
			(width 0.052324)
			(type default)
		)
		(layer "F.Cu")
	)
	(gr_line
		(start 130.50012 -64.499998)
		(end 130.999992 -64.000126)
		(stroke
			(width 0.052324)
			(type default)
		)
		(layer "F.Cu")
	)
	(gr_line
		(start 130.50012 -62.500002)
		(end 130.999992 -62.00013)
		(stroke
			(width 0.052324)
			(type default)
		)
		(layer "F.Cu")
	)
	(gr_line
		(start 130.56616 -76.919328)
		(end 130.719576 -76.919328)
		(stroke
			(width 0.04445)
			(type default)
		)
		(layer "F.Cu")
	)
	(gr_line
		(start 130.57378 -45.363384)
		(end 130.576828 -45.366432)
		(stroke
			(width 0.06223)
			(type default)
		)
		(layer "F.Cu")
	)
	(gr_line
		(start 130.57378 -44.997116)
		(end 130.57378 -45.363384)
		(stroke
			(width 0.06223)
			(type default)
		)
		(layer "F.Cu")
	)
	(gr_line
		(start 130.57378 -44.097448)
		(end 130.57378 -44.438316)
		(stroke
			(width 0.06223)
			(type default)
		)
		(layer "F.Cu")
	)
	(gr_line
		(start 130.57378 -44.097448)
		(end 130.602228 -44.069)
		(stroke
			(width 0.06223)
			(type default)
		)
		(layer "F.Cu")
	)
	(gr_line
		(start 130.576574 -40.781478)
		(end 130.576574 -40.781732)
		(stroke
			(width 0.06223)
			(type default)
		)
		(layer "F.Cu")
	)
	(gr_line
		(start 130.576574 -40.781478)
		(end 131.16179 -40.40124)
		(stroke
			(width 0.06223)
			(type default)
		)
		(layer "F.Cu")
	)
	(gr_line
		(start 130.606292 -39.95674)
		(end 130.975354 -40.034972)
		(stroke
			(width 0.06223)
			(type default)
		)
		(layer "F.Cu")
	)
	(gr_line
		(start 130.694938 -43.553634)
		(end 130.735324 -43.491912)
		(stroke
			(width 0.06223)
			(type default)
		)
		(layer "F.Cu")
	)
	(gr_line
		(start 130.719576 -76.919328)
		(end 130.773932 -76.864972)
		(stroke
			(width 0.04445)
			(type default)
		)
		(layer "F.Cu")
	)
	(gr_line
		(start 130.749548 -77.109828)
		(end 130.773932 -77.134212)
		(stroke
			(width 0.04445)
			(type default)
		)
		(layer "F.Cu")
	)
	(gr_line
		(start 130.77571 -77.13599)
		(end 130.842512 -77.202792)
		(stroke
			(width 0.04445)
			(type default)
		)
		(layer "F.Cu")
	)
	(gr_line
		(start 130.77571 -76.863194)
		(end 130.842512 -76.796392)
		(stroke
			(width 0.04445)
			(type default)
		)
		(layer "F.Cu")
	)
	(gr_line
		(start 130.788918 -54.124098)
		(end 130.810508 -54.110128)
		(stroke
			(width 0.04445)
			(type default)
		)
		(layer "F.Cu")
	)
	(gr_line
		(start 130.842512 -77.202792)
		(end 130.86461 -77.202792)
		(stroke
			(width 0.04445)
			(type default)
		)
		(layer "F.Cu")
	)
	(gr_line
		(start 130.842512 -76.796392)
		(end 130.86461 -76.796392)
		(stroke
			(width 0.04445)
			(type default)
		)
		(layer "F.Cu")
	)
	(gr_line
		(start 130.85191 -55.080916)
		(end 130.873754 -55.066438)
		(stroke
			(width 0.04445)
			(type default)
		)
		(layer "F.Cu")
	)
	(gr_line
		(start 130.86461 -77.202792)
		(end 131.018026 -77.202792)
		(stroke
			(width 0.06223)
			(type default)
		)
		(layer "F.Cu")
	)
	(gr_line
		(start 130.937508 -76.05014)
		(end 131.068318 -76.05014)
		(stroke
			(width 0.04445)
			(type default)
		)
		(layer "F.Cu")
	)
	(gr_line
		(start 131.068318 -76.05014)
		(end 131.14528 -75.973178)
		(stroke
			(width 0.04445)
			(type default)
		)
		(layer "F.Cu")
	)
	(gr_line
		(start 131.143502 -76.24064)
		(end 131.14528 -76.242418)
		(stroke
			(width 0.04445)
			(type default)
		)
		(layer "F.Cu")
	)
	(gr_line
		(start 131.147058 -76.244196)
		(end 131.21386 -76.310998)
		(stroke
			(width 0.04445)
			(type default)
		)
		(layer "F.Cu")
	)
	(gr_line
		(start 131.147058 -75.9714)
		(end 131.21386 -75.904598)
		(stroke
			(width 0.04445)
			(type default)
		)
		(layer "F.Cu")
	)
	(gr_line
		(start 131.154932 -45.366432)
		(end 131.15798 -45.363384)
		(stroke
			(width 0.06223)
			(type default)
		)
		(layer "F.Cu")
	)
	(gr_line
		(start 131.15798 -44.997116)
		(end 131.15798 -45.363384)
		(stroke
			(width 0.06223)
			(type default)
		)
		(layer "F.Cu")
	)
	(gr_line
		(start 131.15798 -44.046648)
		(end 131.15798 -44.438316)
		(stroke
			(width 0.06223)
			(type default)
		)
		(layer "F.Cu")
	)
	(gr_line
		(start 131.21386 -76.310998)
		(end 131.235958 -76.310998)
		(stroke
			(width 0.04445)
			(type default)
		)
		(layer "F.Cu")
	)
	(gr_line
		(start 131.21386 -75.904598)
		(end 131.235958 -75.904598)
		(stroke
			(width 0.04445)
			(type default)
		)
		(layer "F.Cu")
	)
	(gr_line
		(start 131.235958 -76.310998)
		(end 131.366768 -76.310998)
		(stroke
			(width 0.06223)
			(type default)
		)
		(layer "F.Cu")
	)
	(gr_line
		(start 131.289552 -53.799232)
		(end 131.297426 -53.794152)
		(stroke
			(width 0.04445)
			(type default)
		)
		(layer "F.Cu")
	)
	(gr_line
		(start 131.297426 -53.794152)
		(end 131.302506 -53.786024)
		(stroke
			(width 0.04445)
			(type default)
		)
		(layer "F.Cu")
	)
	(gr_line
		(start 131.416044 -56.890412)
		(end 131.520946 -56.890412)
		(stroke
			(width 0.04445)
			(type default)
		)
		(layer "F.Cu")
	)
	(gr_line
		(start 131.42722 -74.919332)
		(end 131.539488 -74.919332)
		(stroke
			(width 0.04445)
			(type default)
		)
		(layer "F.Cu")
	)
	(gr_line
		(start 131.431284 -52.84089)
		(end 131.443222 -52.822348)
		(stroke
			(width 0.04445)
			(type default)
		)
		(layer "F.Cu")
	)
	(gr_line
		(start 131.431284 -52.84089)
		(end 131.494276 -53.134768)
		(stroke
			(width 0.04445)
			(type default)
		)
		(layer "F.Cu")
	)
	(gr_line
		(start 131.523486 -56.887872)
		(end 131.692396 -56.718962)
		(stroke
			(width 0.04445)
			(type default)
		)
		(layer "F.Cu")
	)
	(gr_line
		(start 131.542028 -74.916792)
		(end 131.703572 -74.755248)
		(stroke
			(width 0.04445)
			(type default)
		)
		(layer "F.Cu")
	)
	(gr_line
		(start 131.579366 -73.919334)
		(end 131.71043 -73.919334)
		(stroke
			(width 0.04445)
			(type default)
		)
		(layer "F.Cu")
	)
	(gr_line
		(start 131.637532 -52.52212)
		(end 131.664964 -52.479702)
		(stroke
			(width 0.06223)
			(type default)
		)
		(layer "F.Cu")
	)
	(gr_line
		(start 131.647946 -57.080912)
		(end 131.692396 -57.125362)
		(stroke
			(width 0.04445)
			(type default)
		)
		(layer "F.Cu")
	)
	(gr_line
		(start 131.651756 -75.109832)
		(end 131.703572 -75.161648)
		(stroke
			(width 0.04445)
			(type default)
		)
		(layer "F.Cu")
	)
	(gr_line
		(start 131.664964 -52.479702)
		(end 131.704334 -52.454048)
		(stroke
			(width 0.06223)
			(type default)
		)
		(layer "F.Cu")
	)
	(gr_line
		(start 131.671314 -53.21681)
		(end 131.771136 -53.062632)
		(stroke
			(width 0.04445)
			(type default)
		)
		(layer "F.Cu")
	)
	(gr_line
		(start 131.688078 -59.080908)
		(end 131.727448 -59.120278)
		(stroke
			(width 0.04445)
			(type default)
		)
		(layer "F.Cu")
	)
	(gr_line
		(start 131.688078 -58.890408)
		(end 131.727448 -58.851038)
		(stroke
			(width 0.04445)
			(type default)
		)
		(layer "F.Cu")
	)
	(gr_line
		(start 131.692396 -57.125362)
		(end 131.714494 -57.125362)
		(stroke
			(width 0.04445)
			(type default)
		)
		(layer "F.Cu")
	)
	(gr_line
		(start 131.692396 -56.718962)
		(end 131.714494 -56.718962)
		(stroke
			(width 0.04445)
			(type default)
		)
		(layer "F.Cu")
	)
	(gr_line
		(start 131.703572 -75.161648)
		(end 131.72567 -75.161648)
		(stroke
			(width 0.04445)
			(type default)
		)
		(layer "F.Cu")
	)
	(gr_line
		(start 131.703572 -74.755248)
		(end 131.72567 -74.755248)
		(stroke
			(width 0.04445)
			(type default)
		)
		(layer "F.Cu")
	)
	(gr_line
		(start 131.71043 -73.919334)
		(end 131.787138 -73.842626)
		(stroke
			(width 0.04445)
			(type default)
		)
		(layer "F.Cu")
	)
	(gr_line
		(start 131.714494 -57.125362)
		(end 131.819396 -57.125362)
		(stroke
			(width 0.06223)
			(type default)
		)
		(layer "F.Cu")
	)
	(gr_line
		(start 131.719828 -58.08091)
		(end 131.759198 -58.12028)
		(stroke
			(width 0.04445)
			(type default)
		)
		(layer "F.Cu")
	)
	(gr_line
		(start 131.719828 -57.89041)
		(end 131.759198 -57.85104)
		(stroke
			(width 0.04445)
			(type default)
		)
		(layer "F.Cu")
	)
	(gr_line
		(start 131.72567 -75.161648)
		(end 131.837938 -75.161648)
		(stroke
			(width 0.06223)
			(type default)
		)
		(layer "F.Cu")
	)
	(gr_line
		(start 131.729226 -59.122056)
		(end 131.796028 -59.188858)
		(stroke
			(width 0.04445)
			(type default)
		)
		(layer "F.Cu")
	)
	(gr_line
		(start 131.729226 -58.84926)
		(end 131.796028 -58.782458)
		(stroke
			(width 0.04445)
			(type default)
		)
		(layer "F.Cu")
	)
	(gr_line
		(start 131.750816 -56.01335)
		(end 131.755388 -56.012334)
		(stroke
			(width 0.04445)
			(type default)
		)
		(layer "F.Cu")
	)
	(gr_line
		(start 131.755388 -56.012334)
		(end 131.758944 -56.010048)
		(stroke
			(width 0.04445)
			(type default)
		)
		(layer "F.Cu")
	)
	(gr_line
		(start 131.760976 -58.122058)
		(end 131.827778 -58.18886)
		(stroke
			(width 0.04445)
			(type default)
		)
		(layer "F.Cu")
	)
	(gr_line
		(start 131.760976 -57.849262)
		(end 131.827778 -57.78246)
		(stroke
			(width 0.04445)
			(type default)
		)
		(layer "F.Cu")
	)
	(gr_line
		(start 131.771136 -53.062632)
		(end 131.772152 -53.062378)
		(stroke
			(width 0.04445)
			(type default)
		)
		(layer "F.Cu")
	)
	(gr_line
		(start 131.772152 -53.062378)
		(end 131.78409 -53.043836)
		(stroke
			(width 0.04445)
			(type default)
		)
		(layer "F.Cu")
	)
	(gr_line
		(start 131.776724 -54.237636)
		(end 131.807458 -54.092094)
		(stroke
			(width 0.04445)
			(type default)
		)
		(layer "F.Cu")
	)
	(gr_line
		(start 131.785106 -74.109834)
		(end 131.787138 -74.111866)
		(stroke
			(width 0.04445)
			(type default)
		)
		(layer "F.Cu")
	)
	(gr_line
		(start 131.788916 -74.113644)
		(end 131.855718 -74.180446)
		(stroke
			(width 0.04445)
			(type default)
		)
		(layer "F.Cu")
	)
	(gr_line
		(start 131.788916 -73.840848)
		(end 131.855718 -73.774046)
		(stroke
			(width 0.04445)
			(type default)
		)
		(layer "F.Cu")
	)
	(gr_line
		(start 131.796028 -59.188858)
		(end 131.818126 -59.188858)
		(stroke
			(width 0.04445)
			(type default)
		)
		(layer "F.Cu")
	)
	(gr_line
		(start 131.796028 -58.782458)
		(end 131.818126 -58.782458)
		(stroke
			(width 0.04445)
			(type default)
		)
		(layer "F.Cu")
	)
	(gr_line
		(start 131.807458 -54.092094)
		(end 131.826 -54.080156)
		(stroke
			(width 0.04445)
			(type default)
		)
		(layer "F.Cu")
	)
	(gr_line
		(start 131.827778 -58.18886)
		(end 131.849876 -58.18886)
		(stroke
			(width 0.04445)
			(type default)
		)
		(layer "F.Cu")
	)
	(gr_line
		(start 131.827778 -57.78246)
		(end 131.849876 -57.78246)
		(stroke
			(width 0.04445)
			(type default)
		)
		(layer "F.Cu")
	)
	(gr_line
		(start 131.855718 -74.180446)
		(end 131.877816 -74.180446)
		(stroke
			(width 0.04445)
			(type default)
		)
		(layer "F.Cu")
	)
	(gr_line
		(start 131.855718 -73.774046)
		(end 131.877816 -73.774046)
		(stroke
			(width 0.04445)
			(type default)
		)
		(layer "F.Cu")
	)
	(gr_line
		(start 131.877816 -74.180446)
		(end 132.00888 -74.180446)
		(stroke
			(width 0.06223)
			(type default)
		)
		(layer "F.Cu")
	)
	(gr_line
		(start 131.882896 -54.40172)
		(end 132.0292 -54.432708)
		(stroke
			(width 0.04445)
			(type default)
		)
		(layer "F.Cu")
	)
	(gr_line
		(start 131.95046 -60.426854)
		(end 132.112258 -60.426854)
		(stroke
			(width 0.04445)
			(type default)
		)
		(layer "F.Cu")
	)
	(gr_line
		(start 132.0292 -54.432708)
		(end 132.047742 -54.42077)
		(stroke
			(width 0.04445)
			(type default)
		)
		(layer "F.Cu")
	)
	(gr_line
		(start 132.112258 -60.426854)
		(end 132.158232 -60.472828)
		(stroke
			(width 0.04445)
			(type default)
		)
		(layer "F.Cu")
	)
	(gr_line
		(start 132.125466 -60.236354)
		(end 132.158232 -60.203588)
		(stroke
			(width 0.04445)
			(type default)
		)
		(layer "F.Cu")
	)
	(gr_line
		(start 132.16001 -60.474606)
		(end 132.226812 -60.541408)
		(stroke
			(width 0.04445)
			(type default)
		)
		(layer "F.Cu")
	)
	(gr_line
		(start 132.16001 -60.20181)
		(end 132.226812 -60.135008)
		(stroke
			(width 0.04445)
			(type default)
		)
		(layer "F.Cu")
	)
	(gr_line
		(start 132.220208 -46.70044)
		(end 132.220208 -46.957742)
		(stroke
			(width 0.06223)
			(type default)
		)
		(layer "F.Cu")
	)
	(gr_arc
		(start 132.220208 -46.072044)
		(mid 132.228657 -46.114521)
		(end 132.25272 -46.15053)
		(stroke
			(width 0.06223)
			(type default)
		)
		(layer "F.Cu")
	)
	(gr_line
		(start 132.220208 -45.814742)
		(end 132.220208 -46.072044)
		(stroke
			(width 0.06223)
			(type default)
		)
		(layer "F.Cu")
	)
	(gr_line
		(start 132.226812 -60.541408)
		(end 132.24891 -60.541408)
		(stroke
			(width 0.04445)
			(type default)
		)
		(layer "F.Cu")
	)
	(gr_line
		(start 132.226812 -60.135008)
		(end 132.24891 -60.135008)
		(stroke
			(width 0.04445)
			(type default)
		)
		(layer "F.Cu")
	)
	(gr_line
		(start 132.24891 -60.135008)
		(end 132.410708 -60.135008)
		(stroke
			(width 0.06223)
			(type default)
		)
		(layer "F.Cu")
	)
	(gr_arc
		(start 132.25272 -46.621954)
		(mid 132.228671 -46.657966)
		(end 132.220208 -46.70044)
		(stroke
			(width 0.06223)
			(type default)
		)
		(layer "F.Cu")
	)
	(gr_arc
		(start 132.25272 -46.15053)
		(mid 132.28873 -46.174591)
		(end 132.331206 -46.183042)
		(stroke
			(width 0.06223)
			(type default)
		)
		(layer "F.Cu")
	)
	(gr_line
		(start 132.274056 -76.866242)
		(end 132.34035 -76.932536)
		(stroke
			(width 0.06223)
			(type default)
		)
		(layer "F.Cu")
	)
	(gr_line
		(start 132.274818 -55.447692)
		(end 132.330444 -55.41137)
		(stroke
			(width 0.04445)
			(type default)
		)
		(layer "F.Cu")
	)
	(gr_line
		(start 132.275834 -76.289662)
		(end 132.653024 -76.289662)
		(stroke
			(width 0.06223)
			(type default)
		)
		(layer "F.Cu")
	)
	(gr_line
		(start 132.330444 -55.41137)
		(end 132.352288 -55.329328)
		(stroke
			(width 0.04445)
			(type default)
		)
		(layer "F.Cu")
	)
	(gr_arc
		(start 132.331206 -46.589442)
		(mid 132.288724 -46.597886)
		(end 132.25272 -46.621954)
		(stroke
			(width 0.06223)
			(type default)
		)
		(layer "F.Cu")
	)
	(gr_line
		(start 132.352288 -55.329328)
		(end 132.37083 -55.31739)
		(stroke
			(width 0.04445)
			(type default)
		)
		(layer "F.Cu")
	)
	(gr_line
		(start 132.357114 -55.624222)
		(end 132.573776 -55.670196)
		(stroke
			(width 0.04445)
			(type default)
		)
		(layer "F.Cu")
	)
	(gr_line
		(start 132.573776 -55.670196)
		(end 132.592318 -55.658258)
		(stroke
			(width 0.04445)
			(type default)
		)
		(layer "F.Cu")
	)
	(gr_line
		(start 132.653024 -76.289662)
		(end 132.91693 -76.553568)
		(stroke
			(width 0.06223)
			(type default)
		)
		(layer "F.Cu")
	)
	(gr_line
		(start 132.663438 -50.226468)
		(end 132.696966 -50.20437)
		(stroke
			(width 0.06223)
			(type default)
		)
		(layer "F.Cu")
	)
	(gr_line
		(start 132.696966 -50.20437)
		(end 132.719064 -50.170588)
		(stroke
			(width 0.06223)
			(type default)
		)
		(layer "F.Cu")
	)
	(gr_line
		(start 132.761482 -37.4904)
		(end 132.79628 -37.467794)
		(stroke
			(width 0.06223)
			(type default)
		)
		(layer "F.Cu")
	)
	(gr_line
		(start 132.76453 -57.125362)
		(end 132.828284 -57.08396)
		(stroke
			(width 0.06223)
			(type default)
		)
		(layer "F.Cu")
	)
	(gr_line
		(start 132.776468 -40.348408)
		(end 132.799074 -40.31361)
		(stroke
			(width 0.06223)
			(type default)
		)
		(layer "F.Cu")
	)
	(gr_line
		(start 132.780532 -75.651868)
		(end 132.84708 -75.718416)
		(stroke
			(width 0.06223)
			(type default)
		)
		(layer "F.Cu")
	)
	(gr_line
		(start 132.78231 -75.075288)
		(end 133.159754 -75.075288)
		(stroke
			(width 0.06223)
			(type default)
		)
		(layer "F.Cu")
	)
	(gr_line
		(start 132.79628 -37.467794)
		(end 132.818886 -37.432996)
		(stroke
			(width 0.06223)
			(type default)
		)
		(layer "F.Cu")
	)
	(gr_line
		(start 132.799074 -40.31361)
		(end 132.833872 -40.291004)
		(stroke
			(width 0.06223)
			(type default)
		)
		(layer "F.Cu")
	)
	(gr_line
		(start 132.85597 -52.191158)
		(end 132.890768 -52.168552)
		(stroke
			(width 0.06223)
			(type default)
		)
		(layer "F.Cu")
	)
	(gr_line
		(start 132.890768 -52.168552)
		(end 132.913374 -52.133754)
		(stroke
			(width 0.06223)
			(type default)
		)
		(layer "F.Cu")
	)
	(gr_line
		(start 132.91693 -76.553568)
		(end 132.91693 -76.930758)
		(stroke
			(width 0.06223)
			(type default)
		)
		(layer "F.Cu")
	)
	(gr_line
		(start 133.14553 -45.348652)
		(end 133.148578 -45.3517)
		(stroke
			(width 0.06223)
			(type default)
		)
		(layer "F.Cu")
	)
	(gr_line
		(start 133.14553 -44.982384)
		(end 133.14553 -45.348652)
		(stroke
			(width 0.06223)
			(type default)
		)
		(layer "F.Cu")
	)
	(gr_line
		(start 133.14553 -44.082716)
		(end 133.14553 -44.423584)
		(stroke
			(width 0.06223)
			(type default)
		)
		(layer "F.Cu")
	)
	(gr_line
		(start 133.14553 -44.082716)
		(end 133.173978 -44.054268)
		(stroke
			(width 0.06223)
			(type default)
		)
		(layer "F.Cu")
	)
	(gr_line
		(start 133.159754 -75.075288)
		(end 133.42366 -75.339448)
		(stroke
			(width 0.06223)
			(type default)
		)
		(layer "F.Cu")
	)
	(gr_line
		(start 133.181344 -39.090346)
		(end 133.216142 -39.06774)
		(stroke
			(width 0.06223)
			(type default)
		)
		(layer "F.Cu")
	)
	(gr_line
		(start 133.202934 -79.928466)
		(end 133.269482 -79.995014)
		(stroke
			(width 0.06223)
			(type default)
		)
		(layer "F.Cu")
	)
	(gr_line
		(start 133.204712 -79.351886)
		(end 133.582156 -79.351886)
		(stroke
			(width 0.06223)
			(type default)
		)
		(layer "F.Cu")
	)
	(gr_line
		(start 133.216142 -39.06774)
		(end 133.238748 -39.032942)
		(stroke
			(width 0.06223)
			(type default)
		)
		(layer "F.Cu")
	)
	(gr_line
		(start 133.25983 -43.398694)
		(end 133.300724 -43.335702)
		(stroke
			(width 0.06223)
			(type default)
		)
		(layer "F.Cu")
	)
	(gr_line
		(start 133.41858 -42.659808)
		(end 133.496812 -43.02887)
		(stroke
			(width 0.06223)
			(type default)
		)
		(layer "F.Cu")
	)
	(gr_line
		(start 133.41858 -42.659808)
		(end 133.62178 -42.346626)
		(stroke
			(width 0.06223)
			(type default)
		)
		(layer "F.Cu")
	)
	(gr_line
		(start 133.42366 -75.339448)
		(end 133.42366 -75.716638)
		(stroke
			(width 0.06223)
			(type default)
		)
		(layer "F.Cu")
	)
	(gr_line
		(start 133.500368 -53.474366)
		(end 133.535674 -53.451252)
		(stroke
			(width 0.06223)
			(type default)
		)
		(layer "F.Cu")
	)
	(gr_line
		(start 133.535674 -53.451252)
		(end 133.558788 -53.415692)
		(stroke
			(width 0.06223)
			(type default)
		)
		(layer "F.Cu")
	)
	(gr_line
		(start 133.582156 -79.351886)
		(end 133.846062 -79.616046)
		(stroke
			(width 0.06223)
			(type default)
		)
		(layer "F.Cu")
	)
	(gr_line
		(start 133.62178 -42.346626)
		(end 133.990842 -42.26814)
		(stroke
			(width 0.06223)
			(type default)
		)
		(layer "F.Cu")
	)
	(gr_line
		(start 133.692392 -74.65187)
		(end 133.75894 -74.718418)
		(stroke
			(width 0.06223)
			(type default)
		)
		(layer "F.Cu")
	)
	(gr_line
		(start 133.69417 -74.07529)
		(end 134.071614 -74.07529)
		(stroke
			(width 0.06223)
			(type default)
		)
		(layer "F.Cu")
	)
	(gr_line
		(start 133.726682 -45.3517)
		(end 133.72973 -45.348652)
		(stroke
			(width 0.06223)
			(type default)
		)
		(layer "F.Cu")
	)
	(gr_line
		(start 133.72973 -44.982384)
		(end 133.72973 -45.348652)
		(stroke
			(width 0.06223)
			(type default)
		)
		(layer "F.Cu")
	)
	(gr_line
		(start 133.72973 -44.031916)
		(end 133.72973 -44.423584)
		(stroke
			(width 0.06223)
			(type default)
		)
		(layer "F.Cu")
	)
	(gr_line
		(start 133.846062 -79.616046)
		(end 133.846062 -79.993236)
		(stroke
			(width 0.06223)
			(type default)
		)
		(layer "F.Cu")
	)
	(gr_line
		(start 133.848348 -57.86628)
		(end 133.879336 -57.859676)
		(stroke
			(width 0.06223)
			(type default)
		)
		(layer "F.Cu")
	)
	(gr_line
		(start 133.862826 -43.216322)
		(end 134.311136 -42.52595)
		(stroke
			(width 0.06223)
			(type default)
		)
		(layer "F.Cu")
	)
	(gr_line
		(start 133.879336 -57.859676)
		(end 133.90626 -57.84215)
		(stroke
			(width 0.06223)
			(type default)
		)
		(layer "F.Cu")
	)
	(gr_line
		(start 134.071614 -74.07529)
		(end 134.33552 -74.33945)
		(stroke
			(width 0.06223)
			(type default)
		)
		(layer "F.Cu")
	)
	(gr_line
		(start 134.335266 -54.526434)
		(end 134.370064 -54.503828)
		(stroke
			(width 0.06223)
			(type default)
		)
		(layer "F.Cu")
	)
	(gr_line
		(start 134.33552 -74.33945)
		(end 134.33552 -74.71664)
		(stroke
			(width 0.06223)
			(type default)
		)
		(layer "F.Cu")
	)
	(gr_line
		(start 134.370064 -54.503828)
		(end 134.39267 -54.46903)
		(stroke
			(width 0.06223)
			(type default)
		)
		(layer "F.Cu")
	)
	(gr_line
		(start 134.38632 -58.997088)
		(end 134.415784 -58.990992)
		(stroke
			(width 0.06223)
			(type default)
		)
		(layer "F.Cu")
	)
	(gr_line
		(start 134.415784 -58.990992)
		(end 134.441692 -58.973974)
		(stroke
			(width 0.06223)
			(type default)
		)
		(layer "F.Cu")
	)
	(gr_line
		(start 134.649972 -38.419024)
		(end 134.728458 -38.787832)
		(stroke
			(width 0.06223)
			(type default)
		)
		(layer "F.Cu")
	)
	(gr_line
		(start 134.649972 -38.419024)
		(end 134.86003 -38.095174)
		(stroke
			(width 0.06223)
			(type default)
		)
		(layer "F.Cu")
	)
	(gr_line
		(start 134.686294 -39.572946)
		(end 134.721092 -39.55034)
		(stroke
			(width 0.06223)
			(type default)
		)
		(layer "F.Cu")
	)
	(gr_line
		(start 134.721092 -39.55034)
		(end 134.743698 -39.515542)
		(stroke
			(width 0.06223)
			(type default)
		)
		(layer "F.Cu")
	)
	(gr_line
		(start 134.742174 -60.223654)
		(end 134.772654 -60.21705)
		(stroke
			(width 0.06223)
			(type default)
		)
		(layer "F.Cu")
	)
	(gr_line
		(start 134.772654 -60.21705)
		(end 134.798816 -60.200032)
		(stroke
			(width 0.06223)
			(type default)
		)
		(layer "F.Cu")
	)
	(gr_line
		(start 134.86003 -38.095174)
		(end 135.229346 -38.016688)
		(stroke
			(width 0.06223)
			(type default)
		)
		(layer "F.Cu")
	)
	(gr_line
		(start 135.092694 -55.613046)
		(end 135.127492 -55.59044)
		(stroke
			(width 0.06223)
			(type default)
		)
		(layer "F.Cu")
	)
	(gr_line
		(start 135.094726 -38.974776)
		(end 135.549894 -38.273736)
		(stroke
			(width 0.06223)
			(type default)
		)
		(layer "F.Cu")
	)
	(gr_line
		(start 135.127492 -55.59044)
		(end 135.150098 -55.555642)
		(stroke
			(width 0.06223)
			(type default)
		)
		(layer "F.Cu")
	)
	(gr_line
		(start 135.627618 -77.830934)
		(end 135.902192 -77.830934)
		(stroke
			(width 0.06223)
			(type default)
		)
		(layer "F.Cu")
	)
	(gr_line
		(start 135.646414 -77.272134)
		(end 135.902192 -77.272134)
		(stroke
			(width 0.06223)
			(type default)
		)
		(layer "F.Cu")
	)
	(gr_line
		(start 135.67664 -79.730092)
		(end 135.947912 -79.730092)
		(stroke
			(width 0.06223)
			(type default)
		)
		(layer "F.Cu")
	)
	(gr_line
		(start 135.688832 -79.171292)
		(end 135.947912 -79.171292)
		(stroke
			(width 0.06223)
			(type default)
		)
		(layer "F.Cu")
	)
	(gr_line
		(start 135.69442 -75.91552)
		(end 135.969502 -75.91552)
		(stroke
			(width 0.06223)
			(type default)
		)
		(layer "F.Cu")
	)
	(gr_line
		(start 135.694928 -81.1276)
		(end 135.9662 -81.1276)
		(stroke
			(width 0.06223)
			(type default)
		)
		(layer "F.Cu")
	)
	(gr_line
		(start 135.70712 -80.5688)
		(end 135.9662 -80.5688)
		(stroke
			(width 0.06223)
			(type default)
		)
		(layer "F.Cu")
	)
	(gr_line
		(start 135.709914 -75.35672)
		(end 135.969502 -75.35672)
		(stroke
			(width 0.06223)
			(type default)
		)
		(layer "F.Cu")
	)
	(gr_line
		(start 136.460992 -77.830934)
		(end 136.585198 -77.830934)
		(stroke
			(width 0.06223)
			(type default)
		)
		(layer "F.Cu")
	)
	(gr_line
		(start 136.460992 -77.272134)
		(end 136.610598 -77.272134)
		(stroke
			(width 0.06223)
			(type default)
		)
		(layer "F.Cu")
	)
	(gr_line
		(start 136.506712 -79.730092)
		(end 136.88568 -79.730092)
		(stroke
			(width 0.06223)
			(type default)
		)
		(layer "F.Cu")
	)
	(gr_line
		(start 136.506712 -79.171292)
		(end 136.88568 -79.171292)
		(stroke
			(width 0.06223)
			(type default)
		)
		(layer "F.Cu")
	)
	(gr_line
		(start 136.525 -81.1276)
		(end 136.903968 -81.1276)
		(stroke
			(width 0.06223)
			(type default)
		)
		(layer "F.Cu")
	)
	(gr_line
		(start 136.525 -80.5688)
		(end 136.903968 -80.5688)
		(stroke
			(width 0.06223)
			(type default)
		)
		(layer "F.Cu")
	)
	(gr_line
		(start 136.563354 -52.632356)
		(end 137.013188 -51.939698)
		(stroke
			(width 0.06223)
			(type default)
		)
		(layer "F.Cu")
	)
	(gr_line
		(start 136.585198 -77.830934)
		(end 136.588246 -77.827886)
		(stroke
			(width 0.06223)
			(type default)
		)
		(layer "F.Cu")
	)
	(gr_line
		(start 136.88441 -52.88915)
		(end 137.253726 -52.810664)
		(stroke
			(width 0.06223)
			(type default)
		)
		(layer "F.Cu")
	)
	(gr_line
		(start 137.067798 -55.784242)
		(end 137.10412 -55.76062)
		(stroke
			(width 0.06223)
			(type default)
		)
		(layer "F.Cu")
	)
	(gr_line
		(start 137.10412 -55.76062)
		(end 137.127742 -55.724044)
		(stroke
			(width 0.06223)
			(type default)
		)
		(layer "F.Cu")
	)
	(gr_line
		(start 137.253726 -52.810664)
		(end 137.456926 -52.497482)
		(stroke
			(width 0.06223)
			(type default)
		)
		(layer "F.Cu")
	)
	(gr_line
		(start 137.263632 -51.554126)
		(end 137.712958 -50.86223)
		(stroke
			(width 0.06223)
			(type default)
		)
		(layer "F.Cu")
	)
	(gr_line
		(start 137.37844 -52.12842)
		(end 137.456926 -52.497482)
		(stroke
			(width 0.06223)
			(type default)
		)
		(layer "F.Cu")
	)
	(gr_line
		(start 137.58418 -51.811174)
		(end 137.953496 -51.732688)
		(stroke
			(width 0.06223)
			(type default)
		)
		(layer "F.Cu")
	)
	(gr_line
		(start 137.953496 -51.732688)
		(end 138.156696 -51.419506)
		(stroke
			(width 0.06223)
			(type default)
		)
		(layer "F.Cu")
	)
	(gr_line
		(start 138.01598 -56.625236)
		(end 138.049254 -56.603392)
		(stroke
			(width 0.06223)
			(type default)
		)
		(layer "F.Cu")
	)
	(gr_line
		(start 138.049254 -56.603392)
		(end 138.070844 -56.570118)
		(stroke
			(width 0.06223)
			(type default)
		)
		(layer "F.Cu")
	)
	(gr_line
		(start 138.078464 -51.05019)
		(end 138.156696 -51.419506)
		(stroke
			(width 0.06223)
			(type default)
		)
		(layer "F.Cu")
	)
	(gr_line
		(start 138.130534 -55.731918)
		(end 138.578082 -55.043324)
		(stroke
			(width 0.06223)
			(type default)
		)
		(layer "F.Cu")
	)
	(gr_line
		(start 138.450574 -55.990236)
		(end 138.819382 -55.912004)
		(stroke
			(width 0.06223)
			(type default)
		)
		(layer "F.Cu")
	)
	(gr_line
		(start 138.479022 -76.52512)
		(end 138.721592 -76.52512)
		(stroke
			(width 0.06223)
			(type default)
		)
		(layer "F.Cu")
	)
	(gr_line
		(start 138.486134 -78.427834)
		(end 138.728704 -78.427834)
		(stroke
			(width 0.06223)
			(type default)
		)
		(layer "F.Cu")
	)
	(gr_line
		(start 138.500612 -80.197452)
		(end 138.743182 -80.197452)
		(stroke
			(width 0.06223)
			(type default)
		)
		(layer "F.Cu")
	)
	(gr_line
		(start 138.579606 -27.814524)
		(end 138.602212 -27.779726)
		(stroke
			(width 0.06223)
			(type default)
		)
		(layer "F.Cu")
	)
	(gr_line
		(start 138.602212 -27.779726)
		(end 138.63701 -27.75712)
		(stroke
			(width 0.06223)
			(type default)
		)
		(layer "F.Cu")
	)
	(gr_arc
		(start 138.721592 -76.52512)
		(mid 138.769469 -76.515543)
		(end 138.809984 -76.48829)
		(stroke
			(width 0.06223)
			(type default)
		)
		(layer "F.Cu")
	)
	(gr_arc
		(start 138.728704 -78.427834)
		(mid 138.776579 -78.418254)
		(end 138.817096 -78.391004)
		(stroke
			(width 0.06223)
			(type default)
		)
		(layer "F.Cu")
	)
	(gr_line
		(start 138.739118 -64.972184)
		(end 138.981942 -64.972184)
		(stroke
			(width 0.06223)
			(type default)
		)
		(layer "F.Cu")
	)
	(gr_line
		(start 138.80465 -63.045086)
		(end 139.047474 -63.045086)
		(stroke
			(width 0.06223)
			(type default)
		)
		(layer "F.Cu")
	)
	(gr_line
		(start 138.809984 -76.48829)
		(end 138.810238 -76.488036)
		(stroke
			(width 0.06223)
			(type default)
		)
		(layer "F.Cu")
	)
	(gr_arc
		(start 138.810238 -76.488036)
		(mid 138.837622 -76.447138)
		(end 138.847322 -76.398882)
		(stroke
			(width 0.06223)
			(type default)
		)
		(layer "F.Cu")
	)
	(gr_line
		(start 138.817096 -78.391004)
		(end 138.81735 -78.39075)
		(stroke
			(width 0.06223)
			(type default)
		)
		(layer "F.Cu")
	)
	(gr_arc
		(start 138.81735 -78.39075)
		(mid 138.844736 -78.349852)
		(end 138.854434 -78.301596)
		(stroke
			(width 0.06223)
			(type default)
		)
		(layer "F.Cu")
	)
	(gr_line
		(start 138.819382 -55.912004)
		(end 139.022836 -55.598822)
		(stroke
			(width 0.06223)
			(type default)
		)
		(layer "F.Cu")
	)
	(gr_line
		(start 138.830304 -54.65445)
		(end 139.27836 -53.965094)
		(stroke
			(width 0.06223)
			(type default)
		)
		(layer "F.Cu")
	)
	(gr_line
		(start 138.831574 -80.160622)
		(end 138.831828 -80.160368)
		(stroke
			(width 0.06223)
			(type default)
		)
		(layer "F.Cu")
	)
	(gr_line
		(start 138.843258 -82.308446)
		(end 139.085828 -82.308446)
		(stroke
			(width 0.06223)
			(type default)
		)
		(layer "F.Cu")
	)
	(gr_line
		(start 138.94435 -55.230014)
		(end 139.022836 -55.598822)
		(stroke
			(width 0.06223)
			(type default)
		)
		(layer "F.Cu")
	)
	(gr_arc
		(start 138.981942 -64.972184)
		(mid 139.030051 -64.962603)
		(end 139.070842 -64.935354)
		(stroke
			(width 0.06223)
			(type default)
		)
		(layer "F.Cu")
	)
	(gr_line
		(start 139.03071 -61.122052)
		(end 139.273534 -61.122052)
		(stroke
			(width 0.06223)
			(type default)
		)
		(layer "F.Cu")
	)
	(gr_arc
		(start 139.047474 -63.045086)
		(mid 139.095576 -63.035495)
		(end 139.136374 -63.008256)
		(stroke
			(width 0.06223)
			(type default)
		)
		(layer "F.Cu")
	)
	(gr_arc
		(start 139.070842 -64.935354)
		(mid 139.097907 -64.894789)
		(end 139.107418 -64.846962)
		(stroke
			(width 0.06223)
			(type default)
		)
		(layer "F.Cu")
	)
	(gr_arc
		(start 139.085828 -82.308446)
		(mid 139.13372 -82.298891)
		(end 139.17422 -82.271616)
		(stroke
			(width 0.06223)
			(type default)
		)
		(layer "F.Cu")
	)
	(gr_arc
		(start 139.136374 -63.008256)
		(mid 139.163433 -62.967689)
		(end 139.17295 -62.919864)
		(stroke
			(width 0.06223)
			(type default)
		)
		(layer "F.Cu")
	)
	(gr_line
		(start 139.150344 -54.912514)
		(end 139.519406 -54.834282)
		(stroke
			(width 0.06223)
			(type default)
		)
		(layer "F.Cu")
	)
	(gr_line
		(start 139.17422 -82.271616)
		(end 139.174474 -82.271362)
		(stroke
			(width 0.06223)
			(type default)
		)
		(layer "F.Cu")
	)
	(gr_arc
		(start 139.174474 -82.271362)
		(mid 139.20188 -82.230469)
		(end 139.211558 -82.182208)
		(stroke
			(width 0.06223)
			(type default)
		)
		(layer "F.Cu")
	)
	(gr_arc
		(start 139.253722 -76.399898)
		(mid 139.26322 -76.447735)
		(end 139.290298 -76.48829)
		(stroke
			(width 0.06223)
			(type default)
		)
		(layer "F.Cu")
	)
	(gr_arc
		(start 139.260834 -78.302612)
		(mid 139.270354 -78.350439)
		(end 139.29741 -78.391004)
		(stroke
			(width 0.06223)
			(type default)
		)
		(layer "F.Cu")
	)
	(gr_arc
		(start 139.273534 -61.122052)
		(mid 139.321643 -61.112472)
		(end 139.362434 -61.085222)
		(stroke
			(width 0.06223)
			(type default)
		)
		(layer "F.Cu")
	)
	(gr_arc
		(start 139.275312 -80.07223)
		(mid 139.284842 -80.120049)
		(end 139.311888 -80.160622)
		(stroke
			(width 0.06223)
			(type default)
		)
		(layer "F.Cu")
	)
	(gr_arc
		(start 139.290298 -76.48829)
		(mid 139.331086 -76.515543)
		(end 139.379198 -76.52512)
		(stroke
			(width 0.06223)
			(type default)
		)
		(layer "F.Cu")
	)
	(gr_arc
		(start 139.29741 -78.391004)
		(mid 139.338198 -78.418253)
		(end 139.38631 -78.427834)
		(stroke
			(width 0.06223)
			(type default)
		)
		(layer "F.Cu")
	)
	(gr_arc
		(start 139.311888 -80.160622)
		(mid 139.352671 -80.187896)
		(end 139.400788 -80.197452)
		(stroke
			(width 0.06223)
			(type default)
		)
		(layer "F.Cu")
	)
	(gr_arc
		(start 139.362434 -61.085222)
		(mid 139.38949 -61.044656)
		(end 139.39901 -60.99683)
		(stroke
			(width 0.06223)
			(type default)
		)
		(layer "F.Cu")
	)
	(gr_line
		(start 139.379198 -76.52512)
		(end 139.622022 -76.52512)
		(stroke
			(width 0.06223)
			(type default)
		)
		(layer "F.Cu")
	)
	(gr_line
		(start 139.38631 -78.427834)
		(end 139.629134 -78.427834)
		(stroke
			(width 0.06223)
			(type default)
		)
		(layer "F.Cu")
	)
	(gr_line
		(start 139.400788 -80.197452)
		(end 139.643612 -80.197452)
		(stroke
			(width 0.06223)
			(type default)
		)
		(layer "F.Cu")
	)
	(gr_line
		(start 139.432284 -81.402174)
		(end 139.432538 -81.402174)
		(stroke
			(width 0.06223)
			(type default)
		)
		(layer "F.Cu")
	)
	(gr_line
		(start 139.446 -58.9026)
		(end 139.688824 -58.9026)
		(stroke
			(width 0.06223)
			(type default)
		)
		(layer "F.Cu")
	)
	(gr_line
		(start 139.452858 -28.7147)
		(end 139.475464 -28.679902)
		(stroke
			(width 0.06223)
			(type default)
		)
		(layer "F.Cu")
	)
	(gr_line
		(start 139.475464 -28.679902)
		(end 139.510262 -28.657296)
		(stroke
			(width 0.06223)
			(type default)
		)
		(layer "F.Cu")
	)
	(gr_line
		(start 139.519406 -54.834282)
		(end 139.72286 -54.5211)
		(stroke
			(width 0.06223)
			(type default)
		)
		(layer "F.Cu")
	)
	(gr_line
		(start 139.550902 -64.9351)
		(end 139.551156 -64.935354)
		(stroke
			(width 0.06223)
			(type default)
		)
		(layer "F.Cu")
	)
	(gr_arc
		(start 139.551156 -64.935354)
		(mid 139.591668 -64.962614)
		(end 139.639548 -64.972184)
		(stroke
			(width 0.06223)
			(type default)
		)
		(layer "F.Cu")
	)
	(gr_line
		(start 139.616434 -63.008002)
		(end 139.616688 -63.008256)
		(stroke
			(width 0.06223)
			(type default)
		)
		(layer "F.Cu")
	)
	(gr_arc
		(start 139.616688 -63.008256)
		(mid 139.6572 -63.035516)
		(end 139.70508 -63.045086)
		(stroke
			(width 0.06223)
			(type default)
		)
		(layer "F.Cu")
	)
	(gr_arc
		(start 139.617958 -82.183224)
		(mid 139.627456 -82.231061)
		(end 139.654534 -82.271616)
		(stroke
			(width 0.06223)
			(type default)
		)
		(layer "F.Cu")
	)
	(gr_line
		(start 139.639548 -64.972184)
		(end 139.882118 -64.972184)
		(stroke
			(width 0.06223)
			(type default)
		)
		(layer "F.Cu")
	)
	(gr_line
		(start 139.644374 -54.152038)
		(end 139.72286 -54.5211)
		(stroke
			(width 0.06223)
			(type default)
		)
		(layer "F.Cu")
	)
	(gr_arc
		(start 139.654534 -82.271616)
		(mid 139.695322 -82.298869)
		(end 139.743434 -82.308446)
		(stroke
			(width 0.06223)
			(type default)
		)
		(layer "F.Cu")
	)
	(gr_arc
		(start 139.688824 -58.9026)
		(mid 139.736938 -58.893026)
		(end 139.777724 -58.86577)
		(stroke
			(width 0.06223)
			(type default)
		)
		(layer "F.Cu")
	)
	(gr_line
		(start 139.70508 -63.045086)
		(end 139.94765 -63.045086)
		(stroke
			(width 0.06223)
			(type default)
		)
		(layer "F.Cu")
	)
	(gr_line
		(start 139.743434 -82.308446)
		(end 139.986258 -82.308446)
		(stroke
			(width 0.06223)
			(type default)
		)
		(layer "F.Cu")
	)
	(gr_arc
		(start 139.777724 -58.86577)
		(mid 139.804798 -58.825207)
		(end 139.8143 -58.777378)
		(stroke
			(width 0.06223)
			(type default)
		)
		(layer "F.Cu")
	)
	(gr_line
		(start 139.842494 -61.084968)
		(end 139.842748 -61.085222)
		(stroke
			(width 0.06223)
			(type default)
		)
		(layer "F.Cu")
	)
	(gr_arc
		(start 139.842748 -61.085222)
		(mid 139.88326 -61.112482)
		(end 139.93114 -61.122052)
		(stroke
			(width 0.06223)
			(type default)
		)
		(layer "F.Cu")
	)
	(gr_line
		(start 139.93114 -61.122052)
		(end 140.17371 -61.122052)
		(stroke
			(width 0.06223)
			(type default)
		)
		(layer "F.Cu")
	)
	(gr_line
		(start 140.147548 -50.325782)
		(end 140.597128 -49.633378)
		(stroke
			(width 0.06223)
			(type default)
		)
		(layer "F.Cu")
	)
	(gr_line
		(start 140.257784 -58.865516)
		(end 140.258038 -58.86577)
		(stroke
			(width 0.06223)
			(type default)
		)
		(layer "F.Cu")
	)
	(gr_arc
		(start 140.258038 -58.86577)
		(mid 140.29855 -58.89303)
		(end 140.34643 -58.9026)
		(stroke
			(width 0.06223)
			(type default)
		)
		(layer "F.Cu")
	)
	(gr_line
		(start 140.34643 -58.9026)
		(end 140.589 -58.9026)
		(stroke
			(width 0.06223)
			(type default)
		)
		(layer "F.Cu")
	)
	(gr_line
		(start 140.367766 -52.287678)
		(end 140.39088 -52.251864)
		(stroke
			(width 0.06223)
			(type default)
		)
		(layer "F.Cu")
	)
	(gr_line
		(start 140.39088 -52.251864)
		(end 140.426948 -52.228496)
		(stroke
			(width 0.06223)
			(type default)
		)
		(layer "F.Cu")
	)
	(gr_line
		(start 140.46835 -50.58283)
		(end 140.837412 -50.504344)
		(stroke
			(width 0.06223)
			(type default)
		)
		(layer "F.Cu")
	)
	(gr_line
		(start 140.730224 -46.2153)
		(end 140.75283 -46.180502)
		(stroke
			(width 0.06223)
			(type default)
		)
		(layer "F.Cu")
	)
	(gr_line
		(start 140.75283 -46.180502)
		(end 140.787628 -46.157896)
		(stroke
			(width 0.06223)
			(type default)
		)
		(layer "F.Cu")
	)
	(gr_line
		(start 140.837412 -50.504344)
		(end 141.040866 -50.191162)
		(stroke
			(width 0.06223)
			(type default)
		)
		(layer "F.Cu")
	)
	(gr_line
		(start 140.847318 -49.247806)
		(end 141.297152 -48.554894)
		(stroke
			(width 0.06223)
			(type default)
		)
		(layer "F.Cu")
	)
	(gr_line
		(start 140.94206 -29.220922)
		(end 140.965682 -29.184346)
		(stroke
			(width 0.06223)
			(type default)
		)
		(layer "F.Cu")
	)
	(gr_line
		(start 140.96238 -49.821846)
		(end 141.040866 -50.191162)
		(stroke
			(width 0.06223)
			(type default)
		)
		(layer "F.Cu")
	)
	(gr_line
		(start 140.965682 -29.184346)
		(end 141.001496 -29.161232)
		(stroke
			(width 0.06223)
			(type default)
		)
		(layer "F.Cu")
	)
	(gr_line
		(start 141.16812 -49.504854)
		(end 141.537182 -49.426368)
		(stroke
			(width 0.06223)
			(type default)
		)
		(layer "F.Cu")
	)
	(gr_line
		(start 141.213078 -40.882316)
		(end 141.235684 -40.847518)
		(stroke
			(width 0.06223)
			(type default)
		)
		(layer "F.Cu")
	)
	(gr_line
		(start 141.235684 -40.847518)
		(end 141.270482 -40.824912)
		(stroke
			(width 0.06223)
			(type default)
		)
		(layer "F.Cu")
	)
	(gr_line
		(start 141.355064 -43.000676)
		(end 141.37767 -42.965878)
		(stroke
			(width 0.06223)
			(type default)
		)
		(layer "F.Cu")
	)
	(gr_line
		(start 141.37767 -42.965878)
		(end 141.412468 -42.943272)
		(stroke
			(width 0.06223)
			(type default)
		)
		(layer "F.Cu")
	)
	(gr_line
		(start 141.480286 -38.196012)
		(end 141.502892 -38.161214)
		(stroke
			(width 0.06223)
			(type default)
		)
		(layer "F.Cu")
	)
	(gr_line
		(start 141.502892 -38.161214)
		(end 141.53769 -38.138608)
		(stroke
			(width 0.06223)
			(type default)
		)
		(layer "F.Cu")
	)
	(gr_line
		(start 141.511528 -35.907472)
		(end 141.997684 -35.160204)
		(stroke
			(width 0.06223)
			(type default)
		)
		(layer "F.Cu")
	)
	(gr_line
		(start 141.537182 -49.426368)
		(end 141.740636 -49.113186)
		(stroke
			(width 0.06223)
			(type default)
		)
		(layer "F.Cu")
	)
	(gr_line
		(start 141.548104 -48.16856)
		(end 141.57071 -48.133762)
		(stroke
			(width 0.06223)
			(type default)
		)
		(layer "F.Cu")
	)
	(gr_line
		(start 141.57071 -48.133762)
		(end 141.605508 -48.111156)
		(stroke
			(width 0.06223)
			(type default)
		)
		(layer "F.Cu")
	)
	(gr_line
		(start 141.66215 -48.744124)
		(end 141.740636 -49.113186)
		(stroke
			(width 0.06223)
			(type default)
		)
		(layer "F.Cu")
	)
	(gr_line
		(start 141.833092 -36.16325)
		(end 142.246858 -36.07562)
		(stroke
			(width 0.06223)
			(type default)
		)
		(layer "F.Cu")
	)
	(gr_line
		(start 141.881098 -30.118558)
		(end 141.903704 -30.08376)
		(stroke
			(width 0.06223)
			(type default)
		)
		(layer "F.Cu")
	)
	(gr_line
		(start 141.903704 -30.08376)
		(end 141.938502 -30.061154)
		(stroke
			(width 0.06223)
			(type default)
		)
		(layer "F.Cu")
	)
	(gr_line
		(start 141.994636 -55.03672)
		(end 142.021814 -55.019194)
		(stroke
			(width 0.06223)
			(type default)
		)
		(layer "F.Cu")
	)
	(gr_line
		(start 142.021814 -55.019194)
		(end 142.052548 -55.012844)
		(stroke
			(width 0.06223)
			(type default)
		)
		(layer "F.Cu")
	)
	(gr_line
		(start 142.067026 -51.164236)
		(end 142.093442 -51.147218)
		(stroke
			(width 0.06223)
			(type default)
		)
		(layer "F.Cu")
	)
	(gr_line
		(start 142.069312 -62.445138)
		(end 142.07236 -62.448186)
		(stroke
			(width 0.06223)
			(type default)
		)
		(layer "F.Cu")
	)
	(gr_line
		(start 142.069312 -61.867034)
		(end 142.07236 -61.863986)
		(stroke
			(width 0.06223)
			(type default)
		)
		(layer "F.Cu")
	)
	(gr_line
		(start 142.093442 -51.147218)
		(end 142.124176 -51.140614)
		(stroke
			(width 0.06223)
			(type default)
		)
		(layer "F.Cu")
	)
	(gr_line
		(start 142.246858 -36.07562)
		(end 142.450566 -35.762692)
		(stroke
			(width 0.06223)
			(type default)
		)
		(layer "F.Cu")
	)
	(gr_line
		(start 142.248128 -34.775394)
		(end 142.698216 -34.083244)
		(stroke
			(width 0.06223)
			(type default)
		)
		(layer "F.Cu")
	)
	(gr_line
		(start 142.263876 -64.37249)
		(end 142.26667 -64.375284)
		(stroke
			(width 0.06223)
			(type default)
		)
		(layer "F.Cu")
	)
	(gr_line
		(start 142.263876 -63.794132)
		(end 142.266924 -63.791084)
		(stroke
			(width 0.06223)
			(type default)
		)
		(layer "F.Cu")
	)
	(gr_line
		(start 142.26667 -64.375284)
		(end 142.498826 -64.375284)
		(stroke
			(width 0.06223)
			(type default)
		)
		(layer "F.Cu")
	)
	(gr_line
		(start 142.266924 -63.791084)
		(end 142.498826 -63.791084)
		(stroke
			(width 0.06223)
			(type default)
		)
		(layer "F.Cu")
	)
	(gr_line
		(start 142.295372 -60.522104)
		(end 142.29842 -60.525152)
		(stroke
			(width 0.06223)
			(type default)
		)
		(layer "F.Cu")
	)
	(gr_line
		(start 142.295372 -59.944)
		(end 142.29842 -59.940952)
		(stroke
			(width 0.06223)
			(type default)
		)
		(layer "F.Cu")
	)
	(gr_line
		(start 142.362936 -35.348926)
		(end 142.450566 -35.762692)
		(stroke
			(width 0.06223)
			(type default)
		)
		(layer "F.Cu")
	)
	(gr_line
		(start 142.399766 -42.302176)
		(end 143.090392 -41.853612)
		(stroke
			(width 0.06223)
			(type default)
		)
		(layer "F.Cu")
	)
	(gr_line
		(start 142.56893 -35.031934)
		(end 142.938246 -34.953702)
		(stroke
			(width 0.06223)
			(type default)
		)
		(layer "F.Cu")
	)
	(gr_line
		(start 142.586964 -42.66819)
		(end 142.95628 -42.746422)
		(stroke
			(width 0.06223)
			(type default)
		)
		(layer "F.Cu")
	)
	(gr_line
		(start 142.63116 -62.448186)
		(end 142.997428 -62.448186)
		(stroke
			(width 0.06223)
			(type default)
		)
		(layer "F.Cu")
	)
	(gr_line
		(start 142.63116 -61.863986)
		(end 142.997428 -61.863986)
		(stroke
			(width 0.06223)
			(type default)
		)
		(layer "F.Cu")
	)
	(gr_line
		(start 142.699232 -37.384482)
		(end 143.38935 -36.936426)
		(stroke
			(width 0.06223)
			(type default)
		)
		(layer "F.Cu")
	)
	(gr_line
		(start 142.710662 -58.302652)
		(end 142.71371 -58.3057)
		(stroke
			(width 0.06223)
			(type default)
		)
		(layer "F.Cu")
	)
	(gr_line
		(start 142.710662 -57.724548)
		(end 142.71371 -57.7215)
		(stroke
			(width 0.06223)
			(type default)
		)
		(layer "F.Cu")
	)
	(gr_line
		(start 142.787624 -39.839138)
		(end 143.47825 -39.390574)
		(stroke
			(width 0.06223)
			(type default)
		)
		(layer "F.Cu")
	)
	(gr_line
		(start 142.85722 -60.525152)
		(end 143.223488 -60.525152)
		(stroke
			(width 0.06223)
			(type default)
		)
		(layer "F.Cu")
	)
	(gr_line
		(start 142.85722 -59.940952)
		(end 143.223488 -59.940952)
		(stroke
			(width 0.06223)
			(type default)
		)
		(layer "F.Cu")
	)
	(gr_line
		(start 142.886938 -37.750242)
		(end 143.256 -37.828474)
		(stroke
			(width 0.06223)
			(type default)
		)
		(layer "F.Cu")
	)
	(gr_line
		(start 142.938246 -34.953702)
		(end 143.141954 -34.640774)
		(stroke
			(width 0.06223)
			(type default)
		)
		(layer "F.Cu")
	)
	(gr_line
		(start 142.948914 -33.697672)
		(end 143.398748 -33.006284)
		(stroke
			(width 0.06223)
			(type default)
		)
		(layer "F.Cu")
	)
	(gr_line
		(start 142.95628 -42.746422)
		(end 143.269208 -42.543222)
		(stroke
			(width 0.06223)
			(type default)
		)
		(layer "F.Cu")
	)
	(gr_line
		(start 142.975076 -40.205152)
		(end 143.344138 -40.283638)
		(stroke
			(width 0.06223)
			(type default)
		)
		(layer "F.Cu")
	)
	(gr_line
		(start 142.997428 -62.448186)
		(end 143.000476 -62.445138)
		(stroke
			(width 0.06223)
			(type default)
		)
		(layer "F.Cu")
	)
	(gr_line
		(start 142.997428 -61.863986)
		(end 143.000476 -61.867034)
		(stroke
			(width 0.06223)
			(type default)
		)
		(layer "F.Cu")
	)
	(gr_line
		(start 143.057626 -64.375284)
		(end 143.060674 -64.372236)
		(stroke
			(width 0.06223)
			(type default)
		)
		(layer "F.Cu")
	)
	(gr_line
		(start 143.057626 -63.791084)
		(end 143.060674 -63.794132)
		(stroke
			(width 0.06223)
			(type default)
		)
		(layer "F.Cu")
	)
	(gr_line
		(start 143.063722 -34.271458)
		(end 143.141954 -34.640774)
		(stroke
			(width 0.06223)
			(type default)
		)
		(layer "F.Cu")
	)
	(gr_line
		(start 143.223488 -60.525152)
		(end 143.226536 -60.522104)
		(stroke
			(width 0.06223)
			(type default)
		)
		(layer "F.Cu")
	)
	(gr_line
		(start 143.223488 -59.940952)
		(end 143.226536 -59.944)
		(stroke
			(width 0.06223)
			(type default)
		)
		(layer "F.Cu")
	)
	(gr_line
		(start 143.256 -37.828474)
		(end 143.569182 -37.625274)
		(stroke
			(width 0.06223)
			(type default)
		)
		(layer "F.Cu")
	)
	(gr_line
		(start 143.269208 -42.543222)
		(end 143.347694 -42.173906)
		(stroke
			(width 0.06223)
			(type default)
		)
		(layer "F.Cu")
	)
	(gr_line
		(start 143.269716 -33.954466)
		(end 143.639032 -33.876234)
		(stroke
			(width 0.06223)
			(type default)
		)
		(layer "F.Cu")
	)
	(gr_line
		(start 143.27251 -58.3057)
		(end 143.638778 -58.3057)
		(stroke
			(width 0.06223)
			(type default)
		)
		(layer "F.Cu")
	)
	(gr_line
		(start 143.27251 -57.7215)
		(end 143.638778 -57.7215)
		(stroke
			(width 0.06223)
			(type default)
		)
		(layer "F.Cu")
	)
	(gr_line
		(start 143.344138 -40.283638)
		(end 143.65732 -40.080184)
		(stroke
			(width 0.06223)
			(type default)
		)
		(layer "F.Cu")
	)
	(gr_line
		(start 143.47698 -41.602406)
		(end 144.16786 -41.153588)
		(stroke
			(width 0.06223)
			(type default)
		)
		(layer "F.Cu")
	)
	(gr_line
		(start 143.507206 -61.950346)
		(end 143.773906 -61.683646)
		(stroke
			(width 0.06223)
			(type default)
		)
		(layer "F.Cu")
	)
	(gr_line
		(start 143.569182 -37.625274)
		(end 143.647668 -37.256212)
		(stroke
			(width 0.06223)
			(type default)
		)
		(layer "F.Cu")
	)
	(gr_line
		(start 143.638778 -58.3057)
		(end 143.641826 -58.302652)
		(stroke
			(width 0.06223)
			(type default)
		)
		(layer "F.Cu")
	)
	(gr_line
		(start 143.638778 -57.7215)
		(end 143.641826 -57.724548)
		(stroke
			(width 0.06223)
			(type default)
		)
		(layer "F.Cu")
	)
	(gr_line
		(start 143.639032 -33.876234)
		(end 143.84274 -33.563306)
		(stroke
			(width 0.06223)
			(type default)
		)
		(layer "F.Cu")
	)
	(gr_line
		(start 143.650208 -32.619696)
		(end 143.67383 -32.583374)
		(stroke
			(width 0.06223)
			(type default)
		)
		(layer "F.Cu")
	)
	(gr_line
		(start 143.65732 -40.080184)
		(end 143.735552 -39.710868)
		(stroke
			(width 0.06223)
			(type default)
		)
		(layer "F.Cu")
	)
	(gr_line
		(start 143.66494 -41.968166)
		(end 144.034002 -42.046652)
		(stroke
			(width 0.06223)
			(type default)
		)
		(layer "F.Cu")
	)
	(gr_line
		(start 143.67383 -32.583374)
		(end 143.710152 -32.560006)
		(stroke
			(width 0.06223)
			(type default)
		)
		(layer "F.Cu")
	)
	(gr_line
		(start 143.764508 -33.19399)
		(end 143.84274 -33.563306)
		(stroke
			(width 0.06223)
			(type default)
		)
		(layer "F.Cu")
	)
	(gr_line
		(start 143.773906 -61.683646)
		(end 144.147286 -61.683646)
		(stroke
			(width 0.06223)
			(type default)
		)
		(layer "F.Cu")
	)
	(gr_line
		(start 143.776954 -36.684458)
		(end 144.468342 -36.23564)
		(stroke
			(width 0.06223)
			(type default)
		)
		(layer "F.Cu")
	)
	(gr_line
		(start 143.805148 -44.199048)
		(end 143.831564 -44.18203)
		(stroke
			(width 0.06223)
			(type default)
		)
		(layer "F.Cu")
	)
	(gr_line
		(start 143.831564 -44.18203)
		(end 143.862298 -44.175426)
		(stroke
			(width 0.06223)
			(type default)
		)
		(layer "F.Cu")
	)
	(gr_line
		(start 143.857472 -54.629304)
		(end 144.659858 -54.458616)
		(stroke
			(width 0.06223)
			(type default)
		)
		(layer "F.Cu")
	)
	(gr_line
		(start 143.864584 -39.139622)
		(end 144.555972 -38.690296)
		(stroke
			(width 0.06223)
			(type default)
		)
		(layer "F.Cu")
	)
	(gr_line
		(start 143.89989 -55.03799)
		(end 144.216374 -55.24373)
		(stroke
			(width 0.06223)
			(type default)
		)
		(layer "F.Cu")
	)
	(gr_line
		(start 143.913606 -62.359286)
		(end 144.007586 -62.359286)
		(stroke
			(width 0.06223)
			(type default)
		)
		(layer "F.Cu")
	)
	(gr_line
		(start 143.95831 -32.399224)
		(end 143.98498 -32.381952)
		(stroke
			(width 0.06223)
			(type default)
		)
		(layer "F.Cu")
	)
	(gr_line
		(start 143.964914 -37.050218)
		(end 144.333976 -37.12845)
		(stroke
			(width 0.06223)
			(type default)
		)
		(layer "F.Cu")
	)
	(gr_line
		(start 143.96974 -46.576234)
		(end 143.996156 -46.559216)
		(stroke
			(width 0.06223)
			(type default)
		)
		(layer "F.Cu")
	)
	(gr_line
		(start 143.98498 -32.381952)
		(end 144.015714 -32.375348)
		(stroke
			(width 0.06223)
			(type default)
		)
		(layer "F.Cu")
	)
	(gr_line
		(start 143.996156 -46.559216)
		(end 144.02689 -46.552612)
		(stroke
			(width 0.06223)
			(type default)
		)
		(layer "F.Cu")
	)
	(gr_line
		(start 144.034002 -42.046652)
		(end 144.347184 -41.843198)
		(stroke
			(width 0.06223)
			(type default)
		)
		(layer "F.Cu")
	)
	(gr_line
		(start 144.052544 -39.505128)
		(end 144.42186 -39.58336)
		(stroke
			(width 0.06223)
			(type default)
		)
		(layer "F.Cu")
	)
	(gr_line
		(start 144.147286 -61.683646)
		(end 144.413986 -61.950346)
		(stroke
			(width 0.06223)
			(type default)
		)
		(layer "F.Cu")
	)
	(gr_line
		(start 144.216374 -55.24373)
		(end 144.581626 -55.166006)
		(stroke
			(width 0.06223)
			(type default)
		)
		(layer "F.Cu")
	)
	(gr_line
		(start 144.297908 -64.290448)
		(end 144.311116 -64.27724)
		(stroke
			(width 0.06223)
			(type default)
		)
		(layer "F.Cu")
	)
	(gr_line
		(start 144.333976 -37.12845)
		(end 144.647158 -36.92525)
		(stroke
			(width 0.06223)
			(type default)
		)
		(layer "F.Cu")
	)
	(gr_line
		(start 144.347184 -41.843198)
		(end 144.42567 -41.473882)
		(stroke
			(width 0.06223)
			(type default)
		)
		(layer "F.Cu")
	)
	(gr_line
		(start 144.360646 -32.301688)
		(end 144.40154 -32.293052)
		(stroke
			(width 0.06223)
			(type default)
		)
		(layer "F.Cu")
	)
	(gr_line
		(start 144.364202 -60.027312)
		(end 144.630902 -59.760612)
		(stroke
			(width 0.06223)
			(type default)
		)
		(layer "F.Cu")
	)
	(gr_line
		(start 144.40154 -32.293052)
		(end 144.441418 -32.301434)
		(stroke
			(width 0.06223)
			(type default)
		)
		(layer "F.Cu")
	)
	(gr_line
		(start 144.42186 -39.58336)
		(end 144.735042 -39.379906)
		(stroke
			(width 0.06223)
			(type default)
		)
		(layer "F.Cu")
	)
	(gr_line
		(start 144.550384 -32.742632)
		(end 144.617694 -32.845248)
		(stroke
			(width 0.06223)
			(type default)
		)
		(layer "F.Cu")
	)
	(gr_line
		(start 144.561306 -63.803276)
		(end 144.766538 -63.487046)
		(stroke
			(width 0.06223)
			(type default)
		)
		(layer "F.Cu")
	)
	(gr_line
		(start 144.581626 -55.166006)
		(end 144.787112 -54.849522)
		(stroke
			(width 0.06223)
			(type default)
		)
		(layer "F.Cu")
	)
	(gr_line
		(start 144.617694 -32.845248)
		(end 144.975834 -32.921448)
		(stroke
			(width 0.06223)
			(type default)
		)
		(layer "F.Cu")
	)
	(gr_line
		(start 144.630902 -59.760612)
		(end 145.004282 -59.760612)
		(stroke
			(width 0.06223)
			(type default)
		)
		(layer "F.Cu")
	)
	(gr_line
		(start 144.636236 -32.34055)
		(end 144.739106 -32.273748)
		(stroke
			(width 0.06223)
			(type default)
		)
		(layer "F.Cu")
	)
	(gr_line
		(start 144.647158 -36.92525)
		(end 144.725644 -36.556188)
		(stroke
			(width 0.06223)
			(type default)
		)
		(layer "F.Cu")
	)
	(gr_line
		(start 144.687544 -64.19469)
		(end 145.492216 -64.023494)
		(stroke
			(width 0.06223)
			(type default)
		)
		(layer "F.Cu")
	)
	(gr_line
		(start 144.735042 -39.379906)
		(end 144.813274 -39.010844)
		(stroke
			(width 0.06223)
			(type default)
		)
		(layer "F.Cu")
	)
	(gr_line
		(start 144.739106 -32.273748)
		(end 145.097246 -32.349948)
		(stroke
			(width 0.06223)
			(type default)
		)
		(layer "F.Cu")
	)
	(gr_line
		(start 144.766538 -63.487046)
		(end 145.13179 -63.409322)
		(stroke
			(width 0.06223)
			(type default)
		)
		(layer "F.Cu")
	)
	(gr_line
		(start 144.770602 -60.436252)
		(end 144.864582 -60.436252)
		(stroke
			(width 0.06223)
			(type default)
		)
		(layer "F.Cu")
	)
	(gr_line
		(start 144.85493 -35.984434)
		(end 145.546318 -35.535616)
		(stroke
			(width 0.06223)
			(type default)
		)
		(layer "F.Cu")
	)
	(gr_line
		(start 144.964404 -38.425374)
		(end 144.990058 -38.40861)
		(stroke
			(width 0.06223)
			(type default)
		)
		(layer "F.Cu")
	)
	(gr_line
		(start 144.990058 -38.40861)
		(end 145.020792 -38.402006)
		(stroke
			(width 0.06223)
			(type default)
		)
		(layer "F.Cu")
	)
	(gr_line
		(start 145.004282 -59.760612)
		(end 145.270982 -60.027312)
		(stroke
			(width 0.06223)
			(type default)
		)
		(layer "F.Cu")
	)
	(gr_line
		(start 145.04289 -36.350194)
		(end 145.411952 -36.428426)
		(stroke
			(width 0.06223)
			(type default)
		)
		(layer "F.Cu")
	)
	(gr_line
		(start 145.11528 -54.361842)
		(end 145.917666 -54.191154)
		(stroke
			(width 0.06223)
			(type default)
		)
		(layer "F.Cu")
	)
	(gr_line
		(start 145.13179 -63.409322)
		(end 145.448274 -63.614808)
		(stroke
			(width 0.06223)
			(type default)
		)
		(layer "F.Cu")
	)
	(gr_line
		(start 145.138902 -46.316138)
		(end 145.179796 -46.307502)
		(stroke
			(width 0.06223)
			(type default)
		)
		(layer "F.Cu")
	)
	(gr_line
		(start 145.15719 -54.771036)
		(end 145.47342 -54.976522)
		(stroke
			(width 0.06223)
			(type default)
		)
		(layer "F.Cu")
	)
	(gr_line
		(start 145.179796 -46.307502)
		(end 145.219928 -46.316138)
		(stroke
			(width 0.06223)
			(type default)
		)
		(layer "F.Cu")
	)
	(gr_line
		(start 145.3261 -62.359286)
		(end 145.332196 -62.357762)
		(stroke
			(width 0.06223)
			(type default)
		)
		(layer "F.Cu")
	)
	(gr_line
		(start 145.411952 -36.428426)
		(end 145.725134 -36.225226)
		(stroke
			(width 0.06223)
			(type default)
		)
		(layer "F.Cu")
	)
	(gr_line
		(start 145.47342 -54.976522)
		(end 145.838672 -54.898798)
		(stroke
			(width 0.06223)
			(type default)
		)
		(layer "F.Cu")
	)
	(gr_line
		(start 145.522442 -33.03778)
		(end 145.735802 -33.085532)
		(stroke
			(width 0.06223)
			(type default)
		)
		(layer "F.Cu")
	)
	(gr_line
		(start 145.549874 -46.801024)
		(end 145.614898 -46.9011)
		(stroke
			(width 0.06223)
			(type default)
		)
		(layer "F.Cu")
	)
	(gr_line
		(start 145.616422 -46.903132)
		(end 145.618454 -46.906434)
		(stroke
			(width 0.06223)
			(type default)
		)
		(layer "F.Cu")
	)
	(gr_line
		(start 145.618454 -46.906434)
		(end 145.976594 -46.982634)
		(stroke
			(width 0.06223)
			(type default)
		)
		(layer "F.Cu")
	)
	(gr_line
		(start 145.623788 -40.2082)
		(end 145.649188 -40.19169)
		(stroke
			(width 0.06223)
			(type default)
		)
		(layer "F.Cu")
	)
	(gr_line
		(start 145.634456 -46.403514)
		(end 145.734024 -46.338744)
		(stroke
			(width 0.06223)
			(type default)
		)
		(layer "F.Cu")
	)
	(gr_line
		(start 145.643854 -32.46628)
		(end 145.890996 -32.513778)
		(stroke
			(width 0.06223)
			(type default)
		)
		(layer "F.Cu")
	)
	(gr_line
		(start 145.649188 -40.19169)
		(end 145.678652 -40.185594)
		(stroke
			(width 0.06223)
			(type default)
		)
		(layer "F.Cu")
	)
	(gr_line
		(start 145.718276 -23.156164)
		(end 145.744438 -23.139146)
		(stroke
			(width 0.06223)
			(type default)
		)
		(layer "F.Cu")
	)
	(gr_line
		(start 145.722848 -43.779948)
		(end 145.763488 -43.771312)
		(stroke
			(width 0.06223)
			(type default)
		)
		(layer "F.Cu")
	)
	(gr_line
		(start 145.725134 -36.225226)
		(end 145.80362 -35.856164)
		(stroke
			(width 0.06223)
			(type default)
		)
		(layer "F.Cu")
	)
	(gr_line
		(start 145.735802 -33.085532)
		(end 145.884138 -33.0073)
		(stroke
			(width 0.06223)
			(type default)
		)
		(layer "F.Cu")
	)
	(gr_line
		(start 145.736056 -46.337474)
		(end 145.739866 -46.334934)
		(stroke
			(width 0.06223)
			(type default)
		)
		(layer "F.Cu")
	)
	(gr_line
		(start 145.739866 -46.334934)
		(end 146.098006 -46.411388)
		(stroke
			(width 0.06223)
			(type default)
		)
		(layer "F.Cu")
	)
	(gr_line
		(start 145.744438 -23.139146)
		(end 145.775172 -23.132542)
		(stroke
			(width 0.06223)
			(type default)
		)
		(layer "F.Cu")
	)
	(gr_line
		(start 145.763488 -43.771312)
		(end 145.804128 -43.779948)
		(stroke
			(width 0.06223)
			(type default)
		)
		(layer "F.Cu")
	)
	(gr_line
		(start 145.804128 -60.436252)
		(end 145.807176 -60.43549)
		(stroke
			(width 0.06223)
			(type default)
		)
		(layer "F.Cu")
	)
	(gr_line
		(start 145.818098 -63.536068)
		(end 146.023584 -63.219584)
		(stroke
			(width 0.06223)
			(type default)
		)
		(layer "F.Cu")
	)
	(gr_line
		(start 145.838672 -54.898798)
		(end 146.044158 -54.582314)
		(stroke
			(width 0.06223)
			(type default)
		)
		(layer "F.Cu")
	)
	(gr_line
		(start 145.890996 -32.513778)
		(end 145.962878 -32.603694)
		(stroke
			(width 0.06223)
			(type default)
		)
		(layer "F.Cu")
	)
	(gr_line
		(start 145.934938 -35.283394)
		(end 145.959576 -35.267392)
		(stroke
			(width 0.06223)
			(type default)
		)
		(layer "F.Cu")
	)
	(gr_line
		(start 145.944082 -63.927228)
		(end 146.74977 -63.756032)
		(stroke
			(width 0.06223)
			(type default)
		)
		(layer "F.Cu")
	)
	(gr_line
		(start 145.959576 -35.267392)
		(end 145.989294 -35.261042)
		(stroke
			(width 0.06223)
			(type default)
		)
		(layer "F.Cu")
	)
	(gr_line
		(start 146.023584 -63.219584)
		(end 146.388836 -63.14186)
		(stroke
			(width 0.06223)
			(type default)
		)
		(layer "F.Cu")
	)
	(gr_line
		(start 146.033744 -35.251644)
		(end 146.033998 -35.251644)
		(stroke
			(width 0.06223)
			(type default)
		)
		(layer "F.Cu")
	)
	(gr_line
		(start 146.117564 -35.649408)
		(end 146.118072 -35.649408)
		(stroke
			(width 0.06223)
			(type default)
		)
		(layer "F.Cu")
	)
	(gr_line
		(start 146.144488 -50.28565)
		(end 146.185128 -50.277014)
		(stroke
			(width 0.06223)
			(type default)
		)
		(layer "F.Cu")
	)
	(gr_line
		(start 146.185128 -50.277014)
		(end 146.225768 -50.28565)
		(stroke
			(width 0.06223)
			(type default)
		)
		(layer "F.Cu")
	)
	(gr_line
		(start 146.21256 -24.305768)
		(end 146.238976 -24.28875)
		(stroke
			(width 0.06223)
			(type default)
		)
		(layer "F.Cu")
	)
	(gr_line
		(start 146.238976 -24.28875)
		(end 146.26971 -24.282146)
		(stroke
			(width 0.06223)
			(type default)
		)
		(layer "F.Cu")
	)
	(gr_line
		(start 146.286728 -33.472882)
		(end 146.342354 -33.221676)
		(stroke
			(width 0.06223)
			(type default)
		)
		(layer "F.Cu")
	)
	(gr_arc
		(start 146.297396 -32.674814)
		(mid 146.394152 -32.666395)
		(end 146.47037 -32.606234)
		(stroke
			(width 0.06223)
			(type default)
		)
		(layer "F.Cu")
	)
	(gr_arc
		(start 146.342354 -33.221676)
		(mid 146.329512 -33.132783)
		(end 146.255994 -33.081214)
		(stroke
			(width 0.06223)
			(type default)
		)
		(layer "F.Cu")
	)
	(gr_line
		(start 146.388836 -63.14186)
		(end 146.70532 -63.347346)
		(stroke
			(width 0.06223)
			(type default)
		)
		(layer "F.Cu")
	)
	(gr_line
		(start 146.401282 -40.032178)
		(end 146.440398 -40.023796)
		(stroke
			(width 0.06223)
			(type default)
		)
		(layer "F.Cu")
	)
	(gr_line
		(start 146.403822 -54.087522)
		(end 146.44624 -54.078378)
		(stroke
			(width 0.06223)
			(type default)
		)
		(layer "F.Cu")
	)
	(gr_line
		(start 146.440398 -40.023796)
		(end 146.48053 -40.031924)
		(stroke
			(width 0.06223)
			(type default)
		)
		(layer "F.Cu")
	)
	(gr_line
		(start 146.44624 -54.078378)
		(end 146.48815 -54.087268)
		(stroke
			(width 0.06223)
			(type default)
		)
		(layer "F.Cu")
	)
	(gr_line
		(start 146.47037 -32.606234)
		(end 146.524472 -32.354774)
		(stroke
			(width 0.06223)
			(type default)
		)
		(layer "F.Cu")
	)
	(gr_line
		(start 146.523202 -47.098966)
		(end 146.736816 -47.146972)
		(stroke
			(width 0.06223)
			(type default)
		)
		(layer "F.Cu")
	)
	(gr_line
		(start 146.60753 -50.785014)
		(end 146.685762 -50.904902)
		(stroke
			(width 0.06223)
			(type default)
		)
		(layer "F.Cu")
	)
	(gr_line
		(start 146.644614 -46.52772)
		(end 146.891756 -46.575218)
		(stroke
			(width 0.06223)
			(type default)
		)
		(layer "F.Cu")
	)
	(gr_line
		(start 146.685762 -50.904902)
		(end 147.043902 -50.981102)
		(stroke
			(width 0.06223)
			(type default)
		)
		(layer "F.Cu")
	)
	(gr_line
		(start 146.699224 -25.459944)
		(end 146.725386 -25.442926)
		(stroke
			(width 0.06223)
			(type default)
		)
		(layer "F.Cu")
	)
	(gr_line
		(start 146.72056 -50.38979)
		(end 146.807174 -50.333402)
		(stroke
			(width 0.06223)
			(type default)
		)
		(layer "F.Cu")
	)
	(gr_line
		(start 146.725386 -25.442926)
		(end 146.75612 -25.436322)
		(stroke
			(width 0.06223)
			(type default)
		)
		(layer "F.Cu")
	)
	(gr_line
		(start 146.736816 -47.146972)
		(end 146.902932 -47.098458)
		(stroke
			(width 0.06223)
			(type default)
		)
		(layer "F.Cu")
	)
	(gr_line
		(start 146.807174 -50.333402)
		(end 147.165314 -50.409856)
		(stroke
			(width 0.06223)
			(type default)
		)
		(layer "F.Cu")
	)
	(gr_line
		(start 146.814794 -40.51681)
		(end 146.929856 -40.693594)
		(stroke
			(width 0.06223)
			(type default)
		)
		(layer "F.Cu")
	)
	(gr_line
		(start 146.891756 -46.575218)
		(end 146.983196 -46.695106)
		(stroke
			(width 0.06223)
			(type default)
		)
		(layer "F.Cu")
	)
	(gr_line
		(start 146.929856 -40.693594)
		(end 147.19681 -40.750744)
		(stroke
			(width 0.06223)
			(type default)
		)
		(layer "F.Cu")
	)
	(gr_line
		(start 146.93646 -40.124126)
		(end 147.000468 -40.13708)
		(stroke
			(width 0.06223)
			(type default)
		)
		(layer "F.Cu")
	)
	(gr_line
		(start 146.94027 -35.05962)
		(end 146.980148 -35.050984)
		(stroke
			(width 0.06223)
			(type default)
		)
		(layer "F.Cu")
	)
	(gr_line
		(start 146.980148 -35.050984)
		(end 147.020788 -35.05962)
		(stroke
			(width 0.06223)
			(type default)
		)
		(layer "F.Cu")
	)
	(gr_line
		(start 147.000468 -40.13708)
		(end 147.03044 -40.11803)
		(stroke
			(width 0.06223)
			(type default)
		)
		(layer "F.Cu")
	)
	(gr_line
		(start 147.03044 -40.11803)
		(end 147.318222 -40.179498)
		(stroke
			(width 0.06223)
			(type default)
		)
		(layer "F.Cu")
	)
	(gr_line
		(start 147.307046 -47.564294)
		(end 147.362672 -47.313088)
		(stroke
			(width 0.06223)
			(type default)
		)
		(layer "F.Cu")
	)
	(gr_arc
		(start 147.317714 -46.766226)
		(mid 147.414449 -46.757763)
		(end 147.490688 -46.697646)
		(stroke
			(width 0.06223)
			(type default)
		)
		(layer "F.Cu")
	)
	(gr_arc
		(start 147.362672 -47.313088)
		(mid 147.349836 -47.224184)
		(end 147.276312 -47.172626)
		(stroke
			(width 0.06223)
			(type default)
		)
		(layer "F.Cu")
	)
	(gr_line
		(start 147.41652 -35.559746)
		(end 147.43811 -35.59302)
		(stroke
			(width 0.06223)
			(type default)
		)
		(layer "F.Cu")
	)
	(gr_line
		(start 147.43811 -35.59302)
		(end 147.79625 -35.66922)
		(stroke
			(width 0.06223)
			(type default)
		)
		(layer "F.Cu")
	)
	(gr_line
		(start 147.464018 -35.151568)
		(end 147.638008 -35.038284)
		(stroke
			(width 0.06223)
			(type default)
		)
		(layer "F.Cu")
	)
	(gr_line
		(start 147.490688 -46.697646)
		(end 147.54479 -46.446186)
		(stroke
			(width 0.06223)
			(type default)
		)
		(layer "F.Cu")
	)
	(gr_line
		(start 147.59051 -51.097434)
		(end 147.804124 -51.14544)
		(stroke
			(width 0.06223)
			(type default)
		)
		(layer "F.Cu")
	)
	(gr_line
		(start 147.60575 -54.743096)
		(end 147.683728 -54.862984)
		(stroke
			(width 0.06223)
			(type default)
		)
		(layer "F.Cu")
	)
	(gr_line
		(start 147.638008 -35.038284)
		(end 147.917662 -35.097974)
		(stroke
			(width 0.06223)
			(type default)
		)
		(layer "F.Cu")
	)
	(gr_line
		(start 147.683728 -54.862984)
		(end 148.041868 -54.939184)
		(stroke
			(width 0.06223)
			(type default)
		)
		(layer "F.Cu")
	)
	(gr_line
		(start 147.711922 -50.526188)
		(end 147.959064 -50.573686)
		(stroke
			(width 0.06223)
			(type default)
		)
		(layer "F.Cu")
	)
	(gr_line
		(start 147.718272 -54.347872)
		(end 147.80514 -54.291484)
		(stroke
			(width 0.06223)
			(type default)
		)
		(layer "F.Cu")
	)
	(gr_line
		(start 147.743418 -40.867076)
		(end 148.087588 -40.940482)
		(stroke
			(width 0.06223)
			(type default)
		)
		(layer "F.Cu")
	)
	(gr_line
		(start 147.80387 -26.465276)
		(end 147.80641 -26.464006)
		(stroke
			(width 0.06223)
			(type default)
		)
		(layer "F.Cu")
	)
	(gr_line
		(start 147.804124 -51.14544)
		(end 147.952206 -51.067208)
		(stroke
			(width 0.06223)
			(type default)
		)
		(layer "F.Cu")
	)
	(gr_line
		(start 147.80514 -54.291484)
		(end 148.163534 -54.367938)
		(stroke
			(width 0.06223)
			(type default)
		)
		(layer "F.Cu")
	)
	(gr_line
		(start 147.80641 -26.464006)
		(end 147.809712 -26.463244)
		(stroke
			(width 0.06223)
			(type default)
		)
		(layer "F.Cu")
	)
	(gr_line
		(start 147.816316 -44.622974)
		(end 147.83435 -44.626784)
		(stroke
			(width 0.06223)
			(type default)
		)
		(layer "F.Cu")
	)
	(gr_line
		(start 147.83435 -44.626784)
		(end 147.878292 -44.694348)
		(stroke
			(width 0.06223)
			(type default)
		)
		(layer "F.Cu")
	)
	(gr_line
		(start 147.860004 -44.214288)
		(end 147.999704 -44.122848)
		(stroke
			(width 0.06223)
			(type default)
		)
		(layer "F.Cu")
	)
	(gr_line
		(start 147.86483 -40.29583)
		(end 148.220684 -40.371522)
		(stroke
			(width 0.06223)
			(type default)
		)
		(layer "F.Cu")
	)
	(gr_line
		(start 147.878292 -44.694348)
		(end 148.236432 -44.770548)
		(stroke
			(width 0.06223)
			(type default)
		)
		(layer "F.Cu")
	)
	(gr_line
		(start 147.959064 -50.573686)
		(end 148.030946 -50.663602)
		(stroke
			(width 0.06223)
			(type default)
		)
		(layer "F.Cu")
	)
	(gr_line
		(start 147.999704 -44.122848)
		(end 148.357844 -44.199048)
		(stroke
			(width 0.06223)
			(type default)
		)
		(layer "F.Cu")
	)
	(gr_line
		(start 148.087588 -40.940482)
		(end 148.190712 -40.873426)
		(stroke
			(width 0.06223)
			(type default)
		)
		(layer "F.Cu")
	)
	(gr_line
		(start 148.1582 -37.734494)
		(end 148.196046 -37.726366)
		(stroke
			(width 0.06223)
			(type default)
		)
		(layer "F.Cu")
	)
	(gr_line
		(start 148.196046 -37.726366)
		(end 148.235162 -37.733986)
		(stroke
			(width 0.06223)
			(type default)
		)
		(layer "F.Cu")
	)
	(gr_line
		(start 148.220684 -40.371522)
		(end 148.286978 -40.473884)
		(stroke
			(width 0.06223)
			(type default)
		)
		(layer "F.Cu")
	)
	(gr_line
		(start 148.342858 -35.785552)
		(end 148.599144 -35.838638)
		(stroke
			(width 0.06223)
			(type default)
		)
		(layer "F.Cu")
	)
	(gr_line
		(start 148.354796 -51.53279)
		(end 148.410422 -51.281584)
		(stroke
			(width 0.06223)
			(type default)
		)
		(layer "F.Cu")
	)
	(gr_arc
		(start 148.365464 -50.734722)
		(mid 148.46222 -50.726303)
		(end 148.538438 -50.666142)
		(stroke
			(width 0.06223)
			(type default)
		)
		(layer "F.Cu")
	)
	(gr_arc
		(start 148.410422 -51.281584)
		(mid 148.397584 -51.192692)
		(end 148.324062 -51.141122)
		(stroke
			(width 0.06223)
			(type default)
		)
		(layer "F.Cu")
	)
	(gr_line
		(start 148.46427 -35.214306)
		(end 148.698458 -35.26282)
		(stroke
			(width 0.06223)
			(type default)
		)
		(layer "F.Cu")
	)
	(gr_line
		(start 148.538438 -50.666142)
		(end 148.59254 -50.414682)
		(stroke
			(width 0.06223)
			(type default)
		)
		(layer "F.Cu")
	)
	(gr_line
		(start 148.588476 -55.055516)
		(end 148.805138 -55.103522)
		(stroke
			(width 0.06223)
			(type default)
		)
		(layer "F.Cu")
	)
	(gr_line
		(start 148.599144 -35.838638)
		(end 148.72589 -35.75558)
		(stroke
			(width 0.06223)
			(type default)
		)
		(layer "F.Cu")
	)
	(gr_line
		(start 148.62683 -41.353486)
		(end 148.682456 -41.10228)
		(stroke
			(width 0.06223)
			(type default)
		)
		(layer "F.Cu")
	)
	(gr_line
		(start 148.677884 -63.346076)
		(end 148.708618 -63.339472)
		(stroke
			(width 0.06223)
			(type default)
		)
		(layer "F.Cu")
	)
	(gr_arc
		(start 148.677884 -40.558974)
		(mid 148.757451 -40.547299)
		(end 148.810472 -40.486838)
		(stroke
			(width 0.06223)
			(type default)
		)
		(layer "F.Cu")
	)
	(gr_arc
		(start 148.682456 -41.10228)
		(mid 148.681273 -41.014481)
		(end 148.611844 -40.960802)
		(stroke
			(width 0.06223)
			(type default)
		)
		(layer "F.Cu")
	)
	(gr_line
		(start 148.698458 -35.26282)
		(end 148.750782 -35.342068)
		(stroke
			(width 0.06223)
			(type default)
		)
		(layer "F.Cu")
	)
	(gr_line
		(start 148.708618 -63.339472)
		(end 148.735034 -63.322454)
		(stroke
			(width 0.06223)
			(type default)
		)
		(layer "F.Cu")
	)
	(gr_line
		(start 148.710142 -54.48427)
		(end 148.92782 -54.526942)
		(stroke
			(width 0.06223)
			(type default)
		)
		(layer "F.Cu")
	)
	(gr_line
		(start 148.750782 -35.342068)
		(end 148.777452 -35.348164)
		(stroke
			(width 0.06223)
			(type default)
		)
		(layer "F.Cu")
	)
	(gr_line
		(start 148.78304 -44.88688)
		(end 149.042374 -44.940474)
		(stroke
			(width 0.06223)
			(type default)
		)
		(layer "F.Cu")
	)
	(gr_line
		(start 148.805138 -55.103522)
		(end 148.951696 -55.025798)
		(stroke
			(width 0.06223)
			(type default)
		)
		(layer "F.Cu")
	)
	(gr_line
		(start 148.810472 -40.486838)
		(end 148.864574 -40.235378)
		(stroke
			(width 0.06223)
			(type default)
		)
		(layer "F.Cu")
	)
	(gr_line
		(start 148.904452 -44.31538)
		(end 149.147022 -44.365418)
		(stroke
			(width 0.06223)
			(type default)
		)
		(layer "F.Cu")
	)
	(gr_line
		(start 148.92782 -54.526942)
		(end 148.999956 -54.61762)
		(stroke
			(width 0.06223)
			(type default)
		)
		(layer "F.Cu")
	)
	(gr_line
		(start 149.042374 -44.940474)
		(end 149.157436 -44.85894)
		(stroke
			(width 0.06223)
			(type default)
		)
		(layer "F.Cu")
	)
	(gr_line
		(start 149.092412 -57.889648)
		(end 149.12213 -57.883298)
		(stroke
			(width 0.06223)
			(type default)
		)
		(layer "F.Cu")
	)
	(gr_line
		(start 149.12213 -57.883298)
		(end 149.14753 -57.866788)
		(stroke
			(width 0.06223)
			(type default)
		)
		(layer "F.Cu")
	)
	(gr_line
		(start 149.124924 -61.377068)
		(end 149.145498 -61.371734)
		(stroke
			(width 0.06223)
			(type default)
		)
		(layer "F.Cu")
	)
	(gr_line
		(start 149.132036 -36.225988)
		(end 149.187662 -35.974782)
		(stroke
			(width 0.06223)
			(type default)
		)
		(layer "F.Cu")
	)
	(gr_line
		(start 149.142196 -38.330378)
		(end 149.208236 -38.432486)
		(stroke
			(width 0.06223)
			(type default)
		)
		(layer "F.Cu")
	)
	(gr_arc
		(start 149.142704 -35.42792)
		(mid 149.239442 -35.419461)
		(end 149.315678 -35.35934)
		(stroke
			(width 0.06223)
			(type default)
		)
		(layer "F.Cu")
	)
	(gr_line
		(start 149.145498 -61.371734)
		(end 149.162516 -61.360558)
		(stroke
			(width 0.06223)
			(type default)
		)
		(layer "F.Cu")
	)
	(gr_line
		(start 149.147022 -44.365418)
		(end 149.244304 -44.457112)
		(stroke
			(width 0.06223)
			(type default)
		)
		(layer "F.Cu")
	)
	(gr_arc
		(start 149.187662 -35.974782)
		(mid 149.174823 -35.885883)
		(end 149.101302 -35.83432)
		(stroke
			(width 0.06223)
			(type default)
		)
		(layer "F.Cu")
	)
	(gr_line
		(start 149.208236 -38.432486)
		(end 149.564344 -38.508432)
		(stroke
			(width 0.06223)
			(type default)
		)
		(layer "F.Cu")
	)
	(gr_line
		(start 149.220428 -59.65698)
		(end 149.251162 -59.650376)
		(stroke
			(width 0.06223)
			(type default)
		)
		(layer "F.Cu")
	)
	(gr_line
		(start 149.22754 -37.928042)
		(end 149.329902 -37.86124)
		(stroke
			(width 0.06223)
			(type default)
		)
		(layer "F.Cu")
	)
	(gr_line
		(start 149.251162 -59.650376)
		(end 149.277578 -59.633358)
		(stroke
			(width 0.06223)
			(type default)
		)
		(layer "F.Cu")
	)
	(gr_line
		(start 149.315678 -35.35934)
		(end 149.36978 -35.10788)
		(stroke
			(width 0.06223)
			(type default)
		)
		(layer "F.Cu")
	)
	(gr_line
		(start 149.329902 -37.86124)
		(end 149.685756 -37.937186)
		(stroke
			(width 0.06223)
			(type default)
		)
		(layer "F.Cu")
	)
	(gr_line
		(start 149.402546 -55.501286)
		(end 149.458172 -55.25008)
		(stroke
			(width 0.06223)
			(type default)
		)
		(layer "F.Cu")
	)
	(gr_arc
		(start 149.413214 -54.703218)
		(mid 149.509948 -54.694755)
		(end 149.586188 -54.634638)
		(stroke
			(width 0.06223)
			(type default)
		)
		(layer "F.Cu")
	)
	(gr_arc
		(start 149.458172 -55.25008)
		(mid 149.445403 -55.161123)
		(end 149.371812 -55.109618)
		(stroke
			(width 0.06223)
			(type default)
		)
		(layer "F.Cu")
	)
	(gr_line
		(start 149.54758 -45.321982)
		(end 149.603206 -45.070776)
		(stroke
			(width 0.06223)
			(type default)
		)
		(layer "F.Cu")
	)
	(gr_arc
		(start 149.558248 -44.523914)
		(mid 149.655004 -44.515495)
		(end 149.731222 -44.455334)
		(stroke
			(width 0.06223)
			(type default)
		)
		(layer "F.Cu")
	)
	(gr_line
		(start 149.586188 -54.634638)
		(end 149.64029 -54.383178)
		(stroke
			(width 0.06223)
			(type default)
		)
		(layer "F.Cu")
	)
	(gr_arc
		(start 149.603206 -45.070776)
		(mid 149.590363 -44.981892)
		(end 149.516846 -44.930314)
		(stroke
			(width 0.06223)
			(type default)
		)
		(layer "F.Cu")
	)
	(gr_line
		(start 149.731222 -44.455334)
		(end 149.785324 -44.203874)
		(stroke
			(width 0.06223)
			(type default)
		)
		(layer "F.Cu")
	)
	(gr_line
		(start 150.110952 -38.624764)
		(end 150.455122 -38.69817)
		(stroke
			(width 0.06223)
			(type default)
		)
		(layer "F.Cu")
	)
	(gr_line
		(start 150.232364 -38.053518)
		(end 150.588218 -38.12921)
		(stroke
			(width 0.06223)
			(type default)
		)
		(layer "F.Cu")
	)
	(gr_line
		(start 150.455122 -38.69817)
		(end 150.558246 -38.631114)
		(stroke
			(width 0.06223)
			(type default)
		)
		(layer "F.Cu")
	)
	(gr_line
		(start 150.509732 -56.982106)
		(end 150.54453 -56.9595)
		(stroke
			(width 0.06223)
			(type default)
		)
		(layer "F.Cu")
	)
	(gr_line
		(start 150.54453 -56.9595)
		(end 150.567136 -56.924702)
		(stroke
			(width 0.06223)
			(type default)
		)
		(layer "F.Cu")
	)
	(gr_line
		(start 150.588218 -38.12921)
		(end 150.654512 -38.231572)
		(stroke
			(width 0.06223)
			(type default)
		)
		(layer "F.Cu")
	)
	(gr_line
		(start 150.872952 -45.114464)
		(end 150.881588 -45.155104)
		(stroke
			(width 0.06223)
			(type default)
		)
		(layer "F.Cu")
	)
	(gr_line
		(start 150.872952 -45.114464)
		(end 150.881588 -45.07357)
		(stroke
			(width 0.06223)
			(type default)
		)
		(layer "F.Cu")
	)
	(gr_line
		(start 150.930356 -46.678596)
		(end 151.00808 -47.043848)
		(stroke
			(width 0.06223)
			(type default)
		)
		(layer "F.Cu")
	)
	(gr_line
		(start 150.930356 -46.678596)
		(end 151.135842 -46.362112)
		(stroke
			(width 0.06223)
			(type default)
		)
		(layer "F.Cu")
	)
	(gr_line
		(start 150.994364 -39.111174)
		(end 151.04999 -38.859968)
		(stroke
			(width 0.06223)
			(type default)
		)
		(layer "F.Cu")
	)
	(gr_line
		(start 151.00808 -47.043848)
		(end 151.324564 -47.249334)
		(stroke
			(width 0.06223)
			(type default)
		)
		(layer "F.Cu")
	)
	(gr_arc
		(start 151.045418 -38.316662)
		(mid 151.124966 -38.304969)
		(end 151.178006 -38.244526)
		(stroke
			(width 0.06223)
			(type default)
		)
		(layer "F.Cu")
	)
	(gr_arc
		(start 151.04999 -38.859968)
		(mid 151.048736 -38.772226)
		(end 150.979378 -38.71849)
		(stroke
			(width 0.06223)
			(type default)
		)
		(layer "F.Cu")
	)
	(gr_line
		(start 151.061674 -56.163464)
		(end 151.078692 -56.137048)
		(stroke
			(width 0.06223)
			(type default)
		)
		(layer "F.Cu")
	)
	(gr_line
		(start 151.078692 -56.137048)
		(end 151.085296 -56.106314)
		(stroke
			(width 0.06223)
			(type default)
		)
		(layer "F.Cu")
	)
	(gr_line
		(start 151.178006 -38.244526)
		(end 151.232108 -37.993066)
		(stroke
			(width 0.06223)
			(type default)
		)
		(layer "F.Cu")
	)
	(gr_line
		(start 151.197818 -47.935642)
		(end 151.275542 -48.300894)
		(stroke
			(width 0.06223)
			(type default)
		)
		(layer "F.Cu")
	)
	(gr_line
		(start 151.197818 -47.935642)
		(end 151.403304 -47.619158)
		(stroke
			(width 0.06223)
			(type default)
		)
		(layer "F.Cu")
	)
	(gr_line
		(start 151.219916 -42.187622)
		(end 151.297386 -41.82237)
		(stroke
			(width 0.06223)
			(type default)
		)
		(layer "F.Cu")
	)
	(gr_line
		(start 151.219916 -42.187622)
		(end 151.425402 -42.503852)
		(stroke
			(width 0.06223)
			(type default)
		)
		(layer "F.Cu")
	)
	(gr_line
		(start 151.275542 -48.300894)
		(end 151.592026 -48.50638)
		(stroke
			(width 0.06223)
			(type default)
		)
		(layer "F.Cu")
	)
	(gr_line
		(start 151.297386 -41.82237)
		(end 151.61387 -41.616884)
		(stroke
			(width 0.06223)
			(type default)
		)
		(layer "F.Cu")
	)
	(gr_line
		(start 151.353266 -58.284872)
		(end 151.388064 -58.262266)
		(stroke
			(width 0.06223)
			(type default)
		)
		(layer "F.Cu")
	)
	(gr_line
		(start 151.388064 -58.262266)
		(end 151.41067 -58.227468)
		(stroke
			(width 0.06223)
			(type default)
		)
		(layer "F.Cu")
	)
	(gr_line
		(start 151.48687 -40.930322)
		(end 151.564594 -40.565324)
		(stroke
			(width 0.06223)
			(type default)
		)
		(layer "F.Cu")
	)
	(gr_line
		(start 151.48687 -40.930322)
		(end 151.692356 -41.246806)
		(stroke
			(width 0.06223)
			(type default)
		)
		(layer "F.Cu")
	)
	(gr_line
		(start 151.50338 -25.677876)
		(end 151.543512 -25.66924)
		(stroke
			(width 0.06223)
			(type default)
		)
		(layer "F.Cu")
	)
	(gr_line
		(start 151.53767 -24.420322)
		(end 151.57831 -24.411686)
		(stroke
			(width 0.06223)
			(type default)
		)
		(layer "F.Cu")
	)
	(gr_line
		(start 151.543512 -25.66924)
		(end 151.583644 -25.677876)
		(stroke
			(width 0.06223)
			(type default)
		)
		(layer "F.Cu")
	)
	(gr_line
		(start 151.544528 -46.318678)
		(end 151.715216 -47.121826)
		(stroke
			(width 0.06223)
			(type default)
		)
		(layer "F.Cu")
	)
	(gr_line
		(start 151.55164 -21.90496)
		(end 151.59228 -21.896324)
		(stroke
			(width 0.06223)
			(type default)
		)
		(layer "F.Cu")
	)
	(gr_line
		(start 151.564594 -40.565324)
		(end 151.881078 -40.359584)
		(stroke
			(width 0.06223)
			(type default)
		)
		(layer "F.Cu")
	)
	(gr_line
		(start 151.56815 -23.155402)
		(end 151.608282 -23.146766)
		(stroke
			(width 0.06223)
			(type default)
		)
		(layer "F.Cu")
	)
	(gr_line
		(start 151.57831 -24.411686)
		(end 151.618442 -24.420322)
		(stroke
			(width 0.06223)
			(type default)
		)
		(layer "F.Cu")
	)
	(gr_line
		(start 151.59228 -21.896324)
		(end 151.63292 -21.90496)
		(stroke
			(width 0.06223)
			(type default)
		)
		(layer "F.Cu")
	)
	(gr_line
		(start 151.608282 -23.146766)
		(end 151.648922 -23.155402)
		(stroke
			(width 0.06223)
			(type default)
		)
		(layer "F.Cu")
	)
	(gr_line
		(start 151.81199 -47.576232)
		(end 151.982932 -48.378872)
		(stroke
			(width 0.06223)
			(type default)
		)
		(layer "F.Cu")
	)
	(gr_line
		(start 151.834342 -42.54627)
		(end 152.004776 -41.74363)
		(stroke
			(width 0.06223)
			(type default)
		)
		(layer "F.Cu")
	)
	(gr_line
		(start 152.03424 -59.496198)
		(end 152.069038 -59.473592)
		(stroke
			(width 0.06223)
			(type default)
		)
		(layer "F.Cu")
	)
	(gr_line
		(start 152.069038 -59.473592)
		(end 152.091644 -59.438794)
		(stroke
			(width 0.06223)
			(type default)
		)
		(layer "F.Cu")
	)
	(gr_line
		(start 152.069038 -39.486332)
		(end 152.075642 -39.455598)
		(stroke
			(width 0.06223)
			(type default)
		)
		(layer "F.Cu")
	)
	(gr_line
		(start 152.075642 -39.455598)
		(end 152.09266 -39.429182)
		(stroke
			(width 0.06223)
			(type default)
		)
		(layer "F.Cu")
	)
	(gr_line
		(start 152.101296 -41.291002)
		(end 152.272746 -40.484298)
		(stroke
			(width 0.06223)
			(type default)
		)
		(layer "F.Cu")
	)
	(gr_line
		(start 152.136094 -45.074332)
		(end 152.14473 -45.114464)
		(stroke
			(width 0.06223)
			(type default)
		)
		(layer "F.Cu")
	)
	(gr_line
		(start 152.136094 -45.074332)
		(end 152.14473 -45.033946)
		(stroke
			(width 0.06223)
			(type default)
		)
		(layer "F.Cu")
	)
	(gr_line
		(start 152.340564 -54.229762)
		(end 152.418034 -53.864764)
		(stroke
			(width 0.06223)
			(type default)
		)
		(layer "F.Cu")
	)
	(gr_line
		(start 152.340564 -54.229762)
		(end 152.54605 -54.5465)
		(stroke
			(width 0.06223)
			(type default)
		)
		(layer "F.Cu")
	)
	(gr_line
		(start 152.346914 -50.170588)
		(end 152.35555 -50.130456)
		(stroke
			(width 0.06223)
			(type default)
		)
		(layer "F.Cu")
	)
	(gr_line
		(start 152.346914 -50.090324)
		(end 152.35555 -50.130456)
		(stroke
			(width 0.06223)
			(type default)
		)
		(layer "F.Cu")
	)
	(gr_line
		(start 152.418034 -53.864764)
		(end 152.734518 -53.659024)
		(stroke
			(width 0.06223)
			(type default)
		)
		(layer "F.Cu")
	)
	(gr_line
		(start 152.539954 -56.488838)
		(end 152.556972 -56.462422)
		(stroke
			(width 0.06223)
			(type default)
		)
		(layer "F.Cu")
	)
	(gr_line
		(start 152.556972 -56.462422)
		(end 152.563576 -56.431688)
		(stroke
			(width 0.06223)
			(type default)
		)
		(layer "F.Cu")
	)
	(gr_line
		(start 152.607518 -52.972716)
		(end 152.685242 -52.607464)
		(stroke
			(width 0.06223)
			(type default)
		)
		(layer "F.Cu")
	)
	(gr_line
		(start 152.607518 -52.972716)
		(end 152.813004 -53.288946)
		(stroke
			(width 0.06223)
			(type default)
		)
		(layer "F.Cu")
	)
	(gr_line
		(start 152.651714 -25.905206)
		(end 152.682448 -25.91181)
		(stroke
			(width 0.06223)
			(type default)
		)
		(layer "F.Cu")
	)
	(gr_line
		(start 152.682448 -25.91181)
		(end 152.708864 -25.928828)
		(stroke
			(width 0.06223)
			(type default)
		)
		(layer "F.Cu")
	)
	(gr_line
		(start 152.685242 -52.607464)
		(end 153.001726 -52.401724)
		(stroke
			(width 0.06223)
			(type default)
		)
		(layer "F.Cu")
	)
	(gr_line
		(start 152.789636 -60.688982)
		(end 152.823926 -60.666884)
		(stroke
			(width 0.06223)
			(type default)
		)
		(layer "F.Cu")
	)
	(gr_line
		(start 152.823926 -60.666884)
		(end 152.846532 -60.632086)
		(stroke
			(width 0.06223)
			(type default)
		)
		(layer "F.Cu")
	)
	(gr_line
		(start 152.874726 -51.715416)
		(end 152.952196 -51.350164)
		(stroke
			(width 0.06223)
			(type default)
		)
		(layer "F.Cu")
	)
	(gr_line
		(start 152.874726 -51.715416)
		(end 153.080212 -52.032154)
		(stroke
			(width 0.06223)
			(type default)
		)
		(layer "F.Cu")
	)
	(gr_line
		(start 152.952196 -51.350164)
		(end 153.26868 -51.144678)
		(stroke
			(width 0.06223)
			(type default)
		)
		(layer "F.Cu")
	)
	(gr_line
		(start 152.954736 -54.590696)
		(end 153.126186 -53.783992)
		(stroke
			(width 0.06223)
			(type default)
		)
		(layer "F.Cu")
	)
	(gr_line
		(start 153.101548 -24.73579)
		(end 153.132282 -24.742394)
		(stroke
			(width 0.06223)
			(type default)
		)
		(layer "F.Cu")
	)
	(gr_line
		(start 153.132282 -24.742394)
		(end 153.158698 -24.759412)
		(stroke
			(width 0.06223)
			(type default)
		)
		(layer "F.Cu")
	)
	(gr_line
		(start 153.221944 -53.331618)
		(end 153.392124 -52.529994)
		(stroke
			(width 0.06223)
			(type default)
		)
		(layer "F.Cu")
	)
	(gr_line
		(start 153.23058 -39.932102)
		(end 153.237184 -39.901368)
		(stroke
			(width 0.06223)
			(type default)
		)
		(layer "F.Cu")
	)
	(gr_line
		(start 153.237184 -39.901368)
		(end 153.254202 -39.874952)
		(stroke
			(width 0.06223)
			(type default)
		)
		(layer "F.Cu")
	)
	(gr_line
		(start 153.401776 -45.04436)
		(end 153.410412 -45.085762)
		(stroke
			(width 0.06223)
			(type default)
		)
		(layer "F.Cu")
	)
	(gr_line
		(start 153.401776 -45.04436)
		(end 153.410412 -45.003466)
		(stroke
			(width 0.06223)
			(type default)
		)
		(layer "F.Cu")
	)
	(gr_line
		(start 153.489152 -52.074064)
		(end 153.659586 -51.271424)
		(stroke
			(width 0.06223)
			(type default)
		)
		(layer "F.Cu")
	)
	(gr_line
		(start 153.523188 -23.55342)
		(end 153.553922 -23.560024)
		(stroke
			(width 0.06223)
			(type default)
		)
		(layer "F.Cu")
	)
	(gr_line
		(start 153.553922 -23.560024)
		(end 153.580084 -23.577042)
		(stroke
			(width 0.06223)
			(type default)
		)
		(layer "F.Cu")
	)
	(gr_line
		(start 153.624788 -37.070538)
		(end 153.647394 -37.03574)
		(stroke
			(width 0.06223)
			(type default)
		)
		(layer "F.Cu")
	)
	(gr_line
		(start 153.647394 -37.03574)
		(end 153.682192 -37.013134)
		(stroke
			(width 0.06223)
			(type default)
		)
		(layer "F.Cu")
	)
	(gr_line
		(start 153.712164 -56.942736)
		(end 153.729182 -56.91632)
		(stroke
			(width 0.06223)
			(type default)
		)
		(layer "F.Cu")
	)
	(gr_line
		(start 153.729182 -56.91632)
		(end 153.735786 -56.885586)
		(stroke
			(width 0.06223)
			(type default)
		)
		(layer "F.Cu")
	)
	(gr_line
		(start 153.756106 -50.818288)
		(end 153.764742 -50.777648)
		(stroke
			(width 0.06223)
			(type default)
		)
		(layer "F.Cu")
	)
	(gr_line
		(start 153.756106 -50.737516)
		(end 153.764742 -50.777648)
		(stroke
			(width 0.06223)
			(type default)
		)
		(layer "F.Cu")
	)
	(gr_line
		(start 154.026362 -22.41296)
		(end 154.057096 -22.419564)
		(stroke
			(width 0.06223)
			(type default)
		)
		(layer "F.Cu")
	)
	(gr_line
		(start 154.057096 -22.419564)
		(end 154.083512 -22.436582)
		(stroke
			(width 0.06223)
			(type default)
		)
		(layer "F.Cu")
	)
	(gr_line
		(start 154.3939 -40.375586)
		(end 154.400504 -40.344852)
		(stroke
			(width 0.06223)
			(type default)
		)
		(layer "F.Cu")
	)
	(gr_line
		(start 154.400504 -40.344852)
		(end 154.417522 -40.318436)
		(stroke
			(width 0.06223)
			(type default)
		)
		(layer "F.Cu")
	)
	(gr_line
		(start 154.499564 -37.95776)
		(end 154.52217 -37.922962)
		(stroke
			(width 0.06223)
			(type default)
		)
		(layer "F.Cu")
	)
	(gr_line
		(start 154.52217 -37.922962)
		(end 154.556968 -37.900356)
		(stroke
			(width 0.06223)
			(type default)
		)
		(layer "F.Cu")
	)
	(gr_line
		(start 154.65171 -45.019722)
		(end 154.660346 -45.059854)
		(stroke
			(width 0.06223)
			(type default)
		)
		(layer "F.Cu")
	)
	(gr_line
		(start 154.65171 -45.019722)
		(end 154.660346 -44.97959)
		(stroke
			(width 0.06223)
			(type default)
		)
		(layer "F.Cu")
	)
	(gr_line
		(start 154.741118 -27.247596)
		(end 154.777694 -27.271472)
		(stroke
			(width 0.06223)
			(type default)
		)
		(layer "F.Cu")
	)
	(gr_line
		(start 154.777694 -27.271472)
		(end 154.800808 -27.307286)
		(stroke
			(width 0.06223)
			(type default)
		)
		(layer "F.Cu")
	)
	(gr_line
		(start 155.011628 -54.887622)
		(end 155.088844 -54.522116)
		(stroke
			(width 0.06223)
			(type default)
		)
		(layer "F.Cu")
	)
	(gr_line
		(start 155.011628 -54.887622)
		(end 155.217368 -55.203852)
		(stroke
			(width 0.06223)
			(type default)
		)
		(layer "F.Cu")
	)
	(gr_line
		(start 155.02636 -50.814224)
		(end 155.034996 -50.773584)
		(stroke
			(width 0.06223)
			(type default)
		)
		(layer "F.Cu")
	)
	(gr_line
		(start 155.02636 -50.73269)
		(end 155.034996 -50.773584)
		(stroke
			(width 0.06223)
			(type default)
		)
		(layer "F.Cu")
	)
	(gr_line
		(start 155.088844 -54.522116)
		(end 155.405074 -54.316376)
		(stroke
			(width 0.06223)
			(type default)
		)
		(layer "F.Cu")
	)
	(gr_line
		(start 155.262834 -56.910986)
		(end 155.279344 -56.885586)
		(stroke
			(width 0.06223)
			(type default)
		)
		(layer "F.Cu")
	)
	(gr_line
		(start 155.277566 -53.630068)
		(end 155.355036 -53.264816)
		(stroke
			(width 0.06223)
			(type default)
		)
		(layer "F.Cu")
	)
	(gr_line
		(start 155.277566 -53.630068)
		(end 155.483306 -53.946298)
		(stroke
			(width 0.06223)
			(type default)
		)
		(layer "F.Cu")
	)
	(gr_line
		(start 155.279344 -56.885586)
		(end 155.285694 -56.855868)
		(stroke
			(width 0.06223)
			(type default)
		)
		(layer "F.Cu")
	)
	(gr_line
		(start 155.322778 -38.924992)
		(end 155.345384 -38.890194)
		(stroke
			(width 0.06223)
			(type default)
		)
		(layer "F.Cu")
	)
	(gr_line
		(start 155.345384 -38.890194)
		(end 155.380182 -38.867588)
		(stroke
			(width 0.06223)
			(type default)
		)
		(layer "F.Cu")
	)
	(gr_line
		(start 155.355036 -53.264816)
		(end 155.671012 -53.05933)
		(stroke
			(width 0.06223)
			(type default)
		)
		(layer "F.Cu")
	)
	(gr_line
		(start 155.539186 -40.84701)
		(end 155.54579 -40.816276)
		(stroke
			(width 0.06223)
			(type default)
		)
		(layer "F.Cu")
	)
	(gr_line
		(start 155.54579 -40.816276)
		(end 155.562808 -40.790114)
		(stroke
			(width 0.06223)
			(type default)
		)
		(layer "F.Cu")
	)
	(gr_line
		(start 155.626054 -55.246778)
		(end 155.796234 -54.442868)
		(stroke
			(width 0.06223)
			(type default)
		)
		(layer "F.Cu")
	)
	(gr_line
		(start 155.8925 -53.988208)
		(end 156.062426 -53.185568)
		(stroke
			(width 0.06223)
			(type default)
		)
		(layer "F.Cu")
	)
	(gr_line
		(start 155.9306 -35.553142)
		(end 155.957016 -35.536124)
		(stroke
			(width 0.06223)
			(type default)
		)
		(layer "F.Cu")
	)
	(gr_line
		(start 155.957016 -35.536124)
		(end 155.98775 -35.52952)
		(stroke
			(width 0.06223)
			(type default)
		)
		(layer "F.Cu")
	)
	(gr_line
		(start 156.003752 -26.606754)
		(end 156.03855 -26.62936)
		(stroke
			(width 0.06223)
			(type default)
		)
		(layer "F.Cu")
	)
	(gr_line
		(start 156.03855 -26.62936)
		(end 156.061156 -26.664158)
		(stroke
			(width 0.06223)
			(type default)
		)
		(layer "F.Cu")
	)
	(gr_line
		(start 156.072332 -40.005762)
		(end 156.096208 -39.969186)
		(stroke
			(width 0.06223)
			(type default)
		)
		(layer "F.Cu")
	)
	(gr_line
		(start 156.096208 -39.969186)
		(end 156.132784 -39.94531)
		(stroke
			(width 0.06223)
			(type default)
		)
		(layer "F.Cu")
	)
	(gr_line
		(start 156.310584 -38.263322)
		(end 156.336746 -38.246304)
		(stroke
			(width 0.06223)
			(type default)
		)
		(layer "F.Cu")
	)
	(gr_line
		(start 156.336746 -38.246304)
		(end 156.36748 -38.2397)
		(stroke
			(width 0.06223)
			(type default)
		)
		(layer "F.Cu")
	)
	(gr_line
		(start 156.383482 -36.713922)
		(end 156.409898 -36.696904)
		(stroke
			(width 0.06223)
			(type default)
		)
		(layer "F.Cu")
	)
	(gr_line
		(start 156.409898 -36.696904)
		(end 156.440632 -36.6903)
		(stroke
			(width 0.06223)
			(type default)
		)
		(layer "F.Cu")
	)
	(gr_line
		(start 156.424122 -51.477926)
		(end 156.433266 -51.434746)
		(stroke
			(width 0.06223)
			(type default)
		)
		(layer "F.Cu")
	)
	(gr_line
		(start 156.424122 -51.392328)
		(end 156.433266 -51.434746)
		(stroke
			(width 0.06223)
			(type default)
		)
		(layer "F.Cu")
	)
	(gr_line
		(start 156.703522 -38.165786)
		(end 156.909008 -37.849048)
		(stroke
			(width 0.06223)
			(type default)
		)
		(layer "F.Cu")
	)
	(gr_line
		(start 156.781754 -39.524432)
		(end 156.807916 -39.507414)
		(stroke
			(width 0.06223)
			(type default)
		)
		(layer "F.Cu")
	)
	(gr_line
		(start 156.807916 -39.507414)
		(end 156.83865 -39.50081)
		(stroke
			(width 0.06223)
			(type default)
		)
		(layer "F.Cu")
	)
	(gr_line
		(start 156.829506 -38.556946)
		(end 157.635194 -38.385242)
		(stroke
			(width 0.06223)
			(type default)
		)
		(layer "F.Cu")
	)
	(gr_line
		(start 156.909008 -37.849048)
		(end 157.274006 -37.771324)
		(stroke
			(width 0.06223)
			(type default)
		)
		(layer "F.Cu")
	)
	(gr_line
		(start 157.130496 -31.640018)
		(end 157.15361 -31.675578)
		(stroke
			(width 0.06223)
			(type default)
		)
		(layer "F.Cu")
	)
	(gr_line
		(start 157.153356 -31.675832)
		(end 157.15361 -31.675578)
		(stroke
			(width 0.06223)
			(type default)
		)
		(layer "F.Cu")
	)
	(gr_line
		(start 157.153356 -31.675832)
		(end 157.191202 -31.70047)
		(stroke
			(width 0.06223)
			(type default)
		)
		(layer "F.Cu")
	)
	(gr_line
		(start 157.274006 -37.771324)
		(end 157.590744 -37.976556)
		(stroke
			(width 0.06223)
			(type default)
		)
		(layer "F.Cu")
	)
	(gr_line
		(start 157.475682 -25.124918)
		(end 158.167832 -25.574498)
		(stroke
			(width 0.06223)
			(type default)
		)
		(layer "F.Cu")
	)
	(gr_line
		(start 157.664912 -24.75992)
		(end 158.033974 -24.681688)
		(stroke
			(width 0.06223)
			(type default)
		)
		(layer "F.Cu")
	)
	(gr_line
		(start 157.733746 -26.276046)
		(end 157.770322 -26.299922)
		(stroke
			(width 0.06223)
			(type default)
		)
		(layer "F.Cu")
	)
	(gr_line
		(start 157.770322 -26.299922)
		(end 157.793944 -26.336498)
		(stroke
			(width 0.06223)
			(type default)
		)
		(layer "F.Cu")
	)
	(gr_line
		(start 157.938724 -30.301692)
		(end 157.96133 -30.33649)
		(stroke
			(width 0.06223)
			(type default)
		)
		(layer "F.Cu")
	)
	(gr_line
		(start 157.960568 -37.897816)
		(end 158.166054 -37.581078)
		(stroke
			(width 0.06223)
			(type default)
		)
		(layer "F.Cu")
	)
	(gr_line
		(start 157.96133 -30.33649)
		(end 157.996128 -30.359096)
		(stroke
			(width 0.06223)
			(type default)
		)
		(layer "F.Cu")
	)
	(gr_line
		(start 158.033974 -24.681688)
		(end 158.347156 -24.885142)
		(stroke
			(width 0.06223)
			(type default)
		)
		(layer "F.Cu")
	)
	(gr_line
		(start 158.08833 -38.288468)
		(end 158.89224 -38.117272)
		(stroke
			(width 0.06223)
			(type default)
		)
		(layer "F.Cu")
	)
	(gr_line
		(start 158.166054 -37.581078)
		(end 158.531052 -37.503354)
		(stroke
			(width 0.06223)
			(type default)
		)
		(layer "F.Cu")
	)
	(gr_line
		(start 158.347156 -24.885142)
		(end 158.425642 -25.254204)
		(stroke
			(width 0.06223)
			(type default)
		)
		(layer "F.Cu")
	)
	(gr_line
		(start 158.531052 -37.503354)
		(end 158.848044 -37.708586)
		(stroke
			(width 0.06223)
			(type default)
		)
		(layer "F.Cu")
	)
	(gr_line
		(start 159.08655 -32.931354)
		(end 159.11195 -32.947864)
		(stroke
			(width 0.06223)
			(type default)
		)
		(layer "F.Cu")
	)
	(gr_line
		(start 159.11195 -32.947864)
		(end 159.141668 -32.954214)
		(stroke
			(width 0.06223)
			(type default)
		)
		(layer "F.Cu")
	)
	(gr_line
		(start 159.155638 -25.731216)
		(end 159.190436 -25.753822)
		(stroke
			(width 0.06223)
			(type default)
		)
		(layer "F.Cu")
	)
	(gr_line
		(start 159.190436 -25.753822)
		(end 159.213042 -25.78862)
		(stroke
			(width 0.06223)
			(type default)
		)
		(layer "F.Cu")
	)
	(gr_line
		(start 159.217614 -37.629846)
		(end 159.4231 -37.313108)
		(stroke
			(width 0.06223)
			(type default)
		)
		(layer "F.Cu")
	)
	(gr_line
		(start 159.344868 -38.020752)
		(end 160.147762 -37.849556)
		(stroke
			(width 0.06223)
			(type default)
		)
		(layer "F.Cu")
	)
	(gr_line
		(start 159.4231 -37.313108)
		(end 159.788098 -37.235384)
		(stroke
			(width 0.06223)
			(type default)
		)
		(layer "F.Cu")
	)
	(gr_line
		(start 159.48787 -29.692092)
		(end 159.510476 -29.72689)
		(stroke
			(width 0.06223)
			(type default)
		)
		(layer "F.Cu")
	)
	(gr_line
		(start 159.510476 -29.72689)
		(end 159.545528 -29.74975)
		(stroke
			(width 0.06223)
			(type default)
		)
		(layer "F.Cu")
	)
	(gr_line
		(start 159.788098 -37.235384)
		(end 160.104582 -37.44087)
		(stroke
			(width 0.06223)
			(type default)
		)
		(layer "F.Cu")
	)
	(gr_line
		(start 160.571942 -28.627578)
		(end 160.594548 -28.662376)
		(stroke
			(width 0.06223)
			(type default)
		)
		(layer "F.Cu")
	)
	(gr_line
		(start 160.594548 -28.662376)
		(end 160.629346 -28.684982)
		(stroke
			(width 0.06223)
			(type default)
		)
		(layer "F.Cu")
	)
	(gr_line
		(start 160.94202 -36.148772)
		(end 160.972754 -36.142168)
		(stroke
			(width 0.06223)
			(type default)
		)
		(layer "F.Cu")
	)
	(gr_line
		(start 160.972754 -36.142168)
		(end 160.99917 -36.12515)
		(stroke
			(width 0.06223)
			(type default)
		)
		(layer "F.Cu")
	)
	(gr_line
		(start 161.21761 -32.451294)
		(end 161.24301 -32.467804)
		(stroke
			(width 0.06223)
			(type default)
		)
		(layer "F.Cu")
	)
	(gr_line
		(start 161.24301 -32.467804)
		(end 161.272728 -32.474154)
		(stroke
			(width 0.06223)
			(type default)
		)
		(layer "F.Cu")
	)
	(gr_line
		(start 161.451036 -35.346894)
		(end 161.514028 -35.306)
		(stroke
			(width 0.06223)
			(type default)
		)
		(layer "F.Cu")
	)
	(gr_line
		(start 161.728912 -31.166562)
		(end 161.79165 -31.207456)
		(stroke
			(width 0.06223)
			(type default)
		)
		(layer "F.Cu")
	)
	(gr_line
		(start 161.787332 -38.864794)
		(end 161.818066 -38.85819)
		(stroke
			(width 0.06223)
			(type default)
		)
		(layer "F.Cu")
	)
	(gr_line
		(start 161.818066 -38.85819)
		(end 161.844228 -38.841172)
		(stroke
			(width 0.06223)
			(type default)
		)
		(layer "F.Cu")
	)
	(gr_line
		(start 162.330384 -38.040818)
		(end 162.392868 -37.999924)
		(stroke
			(width 0.06223)
			(type default)
		)
		(layer "F.Cu")
	)
	(gr_line
		(start 162.405568 -23.427944)
		(end 162.418268 -23.440644)
		(stroke
			(width 0.072898)
			(type default)
		)
		(layer "F.Cu")
	)
	(gr_line
		(start 162.405568 -22.907244)
		(end 162.405568 -23.427944)
		(stroke
			(width 0.072898)
			(type default)
		)
		(layer "F.Cu")
	)
	(gr_line
		(start 162.405568 -21.594064)
		(end 162.405568 -22.018244)
		(stroke
			(width 0.072898)
			(type default)
		)
		(layer "F.Cu")
	)
	(gr_line
		(start 162.405568 -21.594064)
		(end 162.704526 -21.295106)
		(stroke
			(width 0.072898)
			(type default)
		)
		(layer "F.Cu")
	)
	(gr_line
		(start 162.418268 -23.935944)
		(end 162.704526 -24.222202)
		(stroke
			(width 0.072898)
			(type default)
		)
		(layer "F.Cu")
	)
	(gr_line
		(start 162.418268 -23.440644)
		(end 162.418268 -23.935944)
		(stroke
			(width 0.072898)
			(type default)
		)
		(layer "F.Cu")
	)
	(gr_line
		(start 163.14801 -24.222202)
		(end 163.434268 -23.935944)
		(stroke
			(width 0.072898)
			(type default)
		)
		(layer "F.Cu")
	)
	(gr_line
		(start 163.148264 -21.295106)
		(end 163.446968 -21.59381)
		(stroke
			(width 0.072898)
			(type default)
		)
		(layer "F.Cu")
	)
	(gr_line
		(start 163.215828 -30.364938)
		(end 163.283646 -30.409134)
		(stroke
			(width 0.06223)
			(type default)
		)
		(layer "F.Cu")
	)
	(gr_line
		(start 163.283646 -30.409134)
		(end 163.49345 -30.409134)
		(stroke
			(width 0.06223)
			(type default)
		)
		(layer "F.Cu")
	)
	(gr_line
		(start 163.302696 -34.800032)
		(end 163.399978 -34.800032)
		(stroke
			(width 0.06223)
			(type default)
		)
		(layer "F.Cu")
	)
	(gr_line
		(start 163.359338 -32.399986)
		(end 163.399978 -32.399986)
		(stroke
			(width 0.06223)
			(type default)
		)
		(layer "F.Cu")
	)
	(gr_line
		(start 163.367466 -37.999924)
		(end 163.399978 -37.999924)
		(stroke
			(width 0.06223)
			(type default)
		)
		(layer "F.Cu")
	)
	(gr_line
		(start 163.367974 -33.199832)
		(end 163.399978 -33.199832)
		(stroke
			(width 0.06223)
			(type default)
		)
		(layer "F.Cu")
	)
	(gr_line
		(start 163.37661 -30.801056)
		(end 163.398962 -30.801056)
		(stroke
			(width 0.06223)
			(type default)
		)
		(layer "F.Cu")
	)
	(gr_line
		(start 163.394136 -35.599878)
		(end 163.399978 -35.599878)
		(stroke
			(width 0.06223)
			(type default)
		)
		(layer "F.Cu")
	)
	(gr_line
		(start 163.395152 -29.996384)
		(end 163.399978 -29.999686)
		(stroke
			(width 0.06223)
			(type default)
		)
		(layer "F.Cu")
	)
	(gr_line
		(start 163.398962 -30.801056)
		(end 163.399978 -30.80004)
		(stroke
			(width 0.06223)
			(type default)
		)
		(layer "F.Cu")
	)
	(gr_line
		(start 163.399978 -29.999686)
		(end 163.399978 -29.99994)
		(stroke
			(width 0.06223)
			(type default)
		)
		(layer "F.Cu")
	)
	(gr_line
		(start 163.434268 -23.430992)
		(end 163.434268 -23.935944)
		(stroke
			(width 0.072898)
			(type default)
		)
		(layer "F.Cu")
	)
	(gr_line
		(start 163.434268 -23.430992)
		(end 163.446968 -23.418292)
		(stroke
			(width 0.072898)
			(type default)
		)
		(layer "F.Cu")
	)
	(gr_line
		(start 163.446968 -22.907244)
		(end 163.446968 -23.418292)
		(stroke
			(width 0.072898)
			(type default)
		)
		(layer "F.Cu")
	)
	(gr_line
		(start 163.446968 -21.59381)
		(end 163.446968 -22.018244)
		(stroke
			(width 0.072898)
			(type default)
		)
		(layer "F.Cu")
	)
	(gr_line
		(start 163.46424 -32.806386)
		(end 163.470844 -32.80283)
		(stroke
			(width 0.06223)
			(type default)
		)
		(layer "F.Cu")
	)
	(gr_line
		(start 163.473384 -38.406324)
		(end 163.484814 -38.399974)
		(stroke
			(width 0.06223)
			(type default)
		)
		(layer "F.Cu")
	)
	(gr_line
		(start 163.474146 -33.606232)
		(end 163.48583 -33.599628)
		(stroke
			(width 0.06223)
			(type default)
		)
		(layer "F.Cu")
	)
	(gr_line
		(start 163.477956 -32.798766)
		(end 163.696142 -32.67837)
		(stroke
			(width 0.06223)
			(type default)
		)
		(layer "F.Cu")
	)
	(gr_line
		(start 163.484052 -31.207456)
		(end 163.503356 -31.196534)
		(stroke
			(width 0.06223)
			(type default)
		)
		(layer "F.Cu")
	)
	(gr_line
		(start 163.492434 -38.395656)
		(end 163.688776 -38.285674)
		(stroke
			(width 0.06223)
			(type default)
		)
		(layer "F.Cu")
	)
	(gr_line
		(start 163.49345 -30.409134)
		(end 163.531296 -30.38729)
		(stroke
			(width 0.06223)
			(type default)
		)
		(layer "F.Cu")
	)
	(gr_line
		(start 163.493704 -33.59531)
		(end 163.688268 -33.486344)
		(stroke
			(width 0.06223)
			(type default)
		)
		(layer "F.Cu")
	)
	(gr_line
		(start 163.504118 -36.006278)
		(end 163.545774 -35.981894)
		(stroke
			(width 0.06223)
			(type default)
		)
		(layer "F.Cu")
	)
	(gr_line
		(start 163.512246 -31.191454)
		(end 163.676584 -31.097982)
		(stroke
			(width 0.06223)
			(type default)
		)
		(layer "F.Cu")
	)
	(gr_line
		(start 163.543488 -30.380178)
		(end 163.65855 -30.31363)
		(stroke
			(width 0.06223)
			(type default)
		)
		(layer "F.Cu")
	)
	(gr_line
		(start 163.561268 -35.973004)
		(end 163.64585 -35.923474)
		(stroke
			(width 0.06223)
			(type default)
		)
		(layer "F.Cu")
	)
	(gr_line
		(start 163.582858 -37.606224)
		(end 164.199824 -37.199824)
		(stroke
			(width 0.06223)
			(type default)
		)
		(layer "F.Cu")
	)
	(gr_line
		(start 163.66109 -35.914584)
		(end 164.199824 -35.599878)
		(stroke
			(width 0.06223)
			(type default)
		)
		(layer "F.Cu")
	)
	(gr_line
		(start 163.670742 -30.306518)
		(end 164.199824 -29.99994)
		(stroke
			(width 0.06223)
			(type default)
		)
		(layer "F.Cu")
	)
	(gr_line
		(start 163.685982 -31.092394)
		(end 164.199824 -30.80004)
		(stroke
			(width 0.06223)
			(type default)
		)
		(layer "F.Cu")
	)
	(gr_line
		(start 163.695888 -33.482026)
		(end 164.199824 -33.199832)
		(stroke
			(width 0.06223)
			(type default)
		)
		(layer "F.Cu")
	)
	(gr_line
		(start 163.69665 -38.281356)
		(end 164.199824 -37.999924)
		(stroke
			(width 0.06223)
			(type default)
		)
		(layer "F.Cu")
	)
	(gr_line
		(start 163.703254 -32.674306)
		(end 164.199824 -32.399986)
		(stroke
			(width 0.06223)
			(type default)
		)
		(layer "F.Cu")
	)
	(gr_line
		(start 163.733226 -35.037268)
		(end 164.199824 -34.800032)
		(stroke
			(width 0.06223)
			(type default)
		)
		(layer "F.Cu")
	)
	(gr_line
		(start 165.399974 -36.800028)
		(end 165.79977 -37.199824)
		(stroke
			(width 0.06223)
			(type default)
		)
		(layer "F.Cu")
	)
	(gr_line
		(start 165.399974 -34.399982)
		(end 165.800024 -34.800032)
		(stroke
			(width 0.06223)
			(type default)
		)
		(layer "F.Cu")
	)
	(gr_line
		(start 165.79977 -37.199824)
		(end 165.800024 -37.199824)
		(stroke
			(width 0.06223)
			(type default)
		)
		(layer "F.Cu")
	)
	(gr_line
		(start 165.800024 -38.000178)
		(end 166.19982 -38.399974)
		(stroke
			(width 0.06223)
			(type default)
		)
		(layer "F.Cu")
	)
	(gr_line
		(start 165.800024 -37.999924)
		(end 165.800024 -38.000178)
		(stroke
			(width 0.06223)
			(type default)
		)
		(layer "F.Cu")
	)
	(gr_line
		(start 165.800024 -35.600132)
		(end 166.19982 -35.999928)
		(stroke
			(width 0.06223)
			(type default)
		)
		(layer "F.Cu")
	)
	(gr_line
		(start 165.800024 -35.599878)
		(end 165.800024 -35.600132)
		(stroke
			(width 0.06223)
			(type default)
		)
		(layer "F.Cu")
	)
	(gr_line
		(start 165.800024 -33.200086)
		(end 166.19982 -33.599882)
		(stroke
			(width 0.06223)
			(type default)
		)
		(layer "F.Cu")
	)
	(gr_line
		(start 165.800024 -33.199832)
		(end 165.800024 -33.200086)
		(stroke
			(width 0.06223)
			(type default)
		)
		(layer "F.Cu")
	)
	(gr_line
		(start 165.800024 -32.399986)
		(end 166.200074 -31.999936)
		(stroke
			(width 0.06223)
			(type default)
		)
		(layer "F.Cu")
	)
	(gr_line
		(start 165.800024 -30.80004)
		(end 166.19982 -31.199836)
		(stroke
			(width 0.06223)
			(type default)
		)
		(layer "F.Cu")
	)
	(gr_line
		(start 165.800024 -29.999686)
		(end 165.800024 -29.99994)
		(stroke
			(width 0.06223)
			(type default)
		)
		(layer "F.Cu")
	)
	(gr_line
		(start 165.800024 -29.999686)
		(end 166.19982 -29.59989)
		(stroke
			(width 0.06223)
			(type default)
		)
		(layer "F.Cu")
	)
	(gr_arc
		(start 165.800024 -28.399994)
		(mid 165.972805 -28.32842)
		(end 166.044372 -28.155646)
		(stroke
			(width 0.072898)
			(type default)
		)
		(layer "F.Cu")
	)
	(gr_arc
		(start 165.836346 -23.455884)
		(mid 166.040737 -23.371223)
		(end 166.125398 -23.166832)
		(stroke
			(width 0.072898)
			(type default)
		)
		(layer "F.Cu")
	)
	(gr_arc
		(start 166.125398 -24.055832)
		(mid 166.040822 -23.8516)
		(end 165.8366 -23.767034)
		(stroke
			(width 0.072898)
			(type default)
		)
		(layer "F.Cu")
	)
	(gr_line
		(start 166.19982 -37.599874)
		(end 166.59987 -37.999924)
		(stroke
			(width 0.06223)
			(type default)
		)
		(layer "F.Cu")
	)
	(gr_line
		(start 166.19982 -36.800028)
		(end 166.599616 -37.199824)
		(stroke
			(width 0.06223)
			(type default)
		)
		(layer "F.Cu")
	)
	(gr_line
		(start 166.19982 -35.199828)
		(end 166.59987 -35.599878)
		(stroke
			(width 0.06223)
			(type default)
		)
		(layer "F.Cu")
	)
	(gr_line
		(start 166.19982 -34.399982)
		(end 166.59987 -34.800032)
		(stroke
			(width 0.06223)
			(type default)
		)
		(layer "F.Cu")
	)
	(gr_line
		(start 166.19982 -32.800036)
		(end 166.599616 -33.199832)
		(stroke
			(width 0.06223)
			(type default)
		)
		(layer "F.Cu")
	)
	(gr_line
		(start 166.19982 -30.39999)
		(end 166.59987 -30.80004)
		(stroke
			(width 0.06223)
			(type default)
		)
		(layer "F.Cu")
	)
	(gr_arc
		(start 166.355522 -28.155646)
		(mid 166.42709 -28.328426)
		(end 166.59987 -28.399994)
		(stroke
			(width 0.072898)
			(type default)
		)
		(layer "F.Cu")
	)
	(gr_line
		(start 166.599616 -37.199824)
		(end 166.59987 -37.199824)
		(stroke
			(width 0.06223)
			(type default)
		)
		(layer "F.Cu")
	)
	(gr_line
		(start 166.599616 -33.199832)
		(end 166.59987 -33.199832)
		(stroke
			(width 0.06223)
			(type default)
		)
		(layer "F.Cu")
	)
	(gr_line
		(start 166.59987 -32.399986)
		(end 166.99992 -31.999936)
		(stroke
			(width 0.06223)
			(type default)
		)
		(layer "F.Cu")
	)
	(gr_line
		(start 166.59987 -29.99994)
		(end 166.999666 -29.600144)
		(stroke
			(width 0.0508)
			(type default)
		)
		(layer "F.Cu")
	)
	(gr_line
		(start 167.799766 -30.39999)
		(end 168.199816 -30.80004)
		(stroke
			(width 0.072898)
			(type default)
		)
		(layer "F.Cu")
	)
	(gr_line
		(start 167.80002 -31.199836)
		(end 168.199816 -31.599632)
		(stroke
			(width 0.072898)
			(type default)
		)
		(layer "F.Cu")
	)
	(gr_arc
		(start 167.870886 -23.412958)
		(mid 168.075277 -23.328297)
		(end 168.159938 -23.123906)
		(stroke
			(width 0.072898)
			(type default)
		)
		(layer "F.Cu")
	)
	(gr_arc
		(start 168.159938 -24.012906)
		(mid 168.075356 -23.808677)
		(end 167.87114 -23.724108)
		(stroke
			(width 0.072898)
			(type default)
		)
		(layer "F.Cu")
	)
	(gr_line
		(start 168.199816 -31.599632)
		(end 168.199816 -31.599886)
		(stroke
			(width 0.072898)
			(type default)
		)
		(layer "F.Cu")
	)
	(gr_line
		(start 168.199816 -29.19984)
		(end 168.5798 -28.580588)
		(stroke
			(width 0.072898)
			(type default)
		)
		(layer "F.Cu")
	)
	(gr_line
		(start 168.199816 -28.332684)
		(end 168.199816 -28.399994)
		(stroke
			(width 0.072898)
			(type default)
		)
		(layer "F.Cu")
	)
	(gr_line
		(start 168.5798 -28.26893)
		(end 168.5798 -28.580588)
		(stroke
			(width 0.072898)
			(type default)
		)
		(layer "F.Cu")
	)
	(gr_line
		(start 168.599866 -31.199836)
		(end 168.999916 -31.599886)
		(stroke
			(width 0.072898)
			(type default)
		)
		(layer "F.Cu")
	)
	(gr_line
		(start 168.599866 -30.39999)
		(end 168.999916 -30.80004)
		(stroke
			(width 0.072898)
			(type default)
		)
		(layer "F.Cu")
	)
	(gr_line
		(start 168.999916 -29.19984)
		(end 169.352468 -28.847288)
		(stroke
			(width 0.072898)
			(type default)
		)
		(layer "F.Cu")
	)
	(gr_line
		(start 168.999916 -28.399994)
		(end 169.038778 -28.361132)
		(stroke
			(width 0.072898)
			(type default)
		)
		(layer "F.Cu")
	)
	(gr_line
		(start 169.352468 -28.672282)
		(end 169.352468 -28.847288)
		(stroke
			(width 0.072898)
			(type default)
		)
		(layer "F.Cu")
	)
	(gr_arc
		(start 169.928032 -23.404322)
		(mid 170.132423 -23.319661)
		(end 170.217084 -23.11527)
		(stroke
			(width 0.072898)
			(type default)
		)
		(layer "F.Cu")
	)
	(gr_line
		(start 170.199812 -30.39999)
		(end 170.599862 -30.80004)
		(stroke
			(width 0.072898)
			(type default)
		)
		(layer "F.Cu")
	)
	(gr_line
		(start 170.200066 -31.20009)
		(end 170.599862 -31.599886)
		(stroke
			(width 0.06985)
			(type default)
		)
		(layer "F.Cu")
	)
	(gr_arc
		(start 170.217084 -24.00427)
		(mid 170.132486 -23.800083)
		(end 169.928286 -23.715472)
		(stroke
			(width 0.072898)
			(type default)
		)
		(layer "F.Cu")
	)
	(gr_line
		(start 170.599862 -29.19984)
		(end 170.952414 -28.847288)
		(stroke
			(width 0.072898)
			(type default)
		)
		(layer "F.Cu")
	)
	(gr_line
		(start 170.599862 -28.399994)
		(end 170.638724 -28.361132)
		(stroke
			(width 0.072898)
			(type default)
		)
		(layer "F.Cu")
	)
	(gr_line
		(start 170.952414 -28.672282)
		(end 170.952414 -28.847288)
		(stroke
			(width 0.072898)
			(type default)
		)
		(layer "F.Cu")
	)
	(gr_line
		(start 170.999912 -30.39999)
		(end 171.399962 -30.80004)
		(stroke
			(width 0.072898)
			(type default)
		)
		(layer "F.Cu")
	)
	(gr_line
		(start 171.000166 -31.20009)
		(end 171.399962 -31.599886)
		(stroke
			(width 0.06985)
			(type default)
		)
		(layer "F.Cu")
	)
	(gr_line
		(start 171.399962 -29.19984)
		(end 171.752514 -28.847288)
		(stroke
			(width 0.072898)
			(type default)
		)
		(layer "F.Cu")
	)
	(gr_line
		(start 171.445428 -28.176474)
		(end 171.445428 -28.354528)
		(stroke
			(width 0.072898)
			(type default)
		)
		(layer "F.Cu")
	)
	(gr_line
		(start 171.720764 -14.578076)
		(end 171.802298 -14.496542)
		(stroke
			(width 0.072898)
			(type default)
		)
		(layer "F.Cu")
	)
	(gr_line
		(start 171.722542 -15.020036)
		(end 171.934378 -15.020036)
		(stroke
			(width 0.072898)
			(type default)
		)
		(layer "F.Cu")
	)
	(gr_line
		(start 171.752514 -28.668218)
		(end 171.752514 -28.847288)
		(stroke
			(width 0.072898)
			(type default)
		)
		(layer "F.Cu")
	)
	(gr_line
		(start 171.752514 -28.487624)
		(end 171.752514 -28.665678)
		(stroke
			(width 0.072898)
			(type default)
		)
		(layer "F.Cu")
	)
	(gr_line
		(start 171.934378 -15.020036)
		(end 172.244258 -14.710156)
		(stroke
			(width 0.072898)
			(type default)
		)
		(layer "F.Cu")
	)
	(gr_arc
		(start 171.980098 -23.402036)
		(mid 172.184489 -23.317375)
		(end 172.26915 -23.112984)
		(stroke
			(width 0.072898)
			(type default)
		)
		(layer "F.Cu")
	)
	(gr_line
		(start 172.244258 -14.49832)
		(end 172.244258 -14.710156)
		(stroke
			(width 0.072898)
			(type default)
		)
		(layer "F.Cu")
	)
	(gr_arc
		(start 172.26915 -24.001984)
		(mid 172.184554 -23.7978)
		(end 171.980352 -23.713186)
		(stroke
			(width 0.072898)
			(type default)
		)
		(layer "F.Cu")
	)
	(gr_line
		(start 172.555916 -13.742924)
		(end 172.63745 -13.66139)
		(stroke
			(width 0.072898)
			(type default)
		)
		(layer "F.Cu")
	)
	(gr_line
		(start 172.557694 -14.184884)
		(end 172.76953 -14.184884)
		(stroke
			(width 0.072898)
			(type default)
		)
		(layer "F.Cu")
	)
	(gr_line
		(start 172.599858 -30.39999)
		(end 172.999908 -30.80004)
		(stroke
			(width 0.072898)
			(type default)
		)
		(layer "F.Cu")
	)
	(gr_line
		(start 172.600112 -31.20009)
		(end 172.999908 -31.599886)
		(stroke
			(width 0.06985)
			(type default)
		)
		(layer "F.Cu")
	)
	(gr_line
		(start 172.76953 -14.184884)
		(end 173.07941 -13.875004)
		(stroke
			(width 0.072898)
			(type default)
		)
		(layer "F.Cu")
	)
	(gr_line
		(start 172.999908 -28.91409)
		(end 172.999908 -29.19984)
		(stroke
			(width 0.072898)
			(type default)
		)
		(layer "F.Cu")
	)
	(gr_line
		(start 172.999908 -28.91409)
		(end 173.35246 -28.561538)
		(stroke
			(width 0.072898)
			(type default)
		)
		(layer "F.Cu")
	)
	(gr_line
		(start 173.07941 -13.663168)
		(end 173.07941 -13.875004)
		(stroke
			(width 0.072898)
			(type default)
		)
		(layer "F.Cu")
	)
	(gr_line
		(start 173.162468 -25.867868)
		(end 173.162468 -25.887426)
		(stroke
			(width 0.072898)
			(type default)
		)
		(layer "F.Cu")
	)
	(gr_line
		(start 173.311058 -26.179018)
		(end 173.311058 -26.198576)
		(stroke
			(width 0.072898)
			(type default)
		)
		(layer "F.Cu")
	)
	(gr_line
		(start 173.313598 -28.18003)
		(end 173.35246 -28.218892)
		(stroke
			(width 0.072898)
			(type default)
		)
		(layer "F.Cu")
	)
	(gr_line
		(start 173.35246 -28.218892)
		(end 173.35246 -28.561538)
		(stroke
			(width 0.072898)
			(type default)
		)
		(layer "F.Cu")
	)
	(gr_line
		(start 173.391068 -12.907772)
		(end 173.472602 -12.826238)
		(stroke
			(width 0.072898)
			(type default)
		)
		(layer "F.Cu")
	)
	(gr_line
		(start 173.392846 -13.349732)
		(end 173.604682 -13.349732)
		(stroke
			(width 0.072898)
			(type default)
		)
		(layer "F.Cu")
	)
	(gr_line
		(start 173.399958 -30.39999)
		(end 173.800008 -30.80004)
		(stroke
			(width 0.072898)
			(type default)
		)
		(layer "F.Cu")
	)
	(gr_line
		(start 173.400212 -31.20009)
		(end 173.800008 -31.599886)
		(stroke
			(width 0.06985)
			(type default)
		)
		(layer "F.Cu")
	)
	(gr_line
		(start 173.604682 -13.349732)
		(end 173.914562 -13.039852)
		(stroke
			(width 0.072898)
			(type default)
		)
		(layer "F.Cu")
	)
	(gr_line
		(start 173.800008 -28.917392)
		(end 173.800008 -29.19984)
		(stroke
			(width 0.072898)
			(type default)
		)
		(layer "F.Cu")
	)
	(gr_line
		(start 173.800008 -28.917392)
		(end 174.15256 -28.56484)
		(stroke
			(width 0.072898)
			(type default)
		)
		(layer "F.Cu")
	)
	(gr_line
		(start 173.800008 -28.399994)
		(end 173.83887 -28.361132)
		(stroke
			(width 0.072898)
			(type default)
		)
		(layer "F.Cu")
	)
	(gr_line
		(start 173.914562 -12.828016)
		(end 173.914562 -13.039852)
		(stroke
			(width 0.072898)
			(type default)
		)
		(layer "F.Cu")
	)
	(gr_arc
		(start 174.025814 -23.401528)
		(mid 174.230205 -23.316867)
		(end 174.314866 -23.112476)
		(stroke
			(width 0.072898)
			(type default)
		)
		(layer "F.Cu")
	)
	(gr_line
		(start 174.22622 -12.07262)
		(end 174.307754 -11.991086)
		(stroke
			(width 0.072898)
			(type default)
		)
		(layer "F.Cu")
	)
	(gr_line
		(start 174.227998 -12.51458)
		(end 174.439834 -12.51458)
		(stroke
			(width 0.072898)
			(type default)
		)
		(layer "F.Cu")
	)
	(gr_arc
		(start 174.314866 -24.001476)
		(mid 174.230269 -23.797292)
		(end 174.026068 -23.712678)
		(stroke
			(width 0.072898)
			(type default)
		)
		(layer "F.Cu")
	)
	(gr_line
		(start 174.439834 -12.51458)
		(end 174.749714 -12.2047)
		(stroke
			(width 0.072898)
			(type default)
		)
		(layer "F.Cu")
	)
	(gr_line
		(start 174.749714 -11.992864)
		(end 174.749714 -12.2047)
		(stroke
			(width 0.072898)
			(type default)
		)
		(layer "F.Cu")
	)
	(gr_line
		(start 174.999904 -30.39999)
		(end 175.399954 -30.80004)
		(stroke
			(width 0.06985)
			(type default)
		)
		(layer "F.Cu")
	)
	(gr_line
		(start 175.000158 -31.20009)
		(end 175.399954 -31.599886)
		(stroke
			(width 0.06985)
			(type default)
		)
		(layer "F.Cu")
	)
	(gr_line
		(start 175.399954 -29.19984)
		(end 175.457358 -29.142436)
		(stroke
			(width 0.072898)
			(type default)
		)
		(layer "F.Cu")
	)
	(gr_line
		(start 175.399954 -28.399994)
		(end 175.49749 -28.302458)
		(stroke
			(width 0.072898)
			(type default)
		)
		(layer "F.Cu")
	)
	(gr_line
		(start 175.457358 -28.869894)
		(end 175.457358 -29.142436)
		(stroke
			(width 0.072898)
			(type default)
		)
		(layer "F.Cu")
	)
	(gr_line
		(start 175.457358 -28.869894)
		(end 175.81118 -28.516072)
		(stroke
			(width 0.072898)
			(type default)
		)
		(layer "F.Cu")
	)
	(gr_line
		(start 175.800004 -31.20009)
		(end 176.1998 -31.599886)
		(stroke
			(width 0.06985)
			(type default)
		)
		(layer "F.Cu")
	)
	(gr_line
		(start 175.800004 -30.400244)
		(end 176.1998 -30.80004)
		(stroke
			(width 0.06985)
			(type default)
		)
		(layer "F.Cu")
	)
	(gr_arc
		(start 176.079658 -23.392384)
		(mid 176.284087 -23.307739)
		(end 176.36871 -23.103332)
		(stroke
			(width 0.072898)
			(type default)
		)
		(layer "F.Cu")
	)
	(gr_line
		(start 176.1998 -29.19984)
		(end 176.552352 -28.847288)
		(stroke
			(width 0.072898)
			(type default)
		)
		(layer "F.Cu")
	)
	(gr_line
		(start 176.1998 -28.399994)
		(end 176.238662 -28.361132)
		(stroke
			(width 0.072898)
			(type default)
		)
		(layer "F.Cu")
	)
	(gr_arc
		(start 176.36871 -23.992332)
		(mid 176.284135 -23.788096)
		(end 176.079912 -23.703534)
		(stroke
			(width 0.072898)
			(type default)
		)
		(layer "F.Cu")
	)
	(gr_line
		(start 176.552352 -28.672282)
		(end 176.552352 -28.847288)
		(stroke
			(width 0.072898)
			(type default)
		)
		(layer "F.Cu")
	)
	(gr_arc
		(start 178.118262 -23.405592)
		(mid 178.322691 -23.320946)
		(end 178.407314 -23.11654)
		(stroke
			(width 0.072898)
			(type default)
		)
		(layer "F.Cu")
	)
	(gr_arc
		(start 178.407314 -24.00554)
		(mid 178.322742 -23.801297)
		(end 178.118516 -23.716742)
		(stroke
			(width 0.072898)
			(type default)
		)
		(layer "F.Cu")
	)
	(gr_arc
		(start 179.823872 -7.944358)
		(mid 179.948369 -7.892814)
		(end 179.999894 -7.768336)
		(stroke
			(width 0.072898)
			(type default)
		)
		(layer "F.Cu")
	)
	(gr_arc
		(start 179.999894 -8.431784)
		(mid 179.948264 -8.307138)
		(end 179.823618 -8.255508)
		(stroke
			(width 0.072898)
			(type default)
		)
		(layer "F.Cu")
	)
	(gr_line
		(start 179.999894 -8.431784)
		(end 179.999894 -8.800084)
		(stroke
			(width 0.072898)
			(type default)
		)
		(layer "F.Cu")
	)
	(gr_line
		(start 179.999894 -7.400036)
		(end 179.999894 -7.768336)
		(stroke
			(width 0.072898)
			(type default)
		)
		(layer "F.Cu")
	)
	(gr_arc
		(start 180.14696 -23.885398)
		(mid 180.351351 -23.800737)
		(end 180.436012 -23.596346)
		(stroke
			(width 0.072898)
			(type default)
		)
		(layer "F.Cu")
	)
	(gr_arc
		(start 180.436012 -24.485346)
		(mid 180.351442 -24.2811)
		(end 180.147214 -24.196548)
		(stroke
			(width 0.072898)
			(type default)
		)
		(layer "F.Cu")
	)
	(gr_line
		(start 85.330538 -38.962584)
		(end 85.339174 -39.003478)
		(stroke
			(width 0.06223)
			(type default)
		)
		(layer "B.Cu")
	)
	(gr_line
		(start 85.330538 -38.962584)
		(end 85.339174 -38.921944)
		(stroke
			(width 0.06223)
			(type default)
		)
		(layer "B.Cu")
	)
	(gr_arc
		(start 85.880956 -4.296918)
		(mid 85.926612 -4.287801)
		(end 85.965284 -4.261866)
		(stroke
			(width 0.06223)
			(type default)
		)
		(layer "B.Cu")
	)
	(gr_arc
		(start 85.965284 -4.261866)
		(mid 85.991058 -4.223293)
		(end 86.000082 -4.177792)
		(stroke
			(width 0.06223)
			(type default)
		)
		(layer "B.Cu")
	)
	(gr_arc
		(start 86.000082 -4.822444)
		(mid 85.991033 -4.776954)
		(end 85.965284 -4.73837)
		(stroke
			(width 0.06223)
			(type default)
		)
		(layer "B.Cu")
	)
	(gr_line
		(start 86.000082 -4.822444)
		(end 86.000082 -5.200142)
		(stroke
			(width 0.06223)
			(type default)
		)
		(layer "B.Cu")
	)
	(gr_line
		(start 86.000082 -3.800094)
		(end 86.000082 -4.177792)
		(stroke
			(width 0.06223)
			(type default)
		)
		(layer "B.Cu")
	)
	(gr_line
		(start 86.160356 -42.866564)
		(end 86.330536 -43.667934)
		(stroke
			(width 0.06223)
			(type default)
		)
		(layer "B.Cu")
	)
	(gr_line
		(start 86.427564 -44.124372)
		(end 86.597744 -44.92498)
		(stroke
			(width 0.06223)
			(type default)
		)
		(layer "B.Cu")
	)
	(gr_line
		(start 86.551262 -42.73931)
		(end 86.867492 -42.944542)
		(stroke
			(width 0.06223)
			(type default)
		)
		(layer "B.Cu")
	)
	(gr_line
		(start 86.694518 -45.380656)
		(end 86.864952 -46.182788)
		(stroke
			(width 0.06223)
			(type default)
		)
		(layer "B.Cu")
	)
	(gr_line
		(start 86.73973 -43.626024)
		(end 86.945216 -43.309794)
		(stroke
			(width 0.06223)
			(type default)
		)
		(layer "B.Cu")
	)
	(gr_line
		(start 86.81847 -43.996356)
		(end 87.1347 -44.201842)
		(stroke
			(width 0.06223)
			(type default)
		)
		(layer "B.Cu")
	)
	(gr_line
		(start 86.867492 -42.944542)
		(end 86.945216 -43.309794)
		(stroke
			(width 0.06223)
			(type default)
		)
		(layer "B.Cu")
	)
	(gr_line
		(start 86.868762 -39.026846)
		(end 86.877398 -39.066978)
		(stroke
			(width 0.06223)
			(type default)
		)
		(layer "B.Cu")
	)
	(gr_line
		(start 86.868762 -39.026846)
		(end 86.877398 -38.986206)
		(stroke
			(width 0.06223)
			(type default)
		)
		(layer "B.Cu")
	)
	(gr_line
		(start 86.961218 -46.636432)
		(end 87.132414 -47.44212)
		(stroke
			(width 0.06223)
			(type default)
		)
		(layer "B.Cu")
	)
	(gr_line
		(start 86.973664 -39.520368)
		(end 87.14486 -40.32504)
		(stroke
			(width 0.06223)
			(type default)
		)
		(layer "B.Cu")
	)
	(gr_line
		(start 87.006938 -44.883324)
		(end 87.212424 -44.567094)
		(stroke
			(width 0.06223)
			(type default)
		)
		(layer "B.Cu")
	)
	(gr_line
		(start 87.085424 -45.253402)
		(end 87.401908 -45.459142)
		(stroke
			(width 0.06223)
			(type default)
		)
		(layer "B.Cu")
	)
	(gr_line
		(start 87.1347 -44.201842)
		(end 87.212424 -44.567094)
		(stroke
			(width 0.06223)
			(type default)
		)
		(layer "B.Cu")
	)
	(gr_line
		(start 87.24138 -40.778938)
		(end 87.412068 -41.580816)
		(stroke
			(width 0.06223)
			(type default)
		)
		(layer "B.Cu")
	)
	(gr_line
		(start 87.253064 -48.00981)
		(end 87.259668 -48.040544)
		(stroke
			(width 0.06223)
			(type default)
		)
		(layer "B.Cu")
	)
	(gr_line
		(start 87.259668 -48.040544)
		(end 87.276686 -48.06696)
		(stroke
			(width 0.06223)
			(type default)
		)
		(layer "B.Cu")
	)
	(gr_line
		(start 87.273892 -46.140624)
		(end 87.479632 -45.82414)
		(stroke
			(width 0.06223)
			(type default)
		)
		(layer "B.Cu")
	)
	(gr_line
		(start 87.337138 -29.52369)
		(end 87.337392 -29.52369)
		(stroke
			(width 0.06223)
			(type default)
		)
		(layer "B.Cu")
	)
	(gr_line
		(start 87.352632 -46.510702)
		(end 87.669116 -46.716188)
		(stroke
			(width 0.06223)
			(type default)
		)
		(layer "B.Cu")
	)
	(gr_line
		(start 87.364824 -39.393876)
		(end 87.681308 -39.599362)
		(stroke
			(width 0.06223)
			(type default)
		)
		(layer "B.Cu")
	)
	(gr_line
		(start 87.401908 -45.459142)
		(end 87.479632 -45.82414)
		(stroke
			(width 0.06223)
			(type default)
		)
		(layer "B.Cu")
	)
	(gr_line
		(start 87.5411 -47.397924)
		(end 87.746586 -47.08144)
		(stroke
			(width 0.06223)
			(type default)
		)
		(layer "B.Cu")
	)
	(gr_line
		(start 87.553546 -40.281098)
		(end 87.759032 -39.964614)
		(stroke
			(width 0.06223)
			(type default)
		)
		(layer "B.Cu")
	)
	(gr_line
		(start 87.632286 -40.651176)
		(end 87.94877 -40.856408)
		(stroke
			(width 0.06223)
			(type default)
		)
		(layer "B.Cu")
	)
	(gr_line
		(start 87.669116 -46.716188)
		(end 87.746586 -47.08144)
		(stroke
			(width 0.06223)
			(type default)
		)
		(layer "B.Cu")
	)
	(gr_arc
		(start 87.681054 -3.096768)
		(mid 87.72671 -3.087651)
		(end 87.765382 -3.061716)
		(stroke
			(width 0.06223)
			(type default)
		)
		(layer "B.Cu")
	)
	(gr_line
		(start 87.681308 -39.599362)
		(end 87.759032 -39.964614)
		(stroke
			(width 0.06223)
			(type default)
		)
		(layer "B.Cu")
	)
	(gr_line
		(start 87.734902 -29.439108)
		(end 87.735156 -29.439108)
		(stroke
			(width 0.06223)
			(type default)
		)
		(layer "B.Cu")
	)
	(gr_line
		(start 87.7443 -29.563822)
		(end 87.752936 -29.52369)
		(stroke
			(width 0.06223)
			(type default)
		)
		(layer "B.Cu")
	)
	(gr_line
		(start 87.7443 -29.482542)
		(end 87.752936 -29.52369)
		(stroke
			(width 0.06223)
			(type default)
		)
		(layer "B.Cu")
	)
	(gr_arc
		(start 87.765382 -3.061716)
		(mid 87.791156 -3.023143)
		(end 87.80018 -2.977642)
		(stroke
			(width 0.06223)
			(type default)
		)
		(layer "B.Cu")
	)
	(gr_arc
		(start 87.80018 -3.622294)
		(mid 87.791131 -3.576804)
		(end 87.765382 -3.53822)
		(stroke
			(width 0.06223)
			(type default)
		)
		(layer "B.Cu")
	)
	(gr_line
		(start 87.80018 -3.622294)
		(end 87.80018 -3.999992)
		(stroke
			(width 0.06223)
			(type default)
		)
		(layer "B.Cu")
	)
	(gr_line
		(start 87.80018 -2.600198)
		(end 87.80018 -2.977642)
		(stroke
			(width 0.06223)
			(type default)
		)
		(layer "B.Cu")
	)
	(gr_line
		(start 87.821008 -41.538144)
		(end 88.02624 -41.22166)
		(stroke
			(width 0.06223)
			(type default)
		)
		(layer "B.Cu")
	)
	(gr_line
		(start 87.94877 -40.856408)
		(end 88.02624 -41.22166)
		(stroke
			(width 0.06223)
			(type default)
		)
		(layer "B.Cu")
	)
	(gr_line
		(start 87.95004 -22.565106)
		(end 88.12022 -23.366222)
		(stroke
			(width 0.06223)
			(type default)
		)
		(layer "B.Cu")
	)
	(gr_line
		(start 88.217248 -23.82266)
		(end 88.387428 -24.623776)
		(stroke
			(width 0.06223)
			(type default)
		)
		(layer "B.Cu")
	)
	(gr_line
		(start 88.340692 -22.437598)
		(end 88.657176 -22.643084)
		(stroke
			(width 0.06223)
			(type default)
		)
		(layer "B.Cu")
	)
	(gr_line
		(start 88.484456 -25.080214)
		(end 88.654636 -25.881076)
		(stroke
			(width 0.06223)
			(type default)
		)
		(layer "B.Cu")
	)
	(gr_line
		(start 88.529414 -23.324566)
		(end 88.734646 -23.008336)
		(stroke
			(width 0.06223)
			(type default)
		)
		(layer "B.Cu")
	)
	(gr_line
		(start 88.541352 -50.014378)
		(end 88.989154 -50.704242)
		(stroke
			(width 0.06223)
			(type default)
		)
		(layer "B.Cu")
	)
	(gr_line
		(start 88.6079 -23.694644)
		(end 88.924384 -23.900384)
		(stroke
			(width 0.06223)
			(type default)
		)
		(layer "B.Cu")
	)
	(gr_line
		(start 88.62187 -38.960044)
		(end 88.630506 -39.000684)
		(stroke
			(width 0.06223)
			(type default)
		)
		(layer "B.Cu")
	)
	(gr_line
		(start 88.62187 -38.960044)
		(end 88.630506 -38.919404)
		(stroke
			(width 0.06223)
			(type default)
		)
		(layer "B.Cu")
	)
	(gr_line
		(start 88.642444 -47.367952)
		(end 88.649048 -47.398686)
		(stroke
			(width 0.06223)
			(type default)
		)
		(layer "B.Cu")
	)
	(gr_line
		(start 88.649048 -47.398686)
		(end 88.666066 -47.425102)
		(stroke
			(width 0.06223)
			(type default)
		)
		(layer "B.Cu")
	)
	(gr_line
		(start 88.657176 -22.643084)
		(end 88.734646 -23.008336)
		(stroke
			(width 0.06223)
			(type default)
		)
		(layer "B.Cu")
	)
	(gr_line
		(start 88.750902 -26.33472)
		(end 88.922098 -27.1399)
		(stroke
			(width 0.06223)
			(type default)
		)
		(layer "B.Cu")
	)
	(gr_line
		(start 88.796622 -24.581866)
		(end 89.002108 -24.265636)
		(stroke
			(width 0.06223)
			(type default)
		)
		(layer "B.Cu")
	)
	(gr_line
		(start 88.861138 -49.75606)
		(end 89.2302 -49.834546)
		(stroke
			(width 0.06223)
			(type default)
		)
		(layer "B.Cu")
	)
	(gr_line
		(start 88.867742 -40.119554)
		(end 88.874346 -40.150034)
		(stroke
			(width 0.06223)
			(type default)
		)
		(layer "B.Cu")
	)
	(gr_line
		(start 88.874346 -40.150034)
		(end 88.891364 -40.176196)
		(stroke
			(width 0.06223)
			(type default)
		)
		(layer "B.Cu")
	)
	(gr_line
		(start 88.875108 -24.951944)
		(end 89.191592 -25.15743)
		(stroke
			(width 0.06223)
			(type default)
		)
		(layer "B.Cu")
	)
	(gr_line
		(start 88.924384 -23.900384)
		(end 89.002108 -24.265636)
		(stroke
			(width 0.06223)
			(type default)
		)
		(layer "B.Cu")
	)
	(gr_line
		(start 89.06383 -25.838912)
		(end 89.269316 -25.522682)
		(stroke
			(width 0.06223)
			(type default)
		)
		(layer "B.Cu")
	)
	(gr_line
		(start 89.142316 -26.20899)
		(end 89.4588 -26.41473)
		(stroke
			(width 0.06223)
			(type default)
		)
		(layer "B.Cu")
	)
	(gr_line
		(start 89.191592 -25.15743)
		(end 89.269316 -25.522682)
		(stroke
			(width 0.06223)
			(type default)
		)
		(layer "B.Cu")
	)
	(gr_line
		(start 89.2302 -49.834546)
		(end 89.433654 -50.147728)
		(stroke
			(width 0.06223)
			(type default)
		)
		(layer "B.Cu")
	)
	(gr_line
		(start 89.240106 -51.09083)
		(end 89.68994 -51.783488)
		(stroke
			(width 0.06223)
			(type default)
		)
		(layer "B.Cu")
	)
	(gr_line
		(start 89.331038 -27.096212)
		(end 89.536524 -26.779728)
		(stroke
			(width 0.06223)
			(type default)
		)
		(layer "B.Cu")
	)
	(gr_line
		(start 89.355168 -50.51679)
		(end 89.433654 -50.147728)
		(stroke
			(width 0.06223)
			(type default)
		)
		(layer "B.Cu")
	)
	(gr_line
		(start 89.4588 -26.41473)
		(end 89.536524 -26.779728)
		(stroke
			(width 0.06223)
			(type default)
		)
		(layer "B.Cu")
	)
	(gr_arc
		(start 89.480898 -4.296918)
		(mid 89.526567 -4.287825)
		(end 89.565226 -4.261866)
		(stroke
			(width 0.06223)
			(type default)
		)
		(layer "B.Cu")
	)
	(gr_line
		(start 89.561162 -50.834036)
		(end 89.930224 -50.912522)
		(stroke
			(width 0.06223)
			(type default)
		)
		(layer "B.Cu")
	)
	(gr_arc
		(start 89.565226 -4.73837)
		(mid 89.526565 -4.71241)
		(end 89.480898 -4.703318)
		(stroke
			(width 0.06223)
			(type default)
		)
		(layer "B.Cu")
	)
	(gr_arc
		(start 89.565226 -4.261866)
		(mid 89.590965 -4.223284)
		(end 89.600024 -4.177792)
		(stroke
			(width 0.06223)
			(type default)
		)
		(layer "B.Cu")
	)
	(gr_line
		(start 89.56548 -28.29306)
		(end 89.574116 -28.252166)
		(stroke
			(width 0.06223)
			(type default)
		)
		(layer "B.Cu")
	)
	(gr_line
		(start 89.56548 -28.211526)
		(end 89.574116 -28.252166)
		(stroke
			(width 0.06223)
			(type default)
		)
		(layer "B.Cu")
	)
	(gr_arc
		(start 89.600024 -4.822444)
		(mid 89.590975 -4.776954)
		(end 89.565226 -4.73837)
		(stroke
			(width 0.06223)
			(type default)
		)
		(layer "B.Cu")
	)
	(gr_line
		(start 89.600024 -4.822444)
		(end 89.600024 -5.200142)
		(stroke
			(width 0.06223)
			(type default)
		)
		(layer "B.Cu")
	)
	(gr_line
		(start 89.600024 -3.800094)
		(end 89.600024 -4.177792)
		(stroke
			(width 0.06223)
			(type default)
		)
		(layer "B.Cu")
	)
	(gr_line
		(start 89.62898 -21.48586)
		(end 89.799922 -22.28977)
		(stroke
			(width 0.06223)
			(type default)
		)
		(layer "B.Cu")
	)
	(gr_line
		(start 89.864438 -40.927782)
		(end 89.881456 -40.953944)
		(stroke
			(width 0.06223)
			(type default)
		)
		(layer "B.Cu")
	)
	(gr_line
		(start 89.881456 -40.953944)
		(end 89.88806 -40.984678)
		(stroke
			(width 0.06223)
			(type default)
		)
		(layer "B.Cu")
	)
	(gr_line
		(start 89.896188 -22.74316)
		(end 90.06713 -23.547324)
		(stroke
			(width 0.06223)
			(type default)
		)
		(layer "B.Cu")
	)
	(gr_line
		(start 89.930224 -50.912522)
		(end 90.133424 -51.225704)
		(stroke
			(width 0.06223)
			(type default)
		)
		(layer "B.Cu")
	)
	(gr_line
		(start 90.02014 -21.359368)
		(end 90.336624 -21.565108)
		(stroke
			(width 0.06223)
			(type default)
		)
		(layer "B.Cu")
	)
	(gr_line
		(start 90.055192 -51.594766)
		(end 90.133424 -51.225704)
		(stroke
			(width 0.06223)
			(type default)
		)
		(layer "B.Cu")
	)
	(gr_line
		(start 90.163396 -23.999698)
		(end 90.334084 -24.802846)
		(stroke
			(width 0.06223)
			(type default)
		)
		(layer "B.Cu")
	)
	(gr_line
		(start 90.208862 -22.24659)
		(end 90.414348 -21.930106)
		(stroke
			(width 0.06223)
			(type default)
		)
		(layer "B.Cu")
	)
	(gr_line
		(start 90.287348 -22.616668)
		(end 90.603832 -22.822154)
		(stroke
			(width 0.06223)
			(type default)
		)
		(layer "B.Cu")
	)
	(gr_line
		(start 90.295984 -52.716684)
		(end 90.31859 -52.751482)
		(stroke
			(width 0.06223)
			(type default)
		)
		(layer "B.Cu")
	)
	(gr_line
		(start 90.31859 -52.751482)
		(end 90.353388 -52.774088)
		(stroke
			(width 0.06223)
			(type default)
		)
		(layer "B.Cu")
	)
	(gr_line
		(start 90.336624 -21.565108)
		(end 90.414348 -21.930106)
		(stroke
			(width 0.06223)
			(type default)
		)
		(layer "B.Cu")
	)
	(gr_line
		(start 90.430858 -25.257506)
		(end 90.601292 -26.060146)
		(stroke
			(width 0.06223)
			(type default)
		)
		(layer "B.Cu")
	)
	(gr_line
		(start 90.4494 -39.140892)
		(end 90.458036 -39.181786)
		(stroke
			(width 0.06223)
			(type default)
		)
		(layer "B.Cu")
	)
	(gr_line
		(start 90.4494 -39.140892)
		(end 90.458036 -39.100252)
		(stroke
			(width 0.06223)
			(type default)
		)
		(layer "B.Cu")
	)
	(gr_line
		(start 90.47607 -23.503636)
		(end 90.681556 -23.187406)
		(stroke
			(width 0.06223)
			(type default)
		)
		(layer "B.Cu")
	)
	(gr_line
		(start 90.554556 -23.873714)
		(end 90.87104 -24.0792)
		(stroke
			(width 0.06223)
			(type default)
		)
		(layer "B.Cu")
	)
	(gr_line
		(start 90.603832 -22.822154)
		(end 90.681556 -23.187406)
		(stroke
			(width 0.06223)
			(type default)
		)
		(layer "B.Cu")
	)
	(gr_line
		(start 90.743024 -24.760682)
		(end 90.948764 -24.444452)
		(stroke
			(width 0.06223)
			(type default)
		)
		(layer "B.Cu")
	)
	(gr_line
		(start 90.821764 -25.13076)
		(end 91.138248 -25.3365)
		(stroke
			(width 0.06223)
			(type default)
		)
		(layer "B.Cu")
	)
	(gr_line
		(start 90.87104 -24.0792)
		(end 90.948764 -24.444452)
		(stroke
			(width 0.06223)
			(type default)
		)
		(layer "B.Cu")
	)
	(gr_line
		(start 91.010486 -26.017982)
		(end 91.215972 -25.701752)
		(stroke
			(width 0.06223)
			(type default)
		)
		(layer "B.Cu")
	)
	(gr_line
		(start 91.025726 -48.286416)
		(end 91.032076 -48.31715)
		(stroke
			(width 0.06223)
			(type default)
		)
		(layer "B.Cu")
	)
	(gr_line
		(start 91.032076 -48.31715)
		(end 91.049602 -48.344074)
		(stroke
			(width 0.06223)
			(type default)
		)
		(layer "B.Cu")
	)
	(gr_line
		(start 91.138248 -25.3365)
		(end 91.215972 -25.701752)
		(stroke
			(width 0.06223)
			(type default)
		)
		(layer "B.Cu")
	)
	(gr_arc
		(start 91.280996 -3.096768)
		(mid 91.326652 -3.087651)
		(end 91.365324 -3.061716)
		(stroke
			(width 0.06223)
			(type default)
		)
		(layer "B.Cu")
	)
	(gr_line
		(start 91.282266 -51.453542)
		(end 91.304872 -51.48834)
		(stroke
			(width 0.06223)
			(type default)
		)
		(layer "B.Cu")
	)
	(gr_line
		(start 91.304872 -51.48834)
		(end 91.33967 -51.510946)
		(stroke
			(width 0.06223)
			(type default)
		)
		(layer "B.Cu")
	)
	(gr_line
		(start 91.31808 -48.756824)
		(end 91.767152 -49.446688)
		(stroke
			(width 0.06223)
			(type default)
		)
		(layer "B.Cu")
	)
	(gr_arc
		(start 91.365324 -3.53822)
		(mid 91.326653 -3.512296)
		(end 91.280996 -3.503168)
		(stroke
			(width 0.06223)
			(type default)
		)
		(layer "B.Cu")
	)
	(gr_arc
		(start 91.365324 -3.061716)
		(mid 91.391098 -3.023143)
		(end 91.400122 -2.977642)
		(stroke
			(width 0.06223)
			(type default)
		)
		(layer "B.Cu")
	)
	(gr_line
		(start 91.389454 -27.89428)
		(end 91.39809 -27.854148)
		(stroke
			(width 0.06223)
			(type default)
		)
		(layer "B.Cu")
	)
	(gr_line
		(start 91.389454 -27.813508)
		(end 91.39809 -27.854148)
		(stroke
			(width 0.06223)
			(type default)
		)
		(layer "B.Cu")
	)
	(gr_arc
		(start 91.400122 -3.622294)
		(mid 91.391095 -3.576792)
		(end 91.365324 -3.53822)
		(stroke
			(width 0.06223)
			(type default)
		)
		(layer "B.Cu")
	)
	(gr_line
		(start 91.400122 -3.622294)
		(end 91.400122 -3.999992)
		(stroke
			(width 0.06223)
			(type default)
		)
		(layer "B.Cu")
	)
	(gr_line
		(start 91.400122 -2.600198)
		(end 91.400122 -2.977642)
		(stroke
			(width 0.06223)
			(type default)
		)
		(layer "B.Cu")
	)
	(gr_line
		(start 91.57589 -22.403054)
		(end 91.746832 -23.206456)
		(stroke
			(width 0.06223)
			(type default)
		)
		(layer "B.Cu")
	)
	(gr_line
		(start 91.6305 -44.700952)
		(end 91.637104 -44.731686)
		(stroke
			(width 0.06223)
			(type default)
		)
		(layer "B.Cu")
	)
	(gr_line
		(start 91.637104 -44.731686)
		(end 91.653868 -44.75734)
		(stroke
			(width 0.06223)
			(type default)
		)
		(layer "B.Cu")
	)
	(gr_line
		(start 91.638628 -48.499522)
		(end 92.00769 -48.5775)
		(stroke
			(width 0.06223)
			(type default)
		)
		(layer "B.Cu")
	)
	(gr_line
		(start 91.843098 -23.660354)
		(end 92.01404 -24.464518)
		(stroke
			(width 0.06223)
			(type default)
		)
		(layer "B.Cu")
	)
	(gr_line
		(start 91.96705 -22.276562)
		(end 92.283534 -22.482302)
		(stroke
			(width 0.06223)
			(type default)
		)
		(layer "B.Cu")
	)
	(gr_line
		(start 92.00769 -48.5775)
		(end 92.211398 -48.890428)
		(stroke
			(width 0.06223)
			(type default)
		)
		(layer "B.Cu")
	)
	(gr_line
		(start 92.018866 -49.834038)
		(end 92.469208 -50.526188)
		(stroke
			(width 0.06223)
			(type default)
		)
		(layer "B.Cu")
	)
	(gr_line
		(start 92.110306 -24.916892)
		(end 92.280994 -25.72004)
		(stroke
			(width 0.06223)
			(type default)
		)
		(layer "B.Cu")
	)
	(gr_line
		(start 92.133166 -49.259744)
		(end 92.211398 -48.890428)
		(stroke
			(width 0.06223)
			(type default)
		)
		(layer "B.Cu")
	)
	(gr_line
		(start 92.155772 -23.163784)
		(end 92.361258 -22.8473)
		(stroke
			(width 0.06223)
			(type default)
		)
		(layer "B.Cu")
	)
	(gr_line
		(start 92.234258 -23.533862)
		(end 92.550742 -23.739348)
		(stroke
			(width 0.06223)
			(type default)
		)
		(layer "B.Cu")
	)
	(gr_line
		(start 92.283534 -22.482302)
		(end 92.361258 -22.8473)
		(stroke
			(width 0.06223)
			(type default)
		)
		(layer "B.Cu")
	)
	(gr_line
		(start 92.33916 -49.576736)
		(end 92.70873 -49.654714)
		(stroke
			(width 0.06223)
			(type default)
		)
		(layer "B.Cu")
	)
	(gr_line
		(start 92.377768 -26.1747)
		(end 92.548202 -26.97734)
		(stroke
			(width 0.06223)
			(type default)
		)
		(layer "B.Cu")
	)
	(gr_line
		(start 92.42298 -24.42083)
		(end 92.628466 -24.1046)
		(stroke
			(width 0.06223)
			(type default)
		)
		(layer "B.Cu")
	)
	(gr_line
		(start 92.501466 -24.790908)
		(end 92.81795 -24.996394)
		(stroke
			(width 0.06223)
			(type default)
		)
		(layer "B.Cu")
	)
	(gr_line
		(start 92.550742 -23.739348)
		(end 92.628466 -24.1046)
		(stroke
			(width 0.06223)
			(type default)
		)
		(layer "B.Cu")
	)
	(gr_line
		(start 92.640404 -50.789078)
		(end 92.663518 -50.824892)
		(stroke
			(width 0.06223)
			(type default)
		)
		(layer "B.Cu")
	)
	(gr_line
		(start 92.663518 -50.824892)
		(end 92.700094 -50.848514)
		(stroke
			(width 0.06223)
			(type default)
		)
		(layer "B.Cu")
	)
	(gr_line
		(start 92.690188 -25.677876)
		(end 92.895674 -25.361646)
		(stroke
			(width 0.06223)
			(type default)
		)
		(layer "B.Cu")
	)
	(gr_line
		(start 92.70873 -49.654714)
		(end 92.912438 -49.967642)
		(stroke
			(width 0.06223)
			(type default)
		)
		(layer "B.Cu")
	)
	(gr_line
		(start 92.768674 -26.047954)
		(end 93.085158 -26.253694)
		(stroke
			(width 0.06223)
			(type default)
		)
		(layer "B.Cu")
	)
	(gr_line
		(start 92.81795 -24.996394)
		(end 92.895674 -25.361646)
		(stroke
			(width 0.06223)
			(type default)
		)
		(layer "B.Cu")
	)
	(gr_line
		(start 92.833952 -50.33645)
		(end 92.912438 -49.967642)
		(stroke
			(width 0.06223)
			(type default)
		)
		(layer "B.Cu")
	)
	(gr_line
		(start 92.95384 -17.366234)
		(end 92.960444 -17.396968)
		(stroke
			(width 0.06223)
			(type default)
		)
		(layer "B.Cu")
	)
	(gr_line
		(start 92.957396 -26.935176)
		(end 93.162882 -26.618946)
		(stroke
			(width 0.06223)
			(type default)
		)
		(layer "B.Cu")
	)
	(gr_line
		(start 92.960444 -17.396968)
		(end 92.977462 -17.423384)
		(stroke
			(width 0.06223)
			(type default)
		)
		(layer "B.Cu")
	)
	(gr_line
		(start 92.97416 -46.792134)
		(end 93.42247 -47.483268)
		(stroke
			(width 0.06223)
			(type default)
		)
		(layer "B.Cu")
	)
	(gr_arc
		(start 93.08084 -4.296918)
		(mid 93.126496 -4.287801)
		(end 93.165168 -4.261866)
		(stroke
			(width 0.06223)
			(type default)
		)
		(layer "B.Cu")
	)
	(gr_line
		(start 93.085158 -26.253694)
		(end 93.162882 -26.618946)
		(stroke
			(width 0.06223)
			(type default)
		)
		(layer "B.Cu")
	)
	(gr_line
		(start 93.159834 -54.596538)
		(end 93.18625 -54.613556)
		(stroke
			(width 0.06223)
			(type default)
		)
		(layer "B.Cu")
	)
	(gr_arc
		(start 93.165168 -4.73837)
		(mid 93.126497 -4.712442)
		(end 93.08084 -4.703318)
		(stroke
			(width 0.06223)
			(type default)
		)
		(layer "B.Cu")
	)
	(gr_arc
		(start 93.165168 -4.261866)
		(mid 93.190942 -4.223293)
		(end 93.199966 -4.177792)
		(stroke
			(width 0.06223)
			(type default)
		)
		(layer "B.Cu")
	)
	(gr_line
		(start 93.18625 -54.613556)
		(end 93.216984 -54.62016)
		(stroke
			(width 0.06223)
			(type default)
		)
		(layer "B.Cu")
	)
	(gr_line
		(start 93.197426 -28.15844)
		(end 93.206062 -28.117546)
		(stroke
			(width 0.06223)
			(type default)
		)
		(layer "B.Cu")
	)
	(gr_line
		(start 93.197426 -28.076906)
		(end 93.206062 -28.117546)
		(stroke
			(width 0.06223)
			(type default)
		)
		(layer "B.Cu")
	)
	(gr_arc
		(start 93.199966 -4.822444)
		(mid 93.190958 -4.776929)
		(end 93.165168 -4.73837)
		(stroke
			(width 0.06223)
			(type default)
		)
		(layer "B.Cu")
	)
	(gr_line
		(start 93.199966 -4.822444)
		(end 93.199966 -5.200142)
		(stroke
			(width 0.06223)
			(type default)
		)
		(layer "B.Cu")
	)
	(gr_line
		(start 93.199966 -3.800094)
		(end 93.199966 -4.177792)
		(stroke
			(width 0.06223)
			(type default)
		)
		(layer "B.Cu")
	)
	(gr_line
		(start 93.294454 -46.534832)
		(end 93.66377 -46.613572)
		(stroke
			(width 0.06223)
			(type default)
		)
		(layer "B.Cu")
	)
	(gr_line
		(start 93.66377 -46.613572)
		(end 93.86697 -46.926754)
		(stroke
			(width 0.06223)
			(type default)
		)
		(layer "B.Cu")
	)
	(gr_line
		(start 93.67393 -47.870872)
		(end 94.12224 -48.561752)
		(stroke
			(width 0.06223)
			(type default)
		)
		(layer "B.Cu")
	)
	(gr_line
		(start 93.788484 -47.295816)
		(end 93.86697 -46.926754)
		(stroke
			(width 0.06223)
			(type default)
		)
		(layer "B.Cu")
	)
	(gr_line
		(start 93.994224 -47.613062)
		(end 94.363286 -47.691802)
		(stroke
			(width 0.06223)
			(type default)
		)
		(layer "B.Cu")
	)
	(gr_line
		(start 94.290388 -53.427122)
		(end 94.315788 -53.443632)
		(stroke
			(width 0.06223)
			(type default)
		)
		(layer "B.Cu")
	)
	(gr_line
		(start 94.315788 -53.443632)
		(end 94.345506 -53.449982)
		(stroke
			(width 0.06223)
			(type default)
		)
		(layer "B.Cu")
	)
	(gr_line
		(start 94.363286 -47.691802)
		(end 94.566486 -48.004984)
		(stroke
			(width 0.06223)
			(type default)
		)
		(layer "B.Cu")
	)
	(gr_line
		(start 94.395544 -19.606514)
		(end 94.845886 -20.299934)
		(stroke
			(width 0.06223)
			(type default)
		)
		(layer "B.Cu")
	)
	(gr_line
		(start 94.488 -48.374046)
		(end 94.566486 -48.004984)
		(stroke
			(width 0.06223)
			(type default)
		)
		(layer "B.Cu")
	)
	(gr_line
		(start 94.493588 -15.725648)
		(end 94.500192 -15.756382)
		(stroke
			(width 0.06223)
			(type default)
		)
		(layer "B.Cu")
	)
	(gr_line
		(start 94.500192 -15.756382)
		(end 94.51721 -15.782798)
		(stroke
			(width 0.06223)
			(type default)
		)
		(layer "B.Cu")
	)
	(gr_line
		(start 94.716092 -19.349212)
		(end 95.085154 -19.427444)
		(stroke
			(width 0.06223)
			(type default)
		)
		(layer "B.Cu")
	)
	(gr_line
		(start 94.74962 -52.179474)
		(end 94.812612 -52.220368)
		(stroke
			(width 0.06223)
			(type default)
		)
		(layer "B.Cu")
	)
	(gr_arc
		(start 94.880938 -3.096768)
		(mid 94.926594 -3.087651)
		(end 94.965266 -3.061716)
		(stroke
			(width 0.06223)
			(type default)
		)
		(layer "B.Cu")
	)
	(gr_arc
		(start 94.965266 -3.53822)
		(mid 94.926598 -3.512282)
		(end 94.880938 -3.503168)
		(stroke
			(width 0.06223)
			(type default)
		)
		(layer "B.Cu")
	)
	(gr_arc
		(start 94.965266 -3.061716)
		(mid 94.99104 -3.023143)
		(end 95.000064 -2.977642)
		(stroke
			(width 0.06223)
			(type default)
		)
		(layer "B.Cu")
	)
	(gr_arc
		(start 95.000064 -3.622294)
		(mid 94.99104 -3.57679)
		(end 94.965266 -3.53822)
		(stroke
			(width 0.06223)
			(type default)
		)
		(layer "B.Cu")
	)
	(gr_line
		(start 95.000064 -3.622294)
		(end 95.000064 -3.999992)
		(stroke
			(width 0.06223)
			(type default)
		)
		(layer "B.Cu")
	)
	(gr_line
		(start 95.000064 -2.600198)
		(end 95.000064 -2.977642)
		(stroke
			(width 0.06223)
			(type default)
		)
		(layer "B.Cu")
	)
	(gr_line
		(start 95.085154 -19.427444)
		(end 95.288608 -19.740626)
		(stroke
			(width 0.06223)
			(type default)
		)
		(layer "B.Cu")
	)
	(gr_line
		(start 95.09506 -20.683474)
		(end 95.545402 -21.376894)
		(stroke
			(width 0.06223)
			(type default)
		)
		(layer "B.Cu")
	)
	(gr_line
		(start 95.210122 -20.110196)
		(end 95.288608 -19.740626)
		(stroke
			(width 0.06223)
			(type default)
		)
		(layer "B.Cu")
	)
	(gr_line
		(start 95.329502 -49.675542)
		(end 95.370396 -49.738534)
		(stroke
			(width 0.06223)
			(type default)
		)
		(layer "B.Cu")
	)
	(gr_line
		(start 95.382588 -17.115536)
		(end 95.832676 -17.808956)
		(stroke
			(width 0.06223)
			(type default)
		)
		(layer "B.Cu")
	)
	(gr_line
		(start 95.415862 -20.426934)
		(end 95.785432 -20.50542)
		(stroke
			(width 0.06223)
			(type default)
		)
		(layer "B.Cu")
	)
	(gr_line
		(start 95.70339 -16.858742)
		(end 96.07296 -16.937228)
		(stroke
			(width 0.06223)
			(type default)
		)
		(layer "B.Cu")
	)
	(gr_line
		(start 95.785432 -20.50542)
		(end 95.988632 -20.818602)
		(stroke
			(width 0.06223)
			(type default)
		)
		(layer "B.Cu")
	)
	(gr_line
		(start 95.795338 -21.76145)
		(end 96.245426 -22.45487)
		(stroke
			(width 0.06223)
			(type default)
		)
		(layer "B.Cu")
	)
	(gr_line
		(start 95.839026 -53.160168)
		(end 96.217994 -53.160168)
		(stroke
			(width 0.06223)
			(type default)
		)
		(layer "B.Cu")
	)
	(gr_line
		(start 95.839026 -51.763168)
		(end 96.217994 -51.763168)
		(stroke
			(width 0.06223)
			(type default)
		)
		(layer "B.Cu")
	)
	(gr_line
		(start 95.848678 -55.13832)
		(end 95.851726 -55.141368)
		(stroke
			(width 0.06223)
			(type default)
		)
		(layer "B.Cu")
	)
	(gr_line
		(start 95.848678 -54.560216)
		(end 95.851726 -54.557168)
		(stroke
			(width 0.06223)
			(type default)
		)
		(layer "B.Cu")
	)
	(gr_line
		(start 95.848678 -53.72862)
		(end 95.864426 -53.744368)
		(stroke
			(width 0.06223)
			(type default)
		)
		(layer "B.Cu")
	)
	(gr_line
		(start 95.848678 -52.33162)
		(end 95.864426 -52.347368)
		(stroke
			(width 0.06223)
			(type default)
		)
		(layer "B.Cu")
	)
	(gr_line
		(start 95.851726 -55.141368)
		(end 96.217994 -55.141368)
		(stroke
			(width 0.06223)
			(type default)
		)
		(layer "B.Cu")
	)
	(gr_line
		(start 95.851726 -54.557168)
		(end 96.217994 -54.557168)
		(stroke
			(width 0.06223)
			(type default)
		)
		(layer "B.Cu")
	)
	(gr_line
		(start 95.851726 -50.366168)
		(end 96.217994 -50.366168)
		(stroke
			(width 0.06223)
			(type default)
		)
		(layer "B.Cu")
	)
	(gr_line
		(start 95.864426 -53.744368)
		(end 96.217994 -53.744368)
		(stroke
			(width 0.06223)
			(type default)
		)
		(layer "B.Cu")
	)
	(gr_line
		(start 95.864426 -52.347368)
		(end 96.217994 -52.347368)
		(stroke
			(width 0.06223)
			(type default)
		)
		(layer "B.Cu")
	)
	(gr_line
		(start 95.890842 -50.905156)
		(end 95.936054 -50.950368)
		(stroke
			(width 0.06223)
			(type default)
		)
		(layer "B.Cu")
	)
	(gr_line
		(start 95.9104 -21.187918)
		(end 95.988632 -20.818602)
		(stroke
			(width 0.06223)
			(type default)
		)
		(layer "B.Cu")
	)
	(gr_line
		(start 95.936054 -50.950368)
		(end 96.217994 -50.950368)
		(stroke
			(width 0.06223)
			(type default)
		)
		(layer "B.Cu")
	)
	(gr_line
		(start 96.034098 -14.693138)
		(end 96.040702 -14.723872)
		(stroke
			(width 0.06223)
			(type default)
		)
		(layer "B.Cu")
	)
	(gr_line
		(start 96.040702 -14.723872)
		(end 96.05772 -14.750288)
		(stroke
			(width 0.06223)
			(type default)
		)
		(layer "B.Cu")
	)
	(gr_line
		(start 96.07296 -16.937228)
		(end 96.27616 -17.25041)
		(stroke
			(width 0.06223)
			(type default)
		)
		(layer "B.Cu")
	)
	(gr_line
		(start 96.082104 -18.19275)
		(end 96.532954 -18.887186)
		(stroke
			(width 0.06223)
			(type default)
		)
		(layer "B.Cu")
	)
	(gr_line
		(start 96.11614 -21.504656)
		(end 96.485456 -21.583142)
		(stroke
			(width 0.06223)
			(type default)
		)
		(layer "B.Cu")
	)
	(gr_line
		(start 96.197674 -17.619726)
		(end 96.27616 -17.25041)
		(stroke
			(width 0.06223)
			(type default)
		)
		(layer "B.Cu")
	)
	(gr_line
		(start 96.403414 -17.936464)
		(end 96.77273 -18.01495)
		(stroke
			(width 0.06223)
			(type default)
		)
		(layer "B.Cu")
	)
	(gr_line
		(start 96.485456 -21.583142)
		(end 96.68891 -21.896324)
		(stroke
			(width 0.06223)
			(type default)
		)
		(layer "B.Cu")
	)
	(gr_line
		(start 96.61017 -22.26564)
		(end 96.68891 -21.896324)
		(stroke
			(width 0.06223)
			(type default)
		)
		(layer "B.Cu")
	)
	(gr_line
		(start 96.647 -44.704)
		(end 96.650048 -44.707048)
		(stroke
			(width 0.06223)
			(type default)
		)
		(layer "B.Cu")
	)
	(gr_line
		(start 96.647 -44.5008)
		(end 96.647 -44.704)
		(stroke
			(width 0.06223)
			(type default)
		)
		(layer "B.Cu")
	)
	(gr_arc
		(start 96.681036 -4.296918)
		(mid 96.726692 -4.287801)
		(end 96.765364 -4.261866)
		(stroke
			(width 0.06223)
			(type default)
		)
		(layer "B.Cu")
	)
	(gr_line
		(start 96.73082 -43.253406)
		(end 96.771714 -43.190414)
		(stroke
			(width 0.06223)
			(type default)
		)
		(layer "B.Cu")
	)
	(gr_line
		(start 96.746822 -46.912276)
		(end 96.746822 -47.006256)
		(stroke
			(width 0.06223)
			(type default)
		)
		(layer "B.Cu")
	)
	(gr_line
		(start 96.746822 -45.627036)
		(end 96.746822 -45.721016)
		(stroke
			(width 0.06223)
			(type default)
		)
		(layer "B.Cu")
	)
	(gr_arc
		(start 96.765364 -4.73837)
		(mid 96.726693 -4.712443)
		(end 96.681036 -4.703318)
		(stroke
			(width 0.06223)
			(type default)
		)
		(layer "B.Cu")
	)
	(gr_arc
		(start 96.765364 -4.261866)
		(mid 96.791138 -4.223293)
		(end 96.800162 -4.177792)
		(stroke
			(width 0.06223)
			(type default)
		)
		(layer "B.Cu")
	)
	(gr_line
		(start 96.77273 -18.01495)
		(end 96.976184 -18.328132)
		(stroke
			(width 0.06223)
			(type default)
		)
		(layer "B.Cu")
	)
	(gr_line
		(start 96.776794 -55.141368)
		(end 97.143062 -55.141368)
		(stroke
			(width 0.06223)
			(type default)
		)
		(layer "B.Cu")
	)
	(gr_line
		(start 96.776794 -54.557168)
		(end 97.143062 -54.557168)
		(stroke
			(width 0.06223)
			(type default)
		)
		(layer "B.Cu")
	)
	(gr_line
		(start 96.776794 -53.744368)
		(end 97.143062 -53.744368)
		(stroke
			(width 0.06223)
			(type default)
		)
		(layer "B.Cu")
	)
	(gr_line
		(start 96.776794 -53.160168)
		(end 97.143062 -53.160168)
		(stroke
			(width 0.06223)
			(type default)
		)
		(layer "B.Cu")
	)
	(gr_line
		(start 96.776794 -52.347368)
		(end 97.143062 -52.347368)
		(stroke
			(width 0.06223)
			(type default)
		)
		(layer "B.Cu")
	)
	(gr_line
		(start 96.776794 -51.763168)
		(end 97.143062 -51.763168)
		(stroke
			(width 0.06223)
			(type default)
		)
		(layer "B.Cu")
	)
	(gr_line
		(start 96.776794 -50.950368)
		(end 97.143062 -50.950368)
		(stroke
			(width 0.06223)
			(type default)
		)
		(layer "B.Cu")
	)
	(gr_line
		(start 96.776794 -50.366168)
		(end 97.143062 -50.366168)
		(stroke
			(width 0.06223)
			(type default)
		)
		(layer "B.Cu")
	)
	(gr_line
		(start 96.780604 -19.26844)
		(end 97.211642 -19.932396)
		(stroke
			(width 0.06223)
			(type default)
		)
		(layer "B.Cu")
	)
	(gr_line
		(start 96.796352 -22.556724)
		(end 96.813116 -22.582378)
		(stroke
			(width 0.06223)
			(type default)
		)
		(layer "B.Cu")
	)
	(gr_arc
		(start 96.800162 -4.822444)
		(mid 96.791154 -4.776929)
		(end 96.765364 -4.73837)
		(stroke
			(width 0.06223)
			(type default)
		)
		(layer "B.Cu")
	)
	(gr_line
		(start 96.800162 -4.822444)
		(end 96.800162 -5.200142)
		(stroke
			(width 0.06223)
			(type default)
		)
		(layer "B.Cu")
	)
	(gr_line
		(start 96.800162 -3.800094)
		(end 96.800162 -4.177792)
		(stroke
			(width 0.06223)
			(type default)
		)
		(layer "B.Cu")
	)
	(gr_line
		(start 96.813116 -22.582378)
		(end 96.81972 -22.613112)
		(stroke
			(width 0.06223)
			(type default)
		)
		(layer "B.Cu")
	)
	(gr_line
		(start 96.897444 -18.697702)
		(end 96.976184 -18.328132)
		(stroke
			(width 0.06223)
			(type default)
		)
		(layer "B.Cu")
	)
	(gr_line
		(start 97.10293 -19.014186)
		(end 97.472754 -19.092926)
		(stroke
			(width 0.06223)
			(type default)
		)
		(layer "B.Cu")
	)
	(gr_line
		(start 97.143062 -55.141368)
		(end 97.14611 -55.13832)
		(stroke
			(width 0.06223)
			(type default)
		)
		(layer "B.Cu")
	)
	(gr_line
		(start 97.143062 -54.557168)
		(end 97.14611 -54.560216)
		(stroke
			(width 0.06223)
			(type default)
		)
		(layer "B.Cu")
	)
	(gr_line
		(start 97.143062 -53.744368)
		(end 97.14611 -53.74132)
		(stroke
			(width 0.06223)
			(type default)
		)
		(layer "B.Cu")
	)
	(gr_line
		(start 97.143062 -53.160168)
		(end 97.14611 -53.163216)
		(stroke
			(width 0.06223)
			(type default)
		)
		(layer "B.Cu")
	)
	(gr_line
		(start 97.143062 -52.347368)
		(end 97.14611 -52.34432)
		(stroke
			(width 0.06223)
			(type default)
		)
		(layer "B.Cu")
	)
	(gr_line
		(start 97.143062 -51.763168)
		(end 97.14611 -51.766216)
		(stroke
			(width 0.06223)
			(type default)
		)
		(layer "B.Cu")
	)
	(gr_line
		(start 97.143062 -50.950368)
		(end 97.14611 -50.94732)
		(stroke
			(width 0.06223)
			(type default)
		)
		(layer "B.Cu")
	)
	(gr_line
		(start 97.143062 -50.366168)
		(end 97.14611 -50.369216)
		(stroke
			(width 0.06223)
			(type default)
		)
		(layer "B.Cu")
	)
	(gr_line
		(start 97.155762 -47.412656)
		(end 97.422462 -47.145956)
		(stroke
			(width 0.06223)
			(type default)
		)
		(layer "B.Cu")
	)
	(gr_line
		(start 97.155762 -46.505876)
		(end 97.422462 -46.772576)
		(stroke
			(width 0.06223)
			(type default)
		)
		(layer "B.Cu")
	)
	(gr_line
		(start 97.155762 -46.127416)
		(end 97.422462 -45.860716)
		(stroke
			(width 0.06223)
			(type default)
		)
		(layer "B.Cu")
	)
	(gr_line
		(start 97.155762 -45.220636)
		(end 97.422462 -45.487336)
		(stroke
			(width 0.06223)
			(type default)
		)
		(layer "B.Cu")
	)
	(gr_line
		(start 97.2058 -44.5008)
		(end 97.2058 -44.7294)
		(stroke
			(width 0.06223)
			(type default)
		)
		(layer "B.Cu")
	)
	(gr_line
		(start 97.282762 -53.629306)
		(end 97.446592 -53.629306)
		(stroke
			(width 0.06223)
			(type default)
		)
		(layer "B.Cu")
	)
	(gr_line
		(start 97.395284 -49.269142)
		(end 97.461832 -49.33569)
		(stroke
			(width 0.06223)
			(type default)
		)
		(layer "B.Cu")
	)
	(gr_line
		(start 97.397062 -48.692562)
		(end 97.774506 -48.692562)
		(stroke
			(width 0.06223)
			(type default)
		)
		(layer "B.Cu")
	)
	(gr_line
		(start 97.422462 -46.772576)
		(end 97.422462 -47.145956)
		(stroke
			(width 0.06223)
			(type default)
		)
		(layer "B.Cu")
	)
	(gr_line
		(start 97.422462 -45.487336)
		(end 97.422462 -45.860716)
		(stroke
			(width 0.06223)
			(type default)
		)
		(layer "B.Cu")
	)
	(gr_line
		(start 97.472754 -19.092926)
		(end 97.676208 -19.406108)
		(stroke
			(width 0.06223)
			(type default)
		)
		(layer "B.Cu")
	)
	(gr_line
		(start 97.59696 -19.778472)
		(end 97.603818 -19.810476)
		(stroke
			(width 0.06223)
			(type default)
		)
		(layer "B.Cu")
	)
	(gr_line
		(start 97.59696 -19.778472)
		(end 97.676208 -19.406108)
		(stroke
			(width 0.06223)
			(type default)
		)
		(layer "B.Cu")
	)
	(gr_line
		(start 97.689162 -53.297074)
		(end 97.852992 -53.297074)
		(stroke
			(width 0.06223)
			(type default)
		)
		(layer "B.Cu")
	)
	(gr_line
		(start 97.774506 -48.692562)
		(end 98.038412 -48.956722)
		(stroke
			(width 0.06223)
			(type default)
		)
		(layer "B.Cu")
	)
	(gr_line
		(start 98.025204 -14.941804)
		(end 98.031808 -14.972538)
		(stroke
			(width 0.06223)
			(type default)
		)
		(layer "B.Cu")
	)
	(gr_line
		(start 98.031808 -14.972538)
		(end 98.048826 -14.9987)
		(stroke
			(width 0.06223)
			(type default)
		)
		(layer "B.Cu")
	)
	(gr_line
		(start 98.038412 -48.956722)
		(end 98.038412 -49.333912)
		(stroke
			(width 0.06223)
			(type default)
		)
		(layer "B.Cu")
	)
	(gr_line
		(start 98.171 -44.5008)
		(end 98.171 -44.879768)
		(stroke
			(width 0.06223)
			(type default)
		)
		(layer "B.Cu")
	)
	(gr_line
		(start 98.235516 -47.18177)
		(end 98.235516 -47.27575)
		(stroke
			(width 0.06223)
			(type default)
		)
		(layer "B.Cu")
	)
	(gr_line
		(start 98.235516 -45.89653)
		(end 98.235516 -45.99051)
		(stroke
			(width 0.06223)
			(type default)
		)
		(layer "B.Cu")
	)
	(gr_line
		(start 98.256852 -43.15206)
		(end 98.298254 -43.088306)
		(stroke
			(width 0.06223)
			(type default)
		)
		(layer "B.Cu")
	)
	(gr_arc
		(start 98.48088 -3.096768)
		(mid 98.526536 -3.087651)
		(end 98.565208 -3.061716)
		(stroke
			(width 0.06223)
			(type default)
		)
		(layer "B.Cu")
	)
	(gr_line
		(start 98.524822 -52.721002)
		(end 98.54692 -52.721002)
		(stroke
			(width 0.04445)
			(type default)
		)
		(layer "B.Cu")
	)
	(gr_line
		(start 98.524822 -52.314602)
		(end 98.54692 -52.314602)
		(stroke
			(width 0.04445)
			(type default)
		)
		(layer "B.Cu")
	)
	(gr_line
		(start 98.53041 -41.228518)
		(end 98.547428 -41.202102)
		(stroke
			(width 0.06223)
			(type default)
		)
		(layer "B.Cu")
	)
	(gr_line
		(start 98.54692 -52.721002)
		(end 98.613722 -52.6542)
		(stroke
			(width 0.04445)
			(type default)
		)
		(layer "B.Cu")
	)
	(gr_line
		(start 98.54692 -52.314602)
		(end 98.613722 -52.381404)
		(stroke
			(width 0.04445)
			(type default)
		)
		(layer "B.Cu")
	)
	(gr_line
		(start 98.547428 -41.202102)
		(end 98.554032 -41.171368)
		(stroke
			(width 0.06223)
			(type default)
		)
		(layer "B.Cu")
	)
	(gr_arc
		(start 98.565208 -3.53822)
		(mid 98.526542 -3.512268)
		(end 98.48088 -3.503168)
		(stroke
			(width 0.06223)
			(type default)
		)
		(layer "B.Cu")
	)
	(gr_arc
		(start 98.565208 -3.061716)
		(mid 98.590982 -3.023143)
		(end 98.600006 -2.977642)
		(stroke
			(width 0.06223)
			(type default)
		)
		(layer "B.Cu")
	)
	(gr_arc
		(start 98.600006 -3.622294)
		(mid 98.590978 -3.576793)
		(end 98.565208 -3.53822)
		(stroke
			(width 0.06223)
			(type default)
		)
		(layer "B.Cu")
	)
	(gr_line
		(start 98.600006 -3.622294)
		(end 98.600006 -3.999992)
		(stroke
			(width 0.06223)
			(type default)
		)
		(layer "B.Cu")
	)
	(gr_line
		(start 98.600006 -2.600198)
		(end 98.600006 -2.977642)
		(stroke
			(width 0.06223)
			(type default)
		)
		(layer "B.Cu")
	)
	(gr_line
		(start 98.6155 -52.652422)
		(end 98.65487 -52.613052)
		(stroke
			(width 0.04445)
			(type default)
		)
		(layer "B.Cu")
	)
	(gr_line
		(start 98.6155 -52.383182)
		(end 98.65487 -52.422552)
		(stroke
			(width 0.04445)
			(type default)
		)
		(layer "B.Cu")
	)
	(gr_line
		(start 98.644456 -47.68215)
		(end 98.911156 -47.41545)
		(stroke
			(width 0.06223)
			(type default)
		)
		(layer "B.Cu")
	)
	(gr_line
		(start 98.644456 -46.77537)
		(end 98.911156 -47.04207)
		(stroke
			(width 0.06223)
			(type default)
		)
		(layer "B.Cu")
	)
	(gr_line
		(start 98.644456 -46.39691)
		(end 98.911156 -46.13021)
		(stroke
			(width 0.06223)
			(type default)
		)
		(layer "B.Cu")
	)
	(gr_line
		(start 98.644456 -45.49013)
		(end 98.911156 -45.75683)
		(stroke
			(width 0.06223)
			(type default)
		)
		(layer "B.Cu")
	)
	(gr_line
		(start 98.659696 -53.703474)
		(end 98.681794 -53.703474)
		(stroke
			(width 0.04445)
			(type default)
		)
		(layer "B.Cu")
	)
	(gr_line
		(start 98.659696 -53.297074)
		(end 98.681794 -53.297074)
		(stroke
			(width 0.04445)
			(type default)
		)
		(layer "B.Cu")
	)
	(gr_line
		(start 98.661982 -51.725322)
		(end 98.68408 -51.725322)
		(stroke
			(width 0.04445)
			(type default)
		)
		(layer "B.Cu")
	)
	(gr_line
		(start 98.661982 -51.318922)
		(end 98.68408 -51.318922)
		(stroke
			(width 0.04445)
			(type default)
		)
		(layer "B.Cu")
	)
	(gr_line
		(start 98.681794 -53.703474)
		(end 98.748596 -53.636672)
		(stroke
			(width 0.04445)
			(type default)
		)
		(layer "B.Cu")
	)
	(gr_line
		(start 98.681794 -53.297074)
		(end 98.748596 -53.363876)
		(stroke
			(width 0.04445)
			(type default)
		)
		(layer "B.Cu")
	)
	(gr_line
		(start 98.68408 -51.725322)
		(end 98.750882 -51.65852)
		(stroke
			(width 0.04445)
			(type default)
		)
		(layer "B.Cu")
	)
	(gr_line
		(start 98.68408 -51.318922)
		(end 98.750882 -51.385724)
		(stroke
			(width 0.04445)
			(type default)
		)
		(layer "B.Cu")
	)
	(gr_line
		(start 98.704146 -18.078196)
		(end 98.721164 -18.104612)
		(stroke
			(width 0.06223)
			(type default)
		)
		(layer "B.Cu")
	)
	(gr_line
		(start 98.721164 -18.104612)
		(end 98.727768 -18.135346)
		(stroke
			(width 0.06223)
			(type default)
		)
		(layer "B.Cu")
	)
	(gr_line
		(start 98.7298 -44.5008)
		(end 98.7298 -44.879768)
		(stroke
			(width 0.06223)
			(type default)
		)
		(layer "B.Cu")
	)
	(gr_line
		(start 98.750374 -53.634894)
		(end 98.789744 -53.595524)
		(stroke
			(width 0.04445)
			(type default)
		)
		(layer "B.Cu")
	)
	(gr_line
		(start 98.750374 -53.365654)
		(end 98.789744 -53.405024)
		(stroke
			(width 0.04445)
			(type default)
		)
		(layer "B.Cu")
	)
	(gr_line
		(start 98.75266 -51.656742)
		(end 98.79203 -51.617372)
		(stroke
			(width 0.04445)
			(type default)
		)
		(layer "B.Cu")
	)
	(gr_line
		(start 98.75266 -51.387502)
		(end 98.79203 -51.426872)
		(stroke
			(width 0.04445)
			(type default)
		)
		(layer "B.Cu")
	)
	(gr_arc
		(start 98.866452 -54.297072)
		(mid 98.960944 -54.257955)
		(end 99.000056 -54.163468)
		(stroke
			(width 0.06223)
			(type default)
		)
		(layer "B.Cu")
	)
	(gr_line
		(start 98.911156 -47.04207)
		(end 98.911156 -47.41545)
		(stroke
			(width 0.06223)
			(type default)
		)
		(layer "B.Cu")
	)
	(gr_line
		(start 98.911156 -45.75683)
		(end 98.911156 -46.13021)
		(stroke
			(width 0.06223)
			(type default)
		)
		(layer "B.Cu")
	)
	(gr_arc
		(start 99.000056 -54.837076)
		(mid 98.960924 -54.742604)
		(end 98.866452 -54.703472)
		(stroke
			(width 0.06223)
			(type default)
		)
		(layer "B.Cu")
	)
	(gr_line
		(start 99.000056 -54.837076)
		(end 99.000056 -55.000144)
		(stroke
			(width 0.06223)
			(type default)
		)
		(layer "B.Cu")
	)
	(gr_line
		(start 99.000056 -54.000146)
		(end 99.000056 -54.163468)
		(stroke
			(width 0.06223)
			(type default)
		)
		(layer "B.Cu")
	)
	(gr_line
		(start 99.421696 -50.679604)
		(end 99.443794 -50.679604)
		(stroke
			(width 0.04445)
			(type default)
		)
		(layer "B.Cu")
	)
	(gr_line
		(start 99.421696 -50.273204)
		(end 99.443794 -50.273204)
		(stroke
			(width 0.04445)
			(type default)
		)
		(layer "B.Cu")
	)
	(gr_line
		(start 99.443794 -50.679604)
		(end 99.510596 -50.612802)
		(stroke
			(width 0.04445)
			(type default)
		)
		(layer "B.Cu")
	)
	(gr_line
		(start 99.443794 -50.273204)
		(end 99.510596 -50.340006)
		(stroke
			(width 0.04445)
			(type default)
		)
		(layer "B.Cu")
	)
	(gr_line
		(start 99.488244 -14.334998)
		(end 99.494848 -14.365732)
		(stroke
			(width 0.06223)
			(type default)
		)
		(layer "B.Cu")
	)
	(gr_line
		(start 99.494848 -14.365732)
		(end 99.511866 -14.392148)
		(stroke
			(width 0.06223)
			(type default)
		)
		(layer "B.Cu")
	)
	(gr_line
		(start 99.512374 -50.611024)
		(end 99.551744 -50.571654)
		(stroke
			(width 0.04445)
			(type default)
		)
		(layer "B.Cu")
	)
	(gr_line
		(start 99.512374 -50.341784)
		(end 99.551744 -50.381154)
		(stroke
			(width 0.04445)
			(type default)
		)
		(layer "B.Cu")
	)
	(gr_line
		(start 99.650296 -36.013136)
		(end 99.658932 -35.972242)
		(stroke
			(width 0.06223)
			(type default)
		)
		(layer "B.Cu")
	)
	(gr_line
		(start 99.650296 -35.931602)
		(end 99.658932 -35.972242)
		(stroke
			(width 0.06223)
			(type default)
		)
		(layer "B.Cu")
	)
	(gr_line
		(start 99.692714 -55.314596)
		(end 99.692968 -55.314596)
		(stroke
			(width 0.04445)
			(type default)
		)
		(layer "B.Cu")
	)
	(gr_line
		(start 99.695 -44.5008)
		(end 99.695 -44.7294)
		(stroke
			(width 0.06223)
			(type default)
		)
		(layer "B.Cu")
	)
	(gr_line
		(start 99.698556 -41.679114)
		(end 99.715574 -41.652698)
		(stroke
			(width 0.06223)
			(type default)
		)
		(layer "B.Cu")
	)
	(gr_line
		(start 99.715574 -41.652698)
		(end 99.722178 -41.621964)
		(stroke
			(width 0.06223)
			(type default)
		)
		(layer "B.Cu")
	)
	(gr_line
		(start 99.758246 -46.930564)
		(end 99.758246 -47.049944)
		(stroke
			(width 0.06223)
			(type default)
		)
		(layer "B.Cu")
	)
	(gr_line
		(start 99.758246 -45.619924)
		(end 99.758246 -45.739304)
		(stroke
			(width 0.06223)
			(type default)
		)
		(layer "B.Cu")
	)
	(gr_line
		(start 99.854004 -43.043602)
		(end 99.860354 -43.013884)
		(stroke
			(width 0.06223)
			(type default)
		)
		(layer "B.Cu")
	)
	(gr_line
		(start 99.860354 -43.013884)
		(end 99.876864 -42.988484)
		(stroke
			(width 0.06223)
			(type default)
		)
		(layer "B.Cu")
	)
	(gr_line
		(start 99.95535 -17.187164)
		(end 99.972368 -17.213326)
		(stroke
			(width 0.06223)
			(type default)
		)
		(layer "B.Cu")
	)
	(gr_line
		(start 99.972368 -17.213326)
		(end 99.978972 -17.24406)
		(stroke
			(width 0.06223)
			(type default)
		)
		(layer "B.Cu")
	)
	(gr_line
		(start 100.167186 -47.456344)
		(end 100.446586 -47.176944)
		(stroke
			(width 0.06223)
			(type default)
		)
		(layer "B.Cu")
	)
	(gr_line
		(start 100.167186 -46.524164)
		(end 100.446586 -46.803564)
		(stroke
			(width 0.06223)
			(type default)
		)
		(layer "B.Cu")
	)
	(gr_line
		(start 100.167186 -46.145704)
		(end 100.446586 -45.866304)
		(stroke
			(width 0.06223)
			(type default)
		)
		(layer "B.Cu")
	)
	(gr_line
		(start 100.167186 -45.213524)
		(end 100.446586 -45.492924)
		(stroke
			(width 0.06223)
			(type default)
		)
		(layer "B.Cu")
	)
	(gr_line
		(start 100.2538 -44.5008)
		(end 100.2538 -44.736512)
		(stroke
			(width 0.06223)
			(type default)
		)
		(layer "B.Cu")
	)
	(gr_arc
		(start 100.280978 -4.296918)
		(mid 100.326634 -4.287801)
		(end 100.365306 -4.261866)
		(stroke
			(width 0.06223)
			(type default)
		)
		(layer "B.Cu")
	)
	(gr_arc
		(start 100.365306 -4.73837)
		(mid 100.326637 -4.71243)
		(end 100.280978 -4.703318)
		(stroke
			(width 0.06223)
			(type default)
		)
		(layer "B.Cu")
	)
	(gr_arc
		(start 100.365306 -4.261866)
		(mid 100.39108 -4.223293)
		(end 100.400104 -4.177792)
		(stroke
			(width 0.06223)
			(type default)
		)
		(layer "B.Cu")
	)
	(gr_arc
		(start 100.400104 -4.822444)
		(mid 100.391093 -4.776933)
		(end 100.365306 -4.73837)
		(stroke
			(width 0.06223)
			(type default)
		)
		(layer "B.Cu")
	)
	(gr_line
		(start 100.400104 -4.822444)
		(end 100.400104 -5.200142)
		(stroke
			(width 0.06223)
			(type default)
		)
		(layer "B.Cu")
	)
	(gr_line
		(start 100.400104 -3.800094)
		(end 100.400104 -4.177792)
		(stroke
			(width 0.06223)
			(type default)
		)
		(layer "B.Cu")
	)
	(gr_line
		(start 100.446586 -46.803564)
		(end 100.446586 -47.176944)
		(stroke
			(width 0.06223)
			(type default)
		)
		(layer "B.Cu")
	)
	(gr_line
		(start 100.446586 -45.492924)
		(end 100.446586 -45.866304)
		(stroke
			(width 0.06223)
			(type default)
		)
		(layer "B.Cu")
	)
	(gr_arc
		(start 100.911152 -55.40502)
		(mid 100.974014 -55.378982)
		(end 101.000052 -55.31612)
		(stroke
			(width 0.04445)
			(type default)
		)
		(layer "B.Cu")
	)
	(gr_line
		(start 100.922328 -41.152572)
		(end 101.093016 -40.349932)
		(stroke
			(width 0.06223)
			(type default)
		)
		(layer "B.Cu")
	)
	(gr_line
		(start 100.97262 -35.740848)
		(end 100.981256 -35.700716)
		(stroke
			(width 0.06223)
			(type default)
		)
		(layer "B.Cu")
	)
	(gr_line
		(start 100.97262 -35.660076)
		(end 100.981256 -35.700716)
		(stroke
			(width 0.06223)
			(type default)
		)
		(layer "B.Cu")
	)
	(gr_arc
		(start 101.000052 -55.68442)
		(mid 100.974018 -55.621562)
		(end 100.911152 -55.59552)
		(stroke
			(width 0.04445)
			(type default)
		)
		(layer "B.Cu")
	)
	(gr_line
		(start 101.000052 -55.68442)
		(end 101.000052 -56.000142)
		(stroke
			(width 0.04445)
			(type default)
		)
		(layer "B.Cu")
	)
	(gr_line
		(start 101.000052 -55.000144)
		(end 101.000052 -55.31612)
		(stroke
			(width 0.04445)
			(type default)
		)
		(layer "B.Cu")
	)
	(gr_line
		(start 101.188774 -39.898066)
		(end 101.360224 -39.090854)
		(stroke
			(width 0.06223)
			(type default)
		)
		(layer "B.Cu")
	)
	(gr_line
		(start 101.215952 -41.673272)
		(end 101.23297 -41.646856)
		(stroke
			(width 0.06223)
			(type default)
		)
		(layer "B.Cu")
	)
	(gr_line
		(start 101.219 -44.5008)
		(end 101.219 -44.798996)
		(stroke
			(width 0.06223)
			(type default)
		)
		(layer "B.Cu")
	)
	(gr_line
		(start 101.23297 -41.646856)
		(end 101.239066 -41.617138)
		(stroke
			(width 0.06223)
			(type default)
		)
		(layer "B.Cu")
	)
	(gr_line
		(start 101.260402 -46.241208)
		(end 101.260402 -46.335188)
		(stroke
			(width 0.06223)
			(type default)
		)
		(layer "B.Cu")
	)
	(gr_line
		(start 101.313488 -41.279572)
		(end 101.629972 -41.074086)
		(stroke
			(width 0.06223)
			(type default)
		)
		(layer "B.Cu")
	)
	(gr_line
		(start 101.359716 -16.490696)
		(end 101.376734 -16.517112)
		(stroke
			(width 0.06223)
			(type default)
		)
		(layer "B.Cu")
	)
	(gr_line
		(start 101.376734 -16.517112)
		(end 101.383338 -16.547846)
		(stroke
			(width 0.06223)
			(type default)
		)
		(layer "B.Cu")
	)
	(gr_line
		(start 101.431598 -14.027404)
		(end 101.438202 -14.058138)
		(stroke
			(width 0.06223)
			(type default)
		)
		(layer "B.Cu")
	)
	(gr_line
		(start 101.438202 -14.058138)
		(end 101.45522 -14.084554)
		(stroke
			(width 0.06223)
			(type default)
		)
		(layer "B.Cu")
	)
	(gr_line
		(start 101.45649 -38.638734)
		(end 101.627178 -37.834316)
		(stroke
			(width 0.06223)
			(type default)
		)
		(layer "B.Cu")
	)
	(gr_line
		(start 101.501956 -40.392604)
		(end 101.707442 -40.709088)
		(stroke
			(width 0.06223)
			(type default)
		)
		(layer "B.Cu")
	)
	(gr_line
		(start 101.580442 -40.02278)
		(end 101.896926 -39.81704)
		(stroke
			(width 0.06223)
			(type default)
		)
		(layer "B.Cu")
	)
	(gr_line
		(start 101.629972 -41.074086)
		(end 101.707442 -40.709088)
		(stroke
			(width 0.06223)
			(type default)
		)
		(layer "B.Cu")
	)
	(gr_line
		(start 101.669342 -46.741588)
		(end 101.936042 -46.474888)
		(stroke
			(width 0.06223)
			(type default)
		)
		(layer "B.Cu")
	)
	(gr_line
		(start 101.669342 -45.834808)
		(end 101.936042 -46.101508)
		(stroke
			(width 0.06223)
			(type default)
		)
		(layer "B.Cu")
	)
	(gr_line
		(start 101.76891 -39.135304)
		(end 101.974396 -39.451788)
		(stroke
			(width 0.06223)
			(type default)
		)
		(layer "B.Cu")
	)
	(gr_line
		(start 101.7778 -44.5008)
		(end 101.7778 -44.796456)
		(stroke
			(width 0.06223)
			(type default)
		)
		(layer "B.Cu")
	)
	(gr_line
		(start 101.847396 -38.76548)
		(end 102.16388 -38.55974)
		(stroke
			(width 0.06223)
			(type default)
		)
		(layer "B.Cu")
	)
	(gr_line
		(start 101.896926 -39.81704)
		(end 101.974396 -39.451788)
		(stroke
			(width 0.06223)
			(type default)
		)
		(layer "B.Cu")
	)
	(gr_arc
		(start 101.91115 -55.40502)
		(mid 101.974051 -55.379001)
		(end 102.00005 -55.31612)
		(stroke
			(width 0.04445)
			(type default)
		)
		(layer "B.Cu")
	)
	(gr_line
		(start 101.936042 -46.101508)
		(end 101.936042 -46.474888)
		(stroke
			(width 0.06223)
			(type default)
		)
		(layer "B.Cu")
	)
	(gr_arc
		(start 102.00005 -55.68442)
		(mid 101.974016 -55.621563)
		(end 101.91115 -55.59552)
		(stroke
			(width 0.04445)
			(type default)
		)
		(layer "B.Cu")
	)
	(gr_line
		(start 102.00005 -55.68442)
		(end 102.00005 -56.000142)
		(stroke
			(width 0.04445)
			(type default)
		)
		(layer "B.Cu")
	)
	(gr_line
		(start 102.00005 -55.000144)
		(end 102.00005 -55.31612)
		(stroke
			(width 0.04445)
			(type default)
		)
		(layer "B.Cu")
	)
	(gr_line
		(start 102.035864 -37.878004)
		(end 102.241604 -38.194488)
		(stroke
			(width 0.06223)
			(type default)
		)
		(layer "B.Cu")
	)
	(gr_arc
		(start 102.081076 -3.096768)
		(mid 102.126747 -3.087679)
		(end 102.165404 -3.061716)
		(stroke
			(width 0.06223)
			(type default)
		)
		(layer "B.Cu")
	)
	(gr_line
		(start 102.15626 -50.439828)
		(end 102.253542 -50.439828)
		(stroke
			(width 0.04445)
			(type default)
		)
		(layer "B.Cu")
	)
	(gr_line
		(start 102.16388 -38.55974)
		(end 102.241604 -38.194488)
		(stroke
			(width 0.06223)
			(type default)
		)
		(layer "B.Cu")
	)
	(gr_arc
		(start 102.165404 -3.061716)
		(mid 102.191143 -3.023132)
		(end 102.200202 -2.977642)
		(stroke
			(width 0.06223)
			(type default)
		)
		(layer "B.Cu")
	)
	(gr_arc
		(start 102.200202 -3.622294)
		(mid 102.191153 -3.576804)
		(end 102.165404 -3.53822)
		(stroke
			(width 0.06223)
			(type default)
		)
		(layer "B.Cu")
	)
	(gr_line
		(start 102.200202 -3.622294)
		(end 102.200202 -3.999992)
		(stroke
			(width 0.06223)
			(type default)
		)
		(layer "B.Cu")
	)
	(gr_line
		(start 102.200202 -2.600198)
		(end 102.200202 -2.977642)
		(stroke
			(width 0.06223)
			(type default)
		)
		(layer "B.Cu")
	)
	(gr_line
		(start 102.256082 -50.439828)
		(end 102.311708 -50.439828)
		(stroke
			(width 0.04445)
			(type default)
		)
		(layer "B.Cu")
	)
	(gr_line
		(start 102.310438 -50.019204)
		(end 102.45217 -50.160936)
		(stroke
			(width 0.06223)
			(type default)
		)
		(layer "B.Cu")
	)
	(gr_line
		(start 102.311708 -50.439828)
		(end 102.40518 -50.5333)
		(stroke
			(width 0.04445)
			(type default)
		)
		(layer "B.Cu")
	)
	(gr_line
		(start 102.317804 -110.838488)
		(end 102.32644 -110.87989)
		(stroke
			(width 0.06223)
			(type default)
		)
		(layer "B.Cu")
	)
	(gr_line
		(start 102.317804 -110.838488)
		(end 102.32644 -110.79734)
		(stroke
			(width 0.06223)
			(type default)
		)
		(layer "B.Cu")
	)
	(gr_line
		(start 102.32644 -110.797086)
		(end 102.326694 -110.796324)
		(stroke
			(width 0.06223)
			(type default)
		)
		(layer "B.Cu")
	)
	(gr_line
		(start 102.336092 -114.595402)
		(end 102.344728 -114.636296)
		(stroke
			(width 0.06223)
			(type default)
		)
		(layer "B.Cu")
	)
	(gr_line
		(start 102.336092 -114.595402)
		(end 102.344728 -114.554762)
		(stroke
			(width 0.06223)
			(type default)
		)
		(layer "B.Cu")
	)
	(gr_line
		(start 102.344728 -114.554)
		(end 102.344728 -114.554508)
		(stroke
			(width 0.06223)
			(type default)
		)
		(layer "B.Cu")
	)
	(gr_line
		(start 102.398322 -111.222282)
		(end 102.404926 -111.253778)
		(stroke
			(width 0.06223)
			(type default)
		)
		(layer "B.Cu")
	)
	(gr_line
		(start 102.404926 -111.253778)
		(end 102.422452 -111.280702)
		(stroke
			(width 0.06223)
			(type default)
		)
		(layer "B.Cu")
	)
	(gr_line
		(start 102.428802 -110.312454)
		(end 102.435152 -110.282736)
		(stroke
			(width 0.06223)
			(type default)
		)
		(layer "B.Cu")
	)
	(gr_line
		(start 102.431596 -114.145314)
		(end 102.437946 -114.115596)
		(stroke
			(width 0.06223)
			(type default)
		)
		(layer "B.Cu")
	)
	(gr_line
		(start 102.435152 -110.282736)
		(end 102.451662 -110.257336)
		(stroke
			(width 0.06223)
			(type default)
		)
		(layer "B.Cu")
	)
	(gr_line
		(start 102.437946 -114.115596)
		(end 102.454456 -114.089942)
		(stroke
			(width 0.06223)
			(type default)
		)
		(layer "B.Cu")
	)
	(gr_line
		(start 102.438708 -115.082066)
		(end 102.445058 -115.112038)
		(stroke
			(width 0.06223)
			(type default)
		)
		(layer "B.Cu")
	)
	(gr_line
		(start 102.445058 -115.112038)
		(end 102.462076 -115.1382)
		(stroke
			(width 0.06223)
			(type default)
		)
		(layer "B.Cu")
	)
	(gr_line
		(start 102.446582 -50.249328)
		(end 102.446582 -50.305208)
		(stroke
			(width 0.04445)
			(type default)
		)
		(layer "B.Cu")
	)
	(gr_line
		(start 102.446582 -50.166524)
		(end 102.446582 -50.246788)
		(stroke
			(width 0.04445)
			(type default)
		)
		(layer "B.Cu")
	)
	(gr_line
		(start 102.446582 -50.166524)
		(end 102.45217 -50.160936)
		(stroke
			(width 0.04445)
			(type default)
		)
		(layer "B.Cu")
	)
	(gr_line
		(start 102.469696 -35.824668)
		(end 102.478332 -35.783774)
		(stroke
			(width 0.06223)
			(type default)
		)
		(layer "B.Cu")
	)
	(gr_line
		(start 102.469696 -35.743134)
		(end 102.478332 -35.783774)
		(stroke
			(width 0.06223)
			(type default)
		)
		(layer "B.Cu")
	)
	(gr_line
		(start 102.486968 -31.002224)
		(end 102.657402 -31.804102)
		(stroke
			(width 0.06223)
			(type default)
		)
		(layer "B.Cu")
	)
	(gr_line
		(start 102.602284 -15.10411)
		(end 102.619302 -15.130526)
		(stroke
			(width 0.06223)
			(type default)
		)
		(layer "B.Cu")
	)
	(gr_line
		(start 102.616 -42.368216)
		(end 102.631748 -42.294302)
		(stroke
			(width 0.06223)
			(type default)
		)
		(layer "B.Cu")
	)
	(gr_line
		(start 102.619302 -15.130526)
		(end 102.625906 -15.16126)
		(stroke
			(width 0.06223)
			(type default)
		)
		(layer "B.Cu")
	)
	(gr_line
		(start 102.675182 -109.912912)
		(end 102.697788 -109.878114)
		(stroke
			(width 0.06223)
			(type default)
		)
		(layer "B.Cu")
	)
	(gr_line
		(start 102.697788 -109.878114)
		(end 102.732586 -109.855508)
		(stroke
			(width 0.06223)
			(type default)
		)
		(layer "B.Cu")
	)
	(gr_line
		(start 102.716838 -113.685574)
		(end 102.739698 -113.650522)
		(stroke
			(width 0.06223)
			(type default)
		)
		(layer "B.Cu")
	)
	(gr_line
		(start 102.739698 -113.650522)
		(end 102.77475 -113.627662)
		(stroke
			(width 0.06223)
			(type default)
		)
		(layer "B.Cu")
	)
	(gr_line
		(start 102.743 -44.5008)
		(end 102.743 -44.7294)
		(stroke
			(width 0.06223)
			(type default)
		)
		(layer "B.Cu")
	)
	(gr_line
		(start 102.750112 -116.249958)
		(end 102.970584 -115.838732)
		(stroke
			(width 0.06223)
			(type default)
		)
		(layer "B.Cu")
	)
	(gr_line
		(start 102.750112 -112.450118)
		(end 102.970584 -112.038892)
		(stroke
			(width 0.06223)
			(type default)
		)
		(layer "B.Cu")
	)
	(gr_line
		(start 102.754176 -32.259778)
		(end 102.924864 -33.062418)
		(stroke
			(width 0.06223)
			(type default)
		)
		(layer "B.Cu")
	)
	(gr_line
		(start 102.807262 -46.332902)
		(end 102.807262 -46.426882)
		(stroke
			(width 0.06223)
			(type default)
		)
		(layer "B.Cu")
	)
	(gr_line
		(start 102.877874 -30.875478)
		(end 103.194358 -31.080964)
		(stroke
			(width 0.06223)
			(type default)
		)
		(layer "B.Cu")
	)
	(gr_line
		(start 102.909624 -115.664742)
		(end 102.91064 -115.66525)
		(stroke
			(width 0.06223)
			(type default)
		)
		(layer "B.Cu")
	)
	(gr_line
		(start 102.909624 -111.864902)
		(end 102.91064 -111.86541)
		(stroke
			(width 0.06223)
			(type default)
		)
		(layer "B.Cu")
	)
	(gr_arc
		(start 102.911148 -55.40502)
		(mid 102.97401 -55.378982)
		(end 103.000048 -55.31612)
		(stroke
			(width 0.04445)
			(type default)
		)
		(layer "B.Cu")
	)
	(gr_arc
		(start 102.970584 -115.838732)
		(mid 102.980121 -115.743884)
		(end 102.919784 -115.670076)
		(stroke
			(width 0.06223)
			(type default)
		)
		(layer "B.Cu")
	)
	(gr_arc
		(start 102.970584 -112.038892)
		(mid 102.980095 -111.944063)
		(end 102.919784 -111.870236)
		(stroke
			(width 0.06223)
			(type default)
		)
		(layer "B.Cu")
	)
	(gr_arc
		(start 103.000048 -55.68442)
		(mid 102.97402 -55.621528)
		(end 102.911148 -55.59552)
		(stroke
			(width 0.04445)
			(type default)
		)
		(layer "B.Cu")
	)
	(gr_line
		(start 103.000048 -55.68442)
		(end 103.000048 -56.000142)
		(stroke
			(width 0.04445)
			(type default)
		)
		(layer "B.Cu")
	)
	(gr_line
		(start 103.000048 -55.000144)
		(end 103.000048 -55.31612)
		(stroke
			(width 0.04445)
			(type default)
		)
		(layer "B.Cu")
	)
	(gr_line
		(start 103.02113 -33.516316)
		(end 103.192072 -34.320988)
		(stroke
			(width 0.06223)
			(type default)
		)
		(layer "B.Cu")
	)
	(gr_line
		(start 103.066342 -31.7627)
		(end 103.272082 -31.446216)
		(stroke
			(width 0.06223)
			(type default)
		)
		(layer "B.Cu")
	)
	(gr_line
		(start 103.104188 -14.0462)
		(end 103.110538 -14.076934)
		(stroke
			(width 0.06223)
			(type default)
		)
		(layer "B.Cu")
	)
	(gr_line
		(start 103.10749 -115.309396)
		(end 103.110538 -115.31092)
		(stroke
			(width 0.06223)
			(type default)
		)
		(layer "B.Cu")
	)
	(gr_line
		(start 103.10749 -111.509556)
		(end 103.110538 -111.51108)
		(stroke
			(width 0.06223)
			(type default)
		)
		(layer "B.Cu")
	)
	(gr_line
		(start 103.110538 -14.076934)
		(end 103.127556 -14.103096)
		(stroke
			(width 0.06223)
			(type default)
		)
		(layer "B.Cu")
	)
	(gr_arc
		(start 103.1113 -115.311428)
		(mid 103.206149 -115.320958)
		(end 103.279956 -115.260628)
		(stroke
			(width 0.06223)
			(type default)
		)
		(layer "B.Cu")
	)
	(gr_arc
		(start 103.1113 -111.511588)
		(mid 103.206149 -111.521118)
		(end 103.279956 -111.460788)
		(stroke
			(width 0.06223)
			(type default)
		)
		(layer "B.Cu")
	)
	(gr_line
		(start 103.121968 -50.27549)
		(end 103.216456 -50.27549)
		(stroke
			(width 0.04445)
			(type default)
		)
		(layer "B.Cu")
	)
	(gr_line
		(start 103.145082 -32.132524)
		(end 103.461566 -32.33801)
		(stroke
			(width 0.06223)
			(type default)
		)
		(layer "B.Cu")
	)
	(gr_line
		(start 103.194358 -31.080964)
		(end 103.272082 -31.446216)
		(stroke
			(width 0.06223)
			(type default)
		)
		(layer "B.Cu")
	)
	(gr_line
		(start 103.216202 -46.833282)
		(end 103.482902 -46.566582)
		(stroke
			(width 0.06223)
			(type default)
		)
		(layer "B.Cu")
	)
	(gr_line
		(start 103.216202 -45.926502)
		(end 103.482902 -46.193202)
		(stroke
			(width 0.06223)
			(type default)
		)
		(layer "B.Cu")
	)
	(gr_line
		(start 103.218996 -50.27549)
		(end 103.28021 -50.27549)
		(stroke
			(width 0.04445)
			(type default)
		)
		(layer "B.Cu")
	)
	(gr_line
		(start 103.277416 -49.856136)
		(end 103.409496 -49.988216)
		(stroke
			(width 0.06223)
			(type default)
		)
		(layer "B.Cu")
	)
	(gr_line
		(start 103.279956 -115.260628)
		(end 103.49992 -114.84991)
		(stroke
			(width 0.06223)
			(type default)
		)
		(layer "B.Cu")
	)
	(gr_line
		(start 103.279956 -111.460788)
		(end 103.49992 -111.05007)
		(stroke
			(width 0.06223)
			(type default)
		)
		(layer "B.Cu")
	)
	(gr_line
		(start 103.28021 -50.27549)
		(end 103.405686 -50.400966)
		(stroke
			(width 0.04445)
			(type default)
		)
		(layer "B.Cu")
	)
	(gr_line
		(start 103.3018 -44.5008)
		(end 103.3018 -44.7294)
		(stroke
			(width 0.06223)
			(type default)
		)
		(layer "B.Cu")
	)
	(gr_line
		(start 103.33355 -33.02)
		(end 103.539036 -32.703262)
		(stroke
			(width 0.06223)
			(type default)
		)
		(layer "B.Cu")
	)
	(gr_line
		(start 103.401114 -113.221262)
		(end 103.42753 -113.204244)
		(stroke
			(width 0.06223)
			(type default)
		)
		(layer "B.Cu")
	)
	(gr_line
		(start 103.40213 -109.420914)
		(end 103.42753 -109.404404)
		(stroke
			(width 0.06223)
			(type default)
		)
		(layer "B.Cu")
	)
	(gr_line
		(start 103.409496 -50.08499)
		(end 103.409496 -50.135282)
		(stroke
			(width 0.04445)
			(type default)
		)
		(layer "B.Cu")
	)
	(gr_line
		(start 103.409496 -49.988216)
		(end 103.409496 -50.08245)
		(stroke
			(width 0.04445)
			(type default)
		)
		(layer "B.Cu")
	)
	(gr_line
		(start 103.41229 -33.389824)
		(end 103.728774 -33.59531)
		(stroke
			(width 0.06223)
			(type default)
		)
		(layer "B.Cu")
	)
	(gr_line
		(start 103.42753 -113.204244)
		(end 103.458264 -113.19764)
		(stroke
			(width 0.06223)
			(type default)
		)
		(layer "B.Cu")
	)
	(gr_line
		(start 103.42753 -109.404404)
		(end 103.457248 -109.398054)
		(stroke
			(width 0.06223)
			(type default)
		)
		(layer "B.Cu")
	)
	(gr_line
		(start 103.461566 -32.33801)
		(end 103.539036 -32.703262)
		(stroke
			(width 0.06223)
			(type default)
		)
		(layer "B.Cu")
	)
	(gr_line
		(start 103.482902 -46.193202)
		(end 103.482902 -46.566582)
		(stroke
			(width 0.06223)
			(type default)
		)
		(layer "B.Cu")
	)
	(gr_line
		(start 103.600758 -34.2773)
		(end 103.806244 -33.960562)
		(stroke
			(width 0.06223)
			(type default)
		)
		(layer "B.Cu")
	)
	(gr_line
		(start 103.728774 -33.59531)
		(end 103.806244 -33.960562)
		(stroke
			(width 0.06223)
			(type default)
		)
		(layer "B.Cu")
	)
	(gr_line
		(start 103.858822 -30.151832)
		(end 104.02951 -30.955234)
		(stroke
			(width 0.06223)
			(type default)
		)
		(layer "B.Cu")
	)
	(gr_line
		(start 103.86568 -42.845482)
		(end 103.881428 -42.771568)
		(stroke
			(width 0.06223)
			(type default)
		)
		(layer "B.Cu")
	)
	(gr_arc
		(start 103.88092 -4.296918)
		(mid 103.926576 -4.287801)
		(end 103.965248 -4.261866)
		(stroke
			(width 0.06223)
			(type default)
		)
		(layer "B.Cu")
	)
	(gr_arc
		(start 103.911146 -55.40502)
		(mid 103.974008 -55.378982)
		(end 104.000046 -55.31612)
		(stroke
			(width 0.04445)
			(type default)
		)
		(layer "B.Cu")
	)
	(gr_line
		(start 103.958136 -36.052252)
		(end 103.966772 -36.011358)
		(stroke
			(width 0.06223)
			(type default)
		)
		(layer "B.Cu")
	)
	(gr_line
		(start 103.958136 -35.970718)
		(end 103.966772 -36.011358)
		(stroke
			(width 0.06223)
			(type default)
		)
		(layer "B.Cu")
	)
	(gr_arc
		(start 103.965248 -4.73837)
		(mid 103.926576 -4.712448)
		(end 103.88092 -4.703318)
		(stroke
			(width 0.06223)
			(type default)
		)
		(layer "B.Cu")
	)
	(gr_arc
		(start 103.965248 -4.261866)
		(mid 103.991022 -4.223293)
		(end 104.000046 -4.177792)
		(stroke
			(width 0.06223)
			(type default)
		)
		(layer "B.Cu")
	)
	(gr_arc
		(start 104.000046 -55.68442)
		(mid 103.974018 -55.621529)
		(end 103.911146 -55.59552)
		(stroke
			(width 0.04445)
			(type default)
		)
		(layer "B.Cu")
	)
	(gr_line
		(start 104.000046 -55.68442)
		(end 104.000046 -56.000142)
		(stroke
			(width 0.04445)
			(type default)
		)
		(layer "B.Cu")
	)
	(gr_line
		(start 104.000046 -55.000144)
		(end 104.000046 -55.31612)
		(stroke
			(width 0.04445)
			(type default)
		)
		(layer "B.Cu")
	)
	(gr_arc
		(start 104.000046 -4.822444)
		(mid 103.991037 -4.77693)
		(end 103.965248 -4.73837)
		(stroke
			(width 0.06223)
			(type default)
		)
		(layer "B.Cu")
	)
	(gr_line
		(start 104.000046 -4.822444)
		(end 104.000046 -5.200142)
		(stroke
			(width 0.06223)
			(type default)
		)
		(layer "B.Cu")
	)
	(gr_line
		(start 104.000046 -3.800094)
		(end 104.000046 -4.177792)
		(stroke
			(width 0.06223)
			(type default)
		)
		(layer "B.Cu")
	)
	(gr_line
		(start 104.101646 -14.856206)
		(end 104.118664 -14.882368)
		(stroke
			(width 0.06223)
			(type default)
		)
		(layer "B.Cu")
	)
	(gr_line
		(start 104.118664 -14.882368)
		(end 104.125268 -14.913102)
		(stroke
			(width 0.06223)
			(type default)
		)
		(layer "B.Cu")
	)
	(gr_line
		(start 104.125776 -31.408878)
		(end 104.296972 -32.21482)
		(stroke
			(width 0.06223)
			(type default)
		)
		(layer "B.Cu")
	)
	(gr_line
		(start 104.249982 -30.025848)
		(end 104.566466 -30.231588)
		(stroke
			(width 0.06223)
			(type default)
		)
		(layer "B.Cu")
	)
	(gr_line
		(start 104.267 -44.5008)
		(end 104.267 -44.752768)
		(stroke
			(width 0.06223)
			(type default)
		)
		(layer "B.Cu")
	)
	(gr_line
		(start 104.31399 -46.367192)
		(end 104.31399 -46.461172)
		(stroke
			(width 0.06223)
			(type default)
		)
		(layer "B.Cu")
	)
	(gr_line
		(start 104.325166 -50.513742)
		(end 104.391968 -50.580544)
		(stroke
			(width 0.04445)
			(type default)
		)
		(layer "B.Cu")
	)
	(gr_line
		(start 104.325166 -50.491644)
		(end 104.325166 -50.513742)
		(stroke
			(width 0.04445)
			(type default)
		)
		(layer "B.Cu")
	)
	(gr_line
		(start 104.325166 -50.36058)
		(end 104.325166 -50.491644)
		(stroke
			(width 0.06223)
			(type default)
		)
		(layer "B.Cu")
	)
	(gr_line
		(start 104.393238 -32.667448)
		(end 104.56418 -33.472374)
		(stroke
			(width 0.06223)
			(type default)
		)
		(layer "B.Cu")
	)
	(gr_line
		(start 104.393746 -50.582322)
		(end 104.405684 -50.59426)
		(stroke
			(width 0.04445)
			(type default)
		)
		(layer "B.Cu")
	)
	(gr_line
		(start 104.43845 -30.913324)
		(end 104.64419 -30.59684)
		(stroke
			(width 0.06223)
			(type default)
		)
		(layer "B.Cu")
	)
	(gr_line
		(start 104.51719 -31.283148)
		(end 104.833674 -31.488634)
		(stroke
			(width 0.06223)
			(type default)
		)
		(layer "B.Cu")
	)
	(gr_line
		(start 104.566466 -30.231588)
		(end 104.64419 -30.59684)
		(stroke
			(width 0.06223)
			(type default)
		)
		(layer "B.Cu")
	)
	(gr_line
		(start 104.596184 -50.649124)
		(end 104.596184 -50.790094)
		(stroke
			(width 0.04445)
			(type default)
		)
		(layer "B.Cu")
	)
	(gr_line
		(start 104.596184 -50.649124)
		(end 104.662986 -50.582322)
		(stroke
			(width 0.04445)
			(type default)
		)
		(layer "B.Cu")
	)
	(gr_line
		(start 104.621584 -111.000794)
		(end 104.63022 -111.041434)
		(stroke
			(width 0.06223)
			(type default)
		)
		(layer "B.Cu")
	)
	(gr_line
		(start 104.621584 -111.000794)
		(end 104.63022 -110.960408)
		(stroke
			(width 0.06223)
			(type default)
		)
		(layer "B.Cu")
	)
	(gr_line
		(start 104.63022 -110.959646)
		(end 104.63022 -110.9599)
		(stroke
			(width 0.06223)
			(type default)
		)
		(layer "B.Cu")
	)
	(gr_line
		(start 104.64546 -114.829082)
		(end 104.65435 -114.870992)
		(stroke
			(width 0.06223)
			(type default)
		)
		(layer "B.Cu")
	)
	(gr_line
		(start 104.64546 -114.829082)
		(end 104.654604 -114.786664)
		(stroke
			(width 0.06223)
			(type default)
		)
		(layer "B.Cu")
	)
	(gr_line
		(start 104.664764 -50.580544)
		(end 104.731566 -50.513742)
		(stroke
			(width 0.04445)
			(type default)
		)
		(layer "B.Cu")
	)
	(gr_line
		(start 104.67848 -111.267494)
		(end 104.684322 -111.295942)
		(stroke
			(width 0.06223)
			(type default)
		)
		(layer "B.Cu")
	)
	(gr_line
		(start 104.684322 -111.295942)
		(end 104.700578 -111.321088)
		(stroke
			(width 0.06223)
			(type default)
		)
		(layer "B.Cu")
	)
	(gr_line
		(start 104.684576 -110.70336)
		(end 104.690926 -110.673642)
		(stroke
			(width 0.06223)
			(type default)
		)
		(layer "B.Cu")
	)
	(gr_line
		(start 104.690926 -110.673642)
		(end 104.707436 -110.648242)
		(stroke
			(width 0.06223)
			(type default)
		)
		(layer "B.Cu")
	)
	(gr_line
		(start 104.704642 -114.552984)
		(end 104.710738 -114.52352)
		(stroke
			(width 0.06223)
			(type default)
		)
		(layer "B.Cu")
	)
	(gr_line
		(start 104.705658 -32.17037)
		(end 104.911144 -31.853886)
		(stroke
			(width 0.06223)
			(type default)
		)
		(layer "B.Cu")
	)
	(gr_line
		(start 104.705912 -115.113308)
		(end 104.712516 -115.144042)
		(stroke
			(width 0.06223)
			(type default)
		)
		(layer "B.Cu")
	)
	(gr_line
		(start 104.710738 -114.52352)
		(end 104.727502 -114.497612)
		(stroke
			(width 0.06223)
			(type default)
		)
		(layer "B.Cu")
	)
	(gr_line
		(start 104.712516 -115.144042)
		(end 104.729534 -115.170204)
		(stroke
			(width 0.06223)
			(type default)
		)
		(layer "B.Cu")
	)
	(gr_line
		(start 104.72293 -46.867572)
		(end 104.98963 -46.600872)
		(stroke
			(width 0.06223)
			(type default)
		)
		(layer "B.Cu")
	)
	(gr_line
		(start 104.72293 -45.960792)
		(end 104.98963 -46.227492)
		(stroke
			(width 0.06223)
			(type default)
		)
		(layer "B.Cu")
	)
	(gr_line
		(start 104.731566 -50.491644)
		(end 104.731566 -50.513742)
		(stroke
			(width 0.04445)
			(type default)
		)
		(layer "B.Cu")
	)
	(gr_line
		(start 104.784398 -32.540448)
		(end 105.100628 -32.745934)
		(stroke
			(width 0.06223)
			(type default)
		)
		(layer "B.Cu")
	)
	(gr_line
		(start 104.8258 -44.5008)
		(end 104.8258 -44.752768)
		(stroke
			(width 0.06223)
			(type default)
		)
		(layer "B.Cu")
	)
	(gr_line
		(start 104.833674 -31.488634)
		(end 104.911144 -31.853886)
		(stroke
			(width 0.06223)
			(type default)
		)
		(layer "B.Cu")
	)
	(gr_line
		(start 104.876346 -110.388146)
		(end 104.898952 -110.353348)
		(stroke
			(width 0.06223)
			(type default)
		)
		(layer "B.Cu")
	)
	(gr_line
		(start 104.898952 -110.353348)
		(end 104.93375 -110.330742)
		(stroke
			(width 0.06223)
			(type default)
		)
		(layer "B.Cu")
	)
	(gr_arc
		(start 104.911144 -55.40502)
		(mid 104.974006 -55.378982)
		(end 105.000044 -55.31612)
		(stroke
			(width 0.04445)
			(type default)
		)
		(layer "B.Cu")
	)
	(gr_line
		(start 104.92994 -115.480338)
		(end 104.930956 -115.482116)
		(stroke
			(width 0.06223)
			(type default)
		)
		(layer "B.Cu")
	)
	(gr_line
		(start 104.930956 -115.482116)
		(end 104.932988 -115.484148)
		(stroke
			(width 0.06223)
			(type default)
		)
		(layer "B.Cu")
	)
	(gr_line
		(start 104.939338 -111.690658)
		(end 104.939592 -111.690912)
		(stroke
			(width 0.06223)
			(type default)
		)
		(layer "B.Cu")
	)
	(gr_line
		(start 104.939592 -111.690912)
		(end 104.9401 -111.69142)
		(stroke
			(width 0.06223)
			(type default)
		)
		(layer "B.Cu")
	)
	(gr_line
		(start 104.964738 -114.130582)
		(end 104.987344 -114.095784)
		(stroke
			(width 0.06223)
			(type default)
		)
		(layer "B.Cu")
	)
	(gr_line
		(start 104.972866 -33.42767)
		(end 105.178352 -33.111186)
		(stroke
			(width 0.06223)
			(type default)
		)
		(layer "B.Cu")
	)
	(gr_line
		(start 104.987344 -114.095784)
		(end 105.022396 -114.072924)
		(stroke
			(width 0.06223)
			(type default)
		)
		(layer "B.Cu")
	)
	(gr_line
		(start 104.98963 -46.227492)
		(end 104.98963 -46.600872)
		(stroke
			(width 0.06223)
			(type default)
		)
		(layer "B.Cu")
	)
	(gr_line
		(start 105.000044 -116.249958)
		(end 105.220516 -115.838732)
		(stroke
			(width 0.06223)
			(type default)
		)
		(layer "B.Cu")
	)
	(gr_line
		(start 105.000044 -112.450118)
		(end 105.220516 -112.038892)
		(stroke
			(width 0.06223)
			(type default)
		)
		(layer "B.Cu")
	)
	(gr_arc
		(start 105.000044 -55.68442)
		(mid 104.974016 -55.62153)
		(end 104.911144 -55.59552)
		(stroke
			(width 0.04445)
			(type default)
		)
		(layer "B.Cu")
	)
	(gr_line
		(start 105.000044 -55.68442)
		(end 105.000044 -56.000142)
		(stroke
			(width 0.04445)
			(type default)
		)
		(layer "B.Cu")
	)
	(gr_line
		(start 105.000044 -55.000144)
		(end 105.000044 -55.31612)
		(stroke
			(width 0.04445)
			(type default)
		)
		(layer "B.Cu")
	)
	(gr_line
		(start 105.021126 -43.41622)
		(end 105.036874 -43.342306)
		(stroke
			(width 0.06223)
			(type default)
		)
		(layer "B.Cu")
	)
	(gr_line
		(start 105.100628 -32.745934)
		(end 105.178352 -33.111186)
		(stroke
			(width 0.06223)
			(type default)
		)
		(layer "B.Cu")
	)
	(gr_line
		(start 105.159556 -115.664742)
		(end 105.160572 -115.66525)
		(stroke
			(width 0.06223)
			(type default)
		)
		(layer "B.Cu")
	)
	(gr_line
		(start 105.159556 -111.864902)
		(end 105.160572 -111.86541)
		(stroke
			(width 0.06223)
			(type default)
		)
		(layer "B.Cu")
	)
	(gr_arc
		(start 105.220516 -115.838732)
		(mid 105.23005 -115.743882)
		(end 105.169716 -115.670076)
		(stroke
			(width 0.06223)
			(type default)
		)
		(layer "B.Cu")
	)
	(gr_arc
		(start 105.220516 -112.038892)
		(mid 105.230024 -111.944061)
		(end 105.169716 -111.870236)
		(stroke
			(width 0.06223)
			(type default)
		)
		(layer "B.Cu")
	)
	(gr_line
		(start 105.253028 -110.123224)
		(end 105.279444 -110.106206)
		(stroke
			(width 0.06223)
			(type default)
		)
		(layer "B.Cu")
	)
	(gr_line
		(start 105.253282 -113.923064)
		(end 105.279444 -113.906046)
		(stroke
			(width 0.06223)
			(type default)
		)
		(layer "B.Cu")
	)
	(gr_line
		(start 105.279444 -113.906046)
		(end 105.310178 -113.899442)
		(stroke
			(width 0.06223)
			(type default)
		)
		(layer "B.Cu")
	)
	(gr_line
		(start 105.279444 -110.106206)
		(end 105.310178 -110.099602)
		(stroke
			(width 0.06223)
			(type default)
		)
		(layer "B.Cu")
	)
	(gr_line
		(start 105.347262 -50.37709)
		(end 105.405174 -50.435002)
		(stroke
			(width 0.04445)
			(type default)
		)
		(layer "B.Cu")
	)
	(gr_line
		(start 105.347262 -50.354992)
		(end 105.347262 -50.37709)
		(stroke
			(width 0.04445)
			(type default)
		)
		(layer "B.Cu")
	)
	(gr_line
		(start 105.347262 -50.236628)
		(end 105.347262 -50.354992)
		(stroke
			(width 0.06223)
			(type default)
		)
		(layer "B.Cu")
	)
	(gr_line
		(start 105.357422 -115.309396)
		(end 105.36047 -115.31092)
		(stroke
			(width 0.06223)
			(type default)
		)
		(layer "B.Cu")
	)
	(gr_line
		(start 105.357422 -111.509556)
		(end 105.36047 -111.51108)
		(stroke
			(width 0.06223)
			(type default)
		)
		(layer "B.Cu")
	)
	(gr_arc
		(start 105.361232 -115.311428)
		(mid 105.456081 -115.320958)
		(end 105.529888 -115.260628)
		(stroke
			(width 0.06223)
			(type default)
		)
		(layer "B.Cu")
	)
	(gr_arc
		(start 105.361232 -111.511588)
		(mid 105.456081 -111.521118)
		(end 105.529888 -111.460788)
		(stroke
			(width 0.06223)
			(type default)
		)
		(layer "B.Cu")
	)
	(gr_line
		(start 105.409746 -35.576764)
		(end 105.418382 -35.53587)
		(stroke
			(width 0.06223)
			(type default)
		)
		(layer "B.Cu")
	)
	(gr_line
		(start 105.409746 -35.49523)
		(end 105.418382 -35.53587)
		(stroke
			(width 0.06223)
			(type default)
		)
		(layer "B.Cu")
	)
	(gr_line
		(start 105.529888 -115.260628)
		(end 105.750106 -114.84991)
		(stroke
			(width 0.06223)
			(type default)
		)
		(layer "B.Cu")
	)
	(gr_line
		(start 105.529888 -111.460788)
		(end 105.750106 -111.05007)
		(stroke
			(width 0.06223)
			(type default)
		)
		(layer "B.Cu")
	)
	(gr_line
		(start 105.532936 -30.79369)
		(end 105.704132 -31.598616)
		(stroke
			(width 0.06223)
			(type default)
		)
		(layer "B.Cu")
	)
	(gr_line
		(start 105.595674 -50.535078)
		(end 105.595674 -50.653442)
		(stroke
			(width 0.04445)
			(type default)
		)
		(layer "B.Cu")
	)
	(gr_line
		(start 105.598214 -50.532538)
		(end 105.753662 -50.37709)
		(stroke
			(width 0.04445)
			(type default)
		)
		(layer "B.Cu")
	)
	(gr_arc
		(start 105.681018 -3.096768)
		(mid 105.726674 -3.087651)
		(end 105.765346 -3.061716)
		(stroke
			(width 0.06223)
			(type default)
		)
		(layer "B.Cu")
	)
	(gr_line
		(start 105.753662 -50.354992)
		(end 105.753662 -50.37709)
		(stroke
			(width 0.04445)
			(type default)
		)
		(layer "B.Cu")
	)
	(gr_arc
		(start 105.765346 -3.061716)
		(mid 105.79112 -3.023143)
		(end 105.800144 -2.977642)
		(stroke
			(width 0.06223)
			(type default)
		)
		(layer "B.Cu")
	)
	(gr_line
		(start 105.791 -44.8564)
		(end 105.795826 -44.861226)
		(stroke
			(width 0.06223)
			(type default)
		)
		(layer "B.Cu")
	)
	(gr_line
		(start 105.791 -44.5008)
		(end 105.791 -44.8564)
		(stroke
			(width 0.06223)
			(type default)
		)
		(layer "B.Cu")
	)
	(gr_line
		(start 105.791 -43.812968)
		(end 105.791 -43.942)
		(stroke
			(width 0.06223)
			(type default)
		)
		(layer "B.Cu")
	)
	(gr_arc
		(start 105.800144 -3.622294)
		(mid 105.791095 -3.576804)
		(end 105.765346 -3.53822)
		(stroke
			(width 0.06223)
			(type default)
		)
		(layer "B.Cu")
	)
	(gr_line
		(start 105.800144 -3.622294)
		(end 105.800144 -3.999992)
		(stroke
			(width 0.06223)
			(type default)
		)
		(layer "B.Cu")
	)
	(gr_line
		(start 105.800144 -2.600198)
		(end 105.800144 -2.977642)
		(stroke
			(width 0.06223)
			(type default)
		)
		(layer "B.Cu")
	)
	(gr_line
		(start 105.800398 -32.051244)
		(end 105.97134 -32.855916)
		(stroke
			(width 0.06223)
			(type default)
		)
		(layer "B.Cu")
	)
	(gr_line
		(start 105.837736 -45.837602)
		(end 105.837736 -45.931582)
		(stroke
			(width 0.06223)
			(type default)
		)
		(layer "B.Cu")
	)
	(gr_arc
		(start 105.911142 -55.40502)
		(mid 105.974004 -55.378982)
		(end 106.000042 -55.31612)
		(stroke
			(width 0.04445)
			(type default)
		)
		(layer "B.Cu")
	)
	(gr_line
		(start 105.92435 -30.667452)
		(end 106.24058 -30.872938)
		(stroke
			(width 0.06223)
			(type default)
		)
		(layer "B.Cu")
	)
	(gr_arc
		(start 106.000042 -55.68442)
		(mid 105.974013 -55.62153)
		(end 105.911142 -55.59552)
		(stroke
			(width 0.04445)
			(type default)
		)
		(layer "B.Cu")
	)
	(gr_line
		(start 106.000042 -55.68442)
		(end 106.000042 -56.000142)
		(stroke
			(width 0.04445)
			(type default)
		)
		(layer "B.Cu")
	)
	(gr_line
		(start 106.000042 -55.000144)
		(end 106.000042 -55.31612)
		(stroke
			(width 0.04445)
			(type default)
		)
		(layer "B.Cu")
	)
	(gr_line
		(start 106.06786 -33.30956)
		(end 106.238548 -34.112962)
		(stroke
			(width 0.06223)
			(type default)
		)
		(layer "B.Cu")
	)
	(gr_line
		(start 106.112818 -31.554674)
		(end 106.318304 -31.23819)
		(stroke
			(width 0.06223)
			(type default)
		)
		(layer "B.Cu")
	)
	(gr_line
		(start 106.191558 -31.924752)
		(end 106.507788 -32.129984)
		(stroke
			(width 0.06223)
			(type default)
		)
		(layer "B.Cu")
	)
	(gr_line
		(start 106.24058 -30.872938)
		(end 106.318304 -31.23819)
		(stroke
			(width 0.06223)
			(type default)
		)
		(layer "B.Cu")
	)
	(gr_line
		(start 106.246676 -46.337982)
		(end 106.513376 -46.071282)
		(stroke
			(width 0.06223)
			(type default)
		)
		(layer "B.Cu")
	)
	(gr_line
		(start 106.246676 -45.431202)
		(end 106.513376 -45.697902)
		(stroke
			(width 0.06223)
			(type default)
		)
		(layer "B.Cu")
	)
	(gr_line
		(start 106.3498 -44.5008)
		(end 106.3498 -44.88561)
		(stroke
			(width 0.06223)
			(type default)
		)
		(layer "B.Cu")
	)
	(gr_line
		(start 106.3498 -43.829478)
		(end 106.3498 -43.942)
		(stroke
			(width 0.06223)
			(type default)
		)
		(layer "B.Cu")
	)
	(gr_line
		(start 106.380026 -32.81172)
		(end 106.585512 -32.495236)
		(stroke
			(width 0.06223)
			(type default)
		)
		(layer "B.Cu")
	)
	(gr_line
		(start 106.458766 -33.181798)
		(end 106.774996 -33.387284)
		(stroke
			(width 0.06223)
			(type default)
		)
		(layer "B.Cu")
	)
	(gr_line
		(start 106.462322 -43.36415)
		(end 106.47807 -43.290236)
		(stroke
			(width 0.06223)
			(type default)
		)
		(layer "B.Cu")
	)
	(gr_line
		(start 106.507788 -32.129984)
		(end 106.585512 -32.495236)
		(stroke
			(width 0.06223)
			(type default)
		)
		(layer "B.Cu")
	)
	(gr_line
		(start 106.513376 -45.697902)
		(end 106.513376 -46.071282)
		(stroke
			(width 0.06223)
			(type default)
		)
		(layer "B.Cu")
	)
	(gr_line
		(start 106.647234 -34.06902)
		(end 106.85272 -33.752536)
		(stroke
			(width 0.06223)
			(type default)
		)
		(layer "B.Cu")
	)
	(gr_line
		(start 106.774996 -33.387284)
		(end 106.85272 -33.752536)
		(stroke
			(width 0.06223)
			(type default)
		)
		(layer "B.Cu")
	)
	(gr_line
		(start 106.816906 -34.960306)
		(end 106.825542 -34.919412)
		(stroke
			(width 0.06223)
			(type default)
		)
		(layer "B.Cu")
	)
	(gr_line
		(start 106.816906 -34.878772)
		(end 106.825542 -34.919412)
		(stroke
			(width 0.06223)
			(type default)
		)
		(layer "B.Cu")
	)
	(gr_arc
		(start 106.91114 -55.40502)
		(mid 106.974002 -55.378982)
		(end 107.00004 -55.31612)
		(stroke
			(width 0.04445)
			(type default)
		)
		(layer "B.Cu")
	)
	(gr_arc
		(start 107.00004 -55.68442)
		(mid 106.974011 -55.621531)
		(end 106.91114 -55.59552)
		(stroke
			(width 0.04445)
			(type default)
		)
		(layer "B.Cu")
	)
	(gr_line
		(start 107.00004 -55.68442)
		(end 107.00004 -56.000142)
		(stroke
			(width 0.04445)
			(type default)
		)
		(layer "B.Cu")
	)
	(gr_line
		(start 107.00004 -55.000144)
		(end 107.00004 -55.31612)
		(stroke
			(width 0.04445)
			(type default)
		)
		(layer "B.Cu")
	)
	(gr_line
		(start 107.08767 -30.805882)
		(end 107.25912 -31.61284)
		(stroke
			(width 0.06223)
			(type default)
		)
		(layer "B.Cu")
	)
	(gr_line
		(start 107.315 -44.5008)
		(end 107.315 -44.879768)
		(stroke
			(width 0.06223)
			(type default)
		)
		(layer "B.Cu")
	)
	(gr_line
		(start 107.329478 -50.690018)
		(end 107.386882 -50.747422)
		(stroke
			(width 0.04445)
			(type default)
		)
		(layer "B.Cu")
	)
	(gr_line
		(start 107.329478 -50.566828)
		(end 107.329478 -50.690018)
		(stroke
			(width 0.06223)
			(type default)
		)
		(layer "B.Cu")
	)
	(gr_line
		(start 107.355132 -32.063436)
		(end 107.526328 -32.869124)
		(stroke
			(width 0.06223)
			(type default)
		)
		(layer "B.Cu")
	)
	(gr_line
		(start 107.355894 -45.796708)
		(end 107.355894 -45.890688)
		(stroke
			(width 0.06223)
			(type default)
		)
		(layer "B.Cu")
	)
	(gr_line
		(start 107.38866 -50.7492)
		(end 107.40517 -50.76571)
		(stroke
			(width 0.04445)
			(type default)
		)
		(layer "B.Cu")
	)
	(gr_line
		(start 107.479338 -30.680914)
		(end 107.795822 -30.8864)
		(stroke
			(width 0.06223)
			(type default)
		)
		(layer "B.Cu")
	)
	(gr_arc
		(start 107.480862 -4.296918)
		(mid 107.526518 -4.287801)
		(end 107.56519 -4.261866)
		(stroke
			(width 0.06223)
			(type default)
		)
		(layer "B.Cu")
	)
	(gr_arc
		(start 107.56519 -4.73837)
		(mid 107.52652 -4.712435)
		(end 107.480862 -4.703318)
		(stroke
			(width 0.06223)
			(type default)
		)
		(layer "B.Cu")
	)
	(gr_arc
		(start 107.56519 -4.261866)
		(mid 107.590964 -4.223293)
		(end 107.599988 -4.177792)
		(stroke
			(width 0.06223)
			(type default)
		)
		(layer "B.Cu")
	)
	(gr_line
		(start 107.59567 -50.81143)
		(end 107.59567 -50.988468)
		(stroke
			(width 0.04445)
			(type default)
		)
		(layer "B.Cu")
	)
	(gr_line
		(start 107.59567 -50.81143)
		(end 107.6579 -50.7492)
		(stroke
			(width 0.04445)
			(type default)
		)
		(layer "B.Cu")
	)
	(gr_arc
		(start 107.599988 -4.822444)
		(mid 107.590976 -4.776933)
		(end 107.56519 -4.73837)
		(stroke
			(width 0.06223)
			(type default)
		)
		(layer "B.Cu")
	)
	(gr_line
		(start 107.599988 -4.822444)
		(end 107.599988 -5.200142)
		(stroke
			(width 0.06223)
			(type default)
		)
		(layer "B.Cu")
	)
	(gr_line
		(start 107.599988 -3.800094)
		(end 107.599988 -4.177792)
		(stroke
			(width 0.06223)
			(type default)
		)
		(layer "B.Cu")
	)
	(gr_line
		(start 107.622594 -33.321244)
		(end 107.793536 -34.126678)
		(stroke
			(width 0.06223)
			(type default)
		)
		(layer "B.Cu")
	)
	(gr_line
		(start 107.659678 -50.747422)
		(end 107.735878 -50.671222)
		(stroke
			(width 0.04445)
			(type default)
		)
		(layer "B.Cu")
	)
	(gr_line
		(start 107.667806 -31.56839)
		(end 107.873292 -31.251652)
		(stroke
			(width 0.06223)
			(type default)
		)
		(layer "B.Cu")
	)
	(gr_line
		(start 107.746546 -31.938214)
		(end 108.06303 -32.1437)
		(stroke
			(width 0.06223)
			(type default)
		)
		(layer "B.Cu")
	)
	(gr_line
		(start 107.764834 -46.297088)
		(end 108.031534 -46.030388)
		(stroke
			(width 0.06223)
			(type default)
		)
		(layer "B.Cu")
	)
	(gr_line
		(start 107.764834 -45.390308)
		(end 108.031534 -45.657008)
		(stroke
			(width 0.06223)
			(type default)
		)
		(layer "B.Cu")
	)
	(gr_line
		(start 107.795822 -30.8864)
		(end 107.873292 -31.251652)
		(stroke
			(width 0.06223)
			(type default)
		)
		(layer "B.Cu")
	)
	(gr_line
		(start 107.8738 -44.5008)
		(end 107.8738 -44.879768)
		(stroke
			(width 0.06223)
			(type default)
		)
		(layer "B.Cu")
	)
	(gr_arc
		(start 107.911138 -55.40502)
		(mid 107.974 -55.378982)
		(end 108.000038 -55.31612)
		(stroke
			(width 0.04445)
			(type default)
		)
		(layer "B.Cu")
	)
	(gr_line
		(start 107.935014 -32.825436)
		(end 108.1405 -32.508952)
		(stroke
			(width 0.06223)
			(type default)
		)
		(layer "B.Cu")
	)
	(gr_arc
		(start 108.000038 -55.68442)
		(mid 107.974009 -55.621532)
		(end 107.911138 -55.59552)
		(stroke
			(width 0.04445)
			(type default)
		)
		(layer "B.Cu")
	)
	(gr_line
		(start 108.000038 -55.68442)
		(end 108.000038 -56.000142)
		(stroke
			(width 0.04445)
			(type default)
		)
		(layer "B.Cu")
	)
	(gr_line
		(start 108.000038 -55.000144)
		(end 108.000038 -55.31612)
		(stroke
			(width 0.04445)
			(type default)
		)
		(layer "B.Cu")
	)
	(gr_line
		(start 108.013754 -33.19526)
		(end 108.330238 -33.400746)
		(stroke
			(width 0.06223)
			(type default)
		)
		(layer "B.Cu")
	)
	(gr_line
		(start 108.031534 -45.657008)
		(end 108.031534 -46.030388)
		(stroke
			(width 0.06223)
			(type default)
		)
		(layer "B.Cu")
	)
	(gr_line
		(start 108.06303 -32.1437)
		(end 108.1405 -32.508952)
		(stroke
			(width 0.06223)
			(type default)
		)
		(layer "B.Cu")
	)
	(gr_line
		(start 108.202476 -34.082228)
		(end 108.407708 -33.765998)
		(stroke
			(width 0.06223)
			(type default)
		)
		(layer "B.Cu")
	)
	(gr_line
		(start 108.289344 -29.196792)
		(end 108.46054 -30.001972)
		(stroke
			(width 0.06223)
			(type default)
		)
		(layer "B.Cu")
	)
	(gr_line
		(start 108.308648 -34.676334)
		(end 108.317284 -34.63544)
		(stroke
			(width 0.06223)
			(type default)
		)
		(layer "B.Cu")
	)
	(gr_line
		(start 108.308648 -34.5948)
		(end 108.317284 -34.63544)
		(stroke
			(width 0.06223)
			(type default)
		)
		(layer "B.Cu")
	)
	(gr_line
		(start 108.330238 -33.400746)
		(end 108.407708 -33.765998)
		(stroke
			(width 0.06223)
			(type default)
		)
		(layer "B.Cu")
	)
	(gr_line
		(start 108.333794 -50.655474)
		(end 108.400596 -50.722276)
		(stroke
			(width 0.04445)
			(type default)
		)
		(layer "B.Cu")
	)
	(gr_line
		(start 108.333794 -50.633376)
		(end 108.333794 -50.655474)
		(stroke
			(width 0.04445)
			(type default)
		)
		(layer "B.Cu")
	)
	(gr_line
		(start 108.333794 -50.50282)
		(end 108.333794 -50.633376)
		(stroke
			(width 0.06223)
			(type default)
		)
		(layer "B.Cu")
	)
	(gr_line
		(start 108.402374 -50.724054)
		(end 108.403898 -50.725578)
		(stroke
			(width 0.04445)
			(type default)
		)
		(layer "B.Cu")
	)
	(gr_line
		(start 108.556552 -30.453838)
		(end 108.728002 -31.260034)
		(stroke
			(width 0.06223)
			(type default)
		)
		(layer "B.Cu")
	)
	(gr_line
		(start 108.594398 -50.80127)
		(end 108.594398 -50.931826)
		(stroke
			(width 0.04445)
			(type default)
		)
		(layer "B.Cu")
	)
	(gr_line
		(start 108.594398 -50.80127)
		(end 108.671614 -50.724054)
		(stroke
			(width 0.04445)
			(type default)
		)
		(layer "B.Cu")
	)
	(gr_line
		(start 108.673392 -50.722276)
		(end 108.740194 -50.655474)
		(stroke
			(width 0.04445)
			(type default)
		)
		(layer "B.Cu")
	)
	(gr_line
		(start 108.680758 -29.071062)
		(end 108.997242 -29.276548)
		(stroke
			(width 0.06223)
			(type default)
		)
		(layer "B.Cu")
	)
	(gr_line
		(start 108.740194 -50.633376)
		(end 108.740194 -50.655474)
		(stroke
			(width 0.04445)
			(type default)
		)
		(layer "B.Cu")
	)
	(gr_line
		(start 108.823506 -31.70936)
		(end 108.99521 -32.51708)
		(stroke
			(width 0.06223)
			(type default)
		)
		(layer "B.Cu")
	)
	(gr_line
		(start 108.839 -44.5008)
		(end 108.839 -44.879768)
		(stroke
			(width 0.06223)
			(type default)
		)
		(layer "B.Cu")
	)
	(gr_line
		(start 108.86948 -29.95803)
		(end 109.074966 -29.6418)
		(stroke
			(width 0.06223)
			(type default)
		)
		(layer "B.Cu")
	)
	(gr_line
		(start 108.899452 -45.785278)
		(end 108.899452 -45.879258)
		(stroke
			(width 0.06223)
			(type default)
		)
		(layer "B.Cu")
	)
	(gr_arc
		(start 108.911136 -55.40502)
		(mid 108.973998 -55.378982)
		(end 109.000036 -55.31612)
		(stroke
			(width 0.04445)
			(type default)
		)
		(layer "B.Cu")
	)
	(gr_line
		(start 108.911644 -41.876218)
		(end 108.913676 -41.866312)
		(stroke
			(width 0.06223)
			(type default)
		)
		(layer "B.Cu")
	)
	(gr_line
		(start 108.947966 -30.328108)
		(end 109.26445 -30.533594)
		(stroke
			(width 0.06223)
			(type default)
		)
		(layer "B.Cu")
	)
	(gr_line
		(start 108.997242 -29.276548)
		(end 109.074966 -29.6418)
		(stroke
			(width 0.06223)
			(type default)
		)
		(layer "B.Cu")
	)
	(gr_arc
		(start 109.000036 -55.68442)
		(mid 108.974007 -55.621533)
		(end 108.911136 -55.59552)
		(stroke
			(width 0.04445)
			(type default)
		)
		(layer "B.Cu")
	)
	(gr_line
		(start 109.000036 -55.68442)
		(end 109.000036 -56.000142)
		(stroke
			(width 0.04445)
			(type default)
		)
		(layer "B.Cu")
	)
	(gr_line
		(start 109.000036 -55.000144)
		(end 109.000036 -55.31612)
		(stroke
			(width 0.04445)
			(type default)
		)
		(layer "B.Cu")
	)
	(gr_line
		(start 109.136688 -31.215584)
		(end 109.342174 -30.898846)
		(stroke
			(width 0.06223)
			(type default)
		)
		(layer "B.Cu")
	)
	(gr_line
		(start 109.215428 -31.585408)
		(end 109.531912 -31.790894)
		(stroke
			(width 0.06223)
			(type default)
		)
		(layer "B.Cu")
	)
	(gr_line
		(start 109.26445 -30.533594)
		(end 109.342174 -30.898846)
		(stroke
			(width 0.06223)
			(type default)
		)
		(layer "B.Cu")
	)
	(gr_arc
		(start 109.28096 -3.096768)
		(mid 109.326616 -3.087651)
		(end 109.365288 -3.061716)
		(stroke
			(width 0.06223)
			(type default)
		)
		(layer "B.Cu")
	)
	(gr_line
		(start 109.308392 -46.285658)
		(end 109.575092 -46.018958)
		(stroke
			(width 0.06223)
			(type default)
		)
		(layer "B.Cu")
	)
	(gr_line
		(start 109.308392 -45.378878)
		(end 109.575092 -45.645578)
		(stroke
			(width 0.06223)
			(type default)
		)
		(layer "B.Cu")
	)
	(gr_line
		(start 109.33557 -50.634646)
		(end 109.402372 -50.701448)
		(stroke
			(width 0.04445)
			(type default)
		)
		(layer "B.Cu")
	)
	(gr_line
		(start 109.33557 -50.612548)
		(end 109.33557 -50.634646)
		(stroke
			(width 0.04445)
			(type default)
		)
		(layer "B.Cu")
	)
	(gr_line
		(start 109.33557 -50.482246)
		(end 109.33557 -50.612548)
		(stroke
			(width 0.06223)
			(type default)
		)
		(layer "B.Cu")
	)
	(gr_arc
		(start 109.365288 -3.53822)
		(mid 109.326621 -3.512275)
		(end 109.28096 -3.503168)
		(stroke
			(width 0.06223)
			(type default)
		)
		(layer "B.Cu")
	)
	(gr_arc
		(start 109.365288 -3.061716)
		(mid 109.391062 -3.023143)
		(end 109.400086 -2.977642)
		(stroke
			(width 0.06223)
			(type default)
		)
		(layer "B.Cu")
	)
	(gr_line
		(start 109.3978 -44.5008)
		(end 109.3978 -44.879768)
		(stroke
			(width 0.06223)
			(type default)
		)
		(layer "B.Cu")
	)
	(gr_arc
		(start 109.400086 -3.622294)
		(mid 109.391057 -3.576794)
		(end 109.365288 -3.53822)
		(stroke
			(width 0.06223)
			(type default)
		)
		(layer "B.Cu")
	)
	(gr_line
		(start 109.400086 -3.622294)
		(end 109.400086 -3.999992)
		(stroke
			(width 0.06223)
			(type default)
		)
		(layer "B.Cu")
	)
	(gr_line
		(start 109.400086 -2.600198)
		(end 109.400086 -2.977642)
		(stroke
			(width 0.06223)
			(type default)
		)
		(layer "B.Cu")
	)
	(gr_line
		(start 109.40415 -50.703226)
		(end 109.40542 -50.704496)
		(stroke
			(width 0.04445)
			(type default)
		)
		(layer "B.Cu")
	)
	(gr_line
		(start 109.40415 -32.472376)
		(end 109.609636 -32.156146)
		(stroke
			(width 0.06223)
			(type default)
		)
		(layer "B.Cu")
	)
	(gr_line
		(start 109.531912 -31.790894)
		(end 109.609636 -32.156146)
		(stroke
			(width 0.06223)
			(type default)
		)
		(layer "B.Cu")
	)
	(gr_line
		(start 109.575092 -45.645578)
		(end 109.575092 -46.018958)
		(stroke
			(width 0.06223)
			(type default)
		)
		(layer "B.Cu")
	)
	(gr_line
		(start 109.59592 -50.780696)
		(end 109.59592 -50.910998)
		(stroke
			(width 0.04445)
			(type default)
		)
		(layer "B.Cu")
	)
	(gr_line
		(start 109.59592 -50.780696)
		(end 109.67339 -50.703226)
		(stroke
			(width 0.04445)
			(type default)
		)
		(layer "B.Cu")
	)
	(gr_line
		(start 109.675168 -50.701448)
		(end 109.74197 -50.634646)
		(stroke
			(width 0.04445)
			(type default)
		)
		(layer "B.Cu")
	)
	(gr_line
		(start 109.70387 -33.975294)
		(end 109.712506 -33.934908)
		(stroke
			(width 0.06223)
			(type default)
		)
		(layer "B.Cu")
	)
	(gr_line
		(start 109.70387 -33.894268)
		(end 109.712506 -33.934908)
		(stroke
			(width 0.06223)
			(type default)
		)
		(layer "B.Cu")
	)
	(gr_line
		(start 109.710982 -28.667964)
		(end 109.881162 -29.469334)
		(stroke
			(width 0.06223)
			(type default)
		)
		(layer "B.Cu")
	)
	(gr_line
		(start 109.74197 -50.612548)
		(end 109.74197 -50.634646)
		(stroke
			(width 0.04445)
			(type default)
		)
		(layer "B.Cu")
	)
	(gr_arc
		(start 109.911134 -55.40502)
		(mid 109.973981 -55.378971)
		(end 110.000034 -55.31612)
		(stroke
			(width 0.04445)
			(type default)
		)
		(layer "B.Cu")
	)
	(gr_line
		(start 109.978444 -29.926026)
		(end 110.14837 -30.726126)
		(stroke
			(width 0.06223)
			(type default)
		)
		(layer "B.Cu")
	)
	(gr_arc
		(start 110.000034 -55.68442)
		(mid 109.974005 -55.621533)
		(end 109.911134 -55.59552)
		(stroke
			(width 0.04445)
			(type default)
		)
		(layer "B.Cu")
	)
	(gr_line
		(start 110.000034 -55.68442)
		(end 110.000034 -56.000142)
		(stroke
			(width 0.04445)
			(type default)
		)
		(layer "B.Cu")
	)
	(gr_line
		(start 110.000034 -55.000144)
		(end 110.000034 -55.31612)
		(stroke
			(width 0.04445)
			(type default)
		)
		(layer "B.Cu")
	)
	(gr_line
		(start 110.101888 -28.54071)
		(end 110.418118 -28.746196)
		(stroke
			(width 0.06223)
			(type default)
		)
		(layer "B.Cu")
	)
	(gr_line
		(start 110.245144 -31.18231)
		(end 110.415832 -31.985458)
		(stroke
			(width 0.06223)
			(type default)
		)
		(layer "B.Cu")
	)
	(gr_line
		(start 110.290356 -29.427678)
		(end 110.495842 -29.111194)
		(stroke
			(width 0.06223)
			(type default)
		)
		(layer "B.Cu")
	)
	(gr_line
		(start 110.363 -44.5008)
		(end 110.363 -44.879768)
		(stroke
			(width 0.06223)
			(type default)
		)
		(layer "B.Cu")
	)
	(gr_line
		(start 110.368842 -29.797756)
		(end 110.685326 -30.003242)
		(stroke
			(width 0.06223)
			(type default)
		)
		(layer "B.Cu")
	)
	(gr_line
		(start 110.415578 -45.738288)
		(end 110.415578 -45.832268)
		(stroke
			(width 0.06223)
			(type default)
		)
		(layer "B.Cu")
	)
	(gr_line
		(start 110.418118 -28.746196)
		(end 110.495842 -29.111194)
		(stroke
			(width 0.06223)
			(type default)
		)
		(layer "B.Cu")
	)
	(gr_line
		(start 110.55731 -30.685232)
		(end 110.762796 -30.368494)
		(stroke
			(width 0.06223)
			(type default)
		)
		(layer "B.Cu")
	)
	(gr_line
		(start 110.63605 -31.055056)
		(end 110.952534 -31.260542)
		(stroke
			(width 0.06223)
			(type default)
		)
		(layer "B.Cu")
	)
	(gr_line
		(start 110.685326 -30.003242)
		(end 110.762796 -30.368494)
		(stroke
			(width 0.06223)
			(type default)
		)
		(layer "B.Cu")
	)
	(gr_line
		(start 110.824518 -46.238668)
		(end 111.091218 -45.971968)
		(stroke
			(width 0.06223)
			(type default)
		)
		(layer "B.Cu")
	)
	(gr_line
		(start 110.824518 -45.331888)
		(end 111.091218 -45.598588)
		(stroke
			(width 0.06223)
			(type default)
		)
		(layer "B.Cu")
	)
	(gr_line
		(start 110.824518 -31.942532)
		(end 111.030004 -31.625794)
		(stroke
			(width 0.06223)
			(type default)
		)
		(layer "B.Cu")
	)
	(gr_arc
		(start 110.911132 -55.40502)
		(mid 110.97398 -55.378972)
		(end 111.000032 -55.31612)
		(stroke
			(width 0.04445)
			(type default)
		)
		(layer "B.Cu")
	)
	(gr_line
		(start 110.9218 -44.5008)
		(end 110.9218 -44.879768)
		(stroke
			(width 0.06223)
			(type default)
		)
		(layer "B.Cu")
	)
	(gr_line
		(start 110.952534 -31.260542)
		(end 111.030004 -31.625794)
		(stroke
			(width 0.06223)
			(type default)
		)
		(layer "B.Cu")
	)
	(gr_arc
		(start 111.000032 -55.68442)
		(mid 110.973994 -55.621558)
		(end 110.911132 -55.59552)
		(stroke
			(width 0.04445)
			(type default)
		)
		(layer "B.Cu")
	)
	(gr_line
		(start 111.000032 -55.68442)
		(end 111.000032 -56.000142)
		(stroke
			(width 0.04445)
			(type default)
		)
		(layer "B.Cu")
	)
	(gr_line
		(start 111.000032 -55.000144)
		(end 111.000032 -55.31612)
		(stroke
			(width 0.04445)
			(type default)
		)
		(layer "B.Cu")
	)
	(gr_line
		(start 111.014002 -50.067972)
		(end 111.080804 -50.134774)
		(stroke
			(width 0.04445)
			(type default)
		)
		(layer "B.Cu")
	)
	(gr_line
		(start 111.014002 -50.045874)
		(end 111.014002 -50.067972)
		(stroke
			(width 0.04445)
			(type default)
		)
		(layer "B.Cu")
	)
	(gr_arc
		(start 111.081058 -4.296918)
		(mid 111.126714 -4.287801)
		(end 111.165386 -4.261866)
		(stroke
			(width 0.06223)
			(type default)
		)
		(layer "B.Cu")
	)
	(gr_line
		(start 111.082582 -50.136552)
		(end 111.121952 -50.175922)
		(stroke
			(width 0.04445)
			(type default)
		)
		(layer "B.Cu")
	)
	(gr_line
		(start 111.091218 -45.598588)
		(end 111.091218 -45.971968)
		(stroke
			(width 0.06223)
			(type default)
		)
		(layer "B.Cu")
	)
	(gr_line
		(start 111.121698 -33.434274)
		(end 111.130334 -33.39338)
		(stroke
			(width 0.06223)
			(type default)
		)
		(layer "B.Cu")
	)
	(gr_line
		(start 111.121698 -33.35274)
		(end 111.130334 -33.39338)
		(stroke
			(width 0.06223)
			(type default)
		)
		(layer "B.Cu")
	)
	(gr_arc
		(start 111.165386 -4.261866)
		(mid 111.19116 -4.223293)
		(end 111.200184 -4.177792)
		(stroke
			(width 0.06223)
			(type default)
		)
		(layer "B.Cu")
	)
	(gr_arc
		(start 111.200184 -4.822444)
		(mid 111.191135 -4.776954)
		(end 111.165386 -4.73837)
		(stroke
			(width 0.06223)
			(type default)
		)
		(layer "B.Cu")
	)
	(gr_line
		(start 111.200184 -4.822444)
		(end 111.200184 -5.200142)
		(stroke
			(width 0.06223)
			(type default)
		)
		(layer "B.Cu")
	)
	(gr_line
		(start 111.200184 -3.800094)
		(end 111.200184 -4.177792)
		(stroke
			(width 0.06223)
			(type default)
		)
		(layer "B.Cu")
	)
	(gr_line
		(start 111.312452 -50.175922)
		(end 111.351822 -50.136552)
		(stroke
			(width 0.04445)
			(type default)
		)
		(layer "B.Cu")
	)
	(gr_line
		(start 111.3536 -50.134774)
		(end 111.420402 -50.067972)
		(stroke
			(width 0.04445)
			(type default)
		)
		(layer "B.Cu")
	)
	(gr_line
		(start 111.374428 -28.63088)
		(end 111.545116 -29.433266)
		(stroke
			(width 0.06223)
			(type default)
		)
		(layer "B.Cu")
	)
	(gr_line
		(start 111.420402 -50.045874)
		(end 111.420402 -50.067972)
		(stroke
			(width 0.04445)
			(type default)
		)
		(layer "B.Cu")
	)
	(gr_line
		(start 111.641382 -29.887164)
		(end 111.812324 -30.691074)
		(stroke
			(width 0.06223)
			(type default)
		)
		(layer "B.Cu")
	)
	(gr_line
		(start 111.765588 -28.50388)
		(end 112.081818 -28.709112)
		(stroke
			(width 0.06223)
			(type default)
		)
		(layer "B.Cu")
	)
	(gr_line
		(start 111.887 -44.5008)
		(end 111.887 -44.879768)
		(stroke
			(width 0.06223)
			(type default)
		)
		(layer "B.Cu")
	)
	(gr_line
		(start 111.90859 -31.14421)
		(end 112.079532 -31.948628)
		(stroke
			(width 0.06223)
			(type default)
		)
		(layer "B.Cu")
	)
	(gr_arc
		(start 111.91113 -55.40502)
		(mid 111.973979 -55.378972)
		(end 112.00003 -55.31612)
		(stroke
			(width 0.04445)
			(type default)
		)
		(layer "B.Cu")
	)
	(gr_line
		(start 111.939578 -45.738288)
		(end 111.939578 -45.832268)
		(stroke
			(width 0.06223)
			(type default)
		)
		(layer "B.Cu")
	)
	(gr_line
		(start 111.954056 -29.390594)
		(end 112.159542 -29.074364)
		(stroke
			(width 0.06223)
			(type default)
		)
		(layer "B.Cu")
	)
	(gr_arc
		(start 112.00003 -55.68442)
		(mid 111.973992 -55.621558)
		(end 111.91113 -55.59552)
		(stroke
			(width 0.04445)
			(type default)
		)
		(layer "B.Cu")
	)
	(gr_line
		(start 112.00003 -55.68442)
		(end 112.00003 -56.000142)
		(stroke
			(width 0.04445)
			(type default)
		)
		(layer "B.Cu")
	)
	(gr_line
		(start 112.00003 -55.000144)
		(end 112.00003 -55.31612)
		(stroke
			(width 0.04445)
			(type default)
		)
		(layer "B.Cu")
	)
	(gr_line
		(start 112.032542 -29.760672)
		(end 112.349026 -29.966412)
		(stroke
			(width 0.06223)
			(type default)
		)
		(layer "B.Cu")
	)
	(gr_line
		(start 112.081818 -28.709112)
		(end 112.159542 -29.074364)
		(stroke
			(width 0.06223)
			(type default)
		)
		(layer "B.Cu")
	)
	(gr_line
		(start 112.195102 -50.067972)
		(end 112.261904 -50.134774)
		(stroke
			(width 0.04445)
			(type default)
		)
		(layer "B.Cu")
	)
	(gr_line
		(start 112.195102 -50.045874)
		(end 112.195102 -50.067972)
		(stroke
			(width 0.04445)
			(type default)
		)
		(layer "B.Cu")
	)
	(gr_line
		(start 112.221264 -30.647894)
		(end 112.42675 -30.33141)
		(stroke
			(width 0.06223)
			(type default)
		)
		(layer "B.Cu")
	)
	(gr_line
		(start 112.263682 -50.136552)
		(end 112.303052 -50.175922)
		(stroke
			(width 0.04445)
			(type default)
		)
		(layer "B.Cu")
	)
	(gr_line
		(start 112.29975 -31.017718)
		(end 112.616234 -31.223458)
		(stroke
			(width 0.06223)
			(type default)
		)
		(layer "B.Cu")
	)
	(gr_line
		(start 112.348518 -46.238668)
		(end 112.615218 -45.971968)
		(stroke
			(width 0.06223)
			(type default)
		)
		(layer "B.Cu")
	)
	(gr_line
		(start 112.348518 -45.331888)
		(end 112.615218 -45.598588)
		(stroke
			(width 0.06223)
			(type default)
		)
		(layer "B.Cu")
	)
	(gr_line
		(start 112.349026 -29.966412)
		(end 112.42675 -30.33141)
		(stroke
			(width 0.06223)
			(type default)
		)
		(layer "B.Cu")
	)
	(gr_line
		(start 112.404144 -50.776124)
		(end 112.404144 -50.786538)
		(stroke
			(width 0.04445)
			(type default)
		)
		(layer "B.Cu")
	)
	(gr_line
		(start 112.4458 -44.5008)
		(end 112.4458 -44.879768)
		(stroke
			(width 0.06223)
			(type default)
		)
		(layer "B.Cu")
	)
	(gr_line
		(start 112.488218 -31.905194)
		(end 112.693704 -31.58871)
		(stroke
			(width 0.06223)
			(type default)
		)
		(layer "B.Cu")
	)
	(gr_line
		(start 112.493552 -50.585624)
		(end 112.493552 -50.596038)
		(stroke
			(width 0.04445)
			(type default)
		)
		(layer "B.Cu")
	)
	(gr_line
		(start 112.493552 -50.175922)
		(end 112.532922 -50.136552)
		(stroke
			(width 0.04445)
			(type default)
		)
		(layer "B.Cu")
	)
	(gr_line
		(start 112.5347 -50.134774)
		(end 112.601502 -50.067972)
		(stroke
			(width 0.04445)
			(type default)
		)
		(layer "B.Cu")
	)
	(gr_line
		(start 112.601502 -50.045874)
		(end 112.601502 -50.067972)
		(stroke
			(width 0.04445)
			(type default)
		)
		(layer "B.Cu")
	)
	(gr_line
		(start 112.615218 -45.598588)
		(end 112.615218 -45.971968)
		(stroke
			(width 0.06223)
			(type default)
		)
		(layer "B.Cu")
	)
	(gr_line
		(start 112.616234 -31.223458)
		(end 112.693704 -31.58871)
		(stroke
			(width 0.06223)
			(type default)
		)
		(layer "B.Cu")
	)
	(gr_line
		(start 112.691672 -32.954722)
		(end 112.700308 -32.91459)
		(stroke
			(width 0.06223)
			(type default)
		)
		(layer "B.Cu")
	)
	(gr_line
		(start 112.691672 -32.87395)
		(end 112.700308 -32.91459)
		(stroke
			(width 0.06223)
			(type default)
		)
		(layer "B.Cu")
	)
	(gr_line
		(start 112.860328 -28.43784)
		(end 113.03127 -29.242004)
		(stroke
			(width 0.06223)
			(type default)
		)
		(layer "B.Cu")
	)
	(gr_arc
		(start 112.880902 -3.096768)
		(mid 112.926558 -3.087651)
		(end 112.96523 -3.061716)
		(stroke
			(width 0.06223)
			(type default)
		)
		(layer "B.Cu")
	)
	(gr_arc
		(start 112.911128 -55.40502)
		(mid 112.973979 -55.378973)
		(end 113.000028 -55.31612)
		(stroke
			(width 0.04445)
			(type default)
		)
		(layer "B.Cu")
	)
	(gr_arc
		(start 112.96523 -3.53822)
		(mid 112.92656 -3.512294)
		(end 112.880902 -3.503168)
		(stroke
			(width 0.06223)
			(type default)
		)
		(layer "B.Cu")
	)
	(gr_arc
		(start 112.96523 -3.061716)
		(mid 112.991004 -3.023143)
		(end 113.000028 -2.977642)
		(stroke
			(width 0.06223)
			(type default)
		)
		(layer "B.Cu")
	)
	(gr_arc
		(start 113.000028 -55.68442)
		(mid 112.97399 -55.621558)
		(end 112.911128 -55.59552)
		(stroke
			(width 0.04445)
			(type default)
		)
		(layer "B.Cu")
	)
	(gr_line
		(start 113.000028 -55.68442)
		(end 113.000028 -56.000142)
		(stroke
			(width 0.04445)
			(type default)
		)
		(layer "B.Cu")
	)
	(gr_line
		(start 113.000028 -55.000144)
		(end 113.000028 -55.31612)
		(stroke
			(width 0.04445)
			(type default)
		)
		(layer "B.Cu")
	)
	(gr_arc
		(start 113.000028 -3.622294)
		(mid 112.991002 -3.576792)
		(end 112.96523 -3.53822)
		(stroke
			(width 0.06223)
			(type default)
		)
		(layer "B.Cu")
	)
	(gr_line
		(start 113.000028 -3.622294)
		(end 113.000028 -3.999992)
		(stroke
			(width 0.06223)
			(type default)
		)
		(layer "B.Cu")
	)
	(gr_line
		(start 113.000028 -2.600198)
		(end 113.000028 -2.977642)
		(stroke
			(width 0.06223)
			(type default)
		)
		(layer "B.Cu")
	)
	(gr_line
		(start 113.127536 -29.694378)
		(end 113.298478 -30.498034)
		(stroke
			(width 0.06223)
			(type default)
		)
		(layer "B.Cu")
	)
	(gr_line
		(start 113.251488 -28.311348)
		(end 113.567972 -28.516834)
		(stroke
			(width 0.06223)
			(type default)
		)
		(layer "B.Cu")
	)
	(gr_line
		(start 113.298732 -50.480214)
		(end 113.365534 -50.547016)
		(stroke
			(width 0.04445)
			(type default)
		)
		(layer "B.Cu")
	)
	(gr_line
		(start 113.298732 -50.458116)
		(end 113.298732 -50.480214)
		(stroke
			(width 0.04445)
			(type default)
		)
		(layer "B.Cu")
	)
	(gr_line
		(start 113.367312 -50.548794)
		(end 113.406682 -50.588164)
		(stroke
			(width 0.04445)
			(type default)
		)
		(layer "B.Cu")
	)
	(gr_line
		(start 113.394998 -30.952186)
		(end 113.565432 -31.754572)
		(stroke
			(width 0.06223)
			(type default)
		)
		(layer "B.Cu")
	)
	(gr_line
		(start 113.411 -44.704)
		(end 113.414048 -44.707048)
		(stroke
			(width 0.06223)
			(type default)
		)
		(layer "B.Cu")
	)
	(gr_line
		(start 113.411 -44.5008)
		(end 113.411 -44.704)
		(stroke
			(width 0.06223)
			(type default)
		)
		(layer "B.Cu")
	)
	(gr_line
		(start 113.44021 -29.198316)
		(end 113.645696 -28.882086)
		(stroke
			(width 0.06223)
			(type default)
		)
		(layer "B.Cu")
	)
	(gr_line
		(start 113.47958 -45.535088)
		(end 113.47958 -45.629068)
		(stroke
			(width 0.06223)
			(type default)
		)
		(layer "B.Cu")
	)
	(gr_line
		(start 113.518696 -29.568394)
		(end 113.83518 -29.77388)
		(stroke
			(width 0.06223)
			(type default)
		)
		(layer "B.Cu")
	)
	(gr_line
		(start 113.567972 -28.516834)
		(end 113.645696 -28.882086)
		(stroke
			(width 0.06223)
			(type default)
		)
		(layer "B.Cu")
	)
	(gr_line
		(start 113.597182 -50.588164)
		(end 113.636552 -50.548794)
		(stroke
			(width 0.04445)
			(type default)
		)
		(layer "B.Cu")
	)
	(gr_line
		(start 113.63833 -50.547016)
		(end 113.705132 -50.480214)
		(stroke
			(width 0.04445)
			(type default)
		)
		(layer "B.Cu")
	)
	(gr_line
		(start 113.705132 -50.458116)
		(end 113.705132 -50.480214)
		(stroke
			(width 0.04445)
			(type default)
		)
		(layer "B.Cu")
	)
	(gr_line
		(start 113.707418 -30.455362)
		(end 113.912904 -30.139132)
		(stroke
			(width 0.06223)
			(type default)
		)
		(layer "B.Cu")
	)
	(gr_line
		(start 113.785904 -30.82544)
		(end 114.102388 -31.030926)
		(stroke
			(width 0.06223)
			(type default)
		)
		(layer "B.Cu")
	)
	(gr_line
		(start 113.83518 -29.77388)
		(end 113.912904 -30.139132)
		(stroke
			(width 0.06223)
			(type default)
		)
		(layer "B.Cu")
	)
	(gr_line
		(start 113.88852 -46.035468)
		(end 114.15522 -45.768768)
		(stroke
			(width 0.06223)
			(type default)
		)
		(layer "B.Cu")
	)
	(gr_line
		(start 113.88852 -45.128688)
		(end 114.15522 -45.395388)
		(stroke
			(width 0.06223)
			(type default)
		)
		(layer "B.Cu")
	)
	(gr_arc
		(start 113.911126 -55.40502)
		(mid 113.973978 -55.378974)
		(end 114.000026 -55.31612)
		(stroke
			(width 0.04445)
			(type default)
		)
		(layer "B.Cu")
	)
	(gr_line
		(start 113.9698 -44.5008)
		(end 113.9698 -44.7294)
		(stroke
			(width 0.06223)
			(type default)
		)
		(layer "B.Cu")
	)
	(gr_line
		(start 113.974372 -31.712662)
		(end 114.180112 -31.396178)
		(stroke
			(width 0.06223)
			(type default)
		)
		(layer "B.Cu")
	)
	(gr_arc
		(start 114.000026 -55.68442)
		(mid 113.973988 -55.621558)
		(end 113.911126 -55.59552)
		(stroke
			(width 0.04445)
			(type default)
		)
		(layer "B.Cu")
	)
	(gr_line
		(start 114.000026 -55.68442)
		(end 114.000026 -56.000142)
		(stroke
			(width 0.04445)
			(type default)
		)
		(layer "B.Cu")
	)
	(gr_line
		(start 114.000026 -55.000144)
		(end 114.000026 -55.31612)
		(stroke
			(width 0.04445)
			(type default)
		)
		(layer "B.Cu")
	)
	(gr_line
		(start 114.102388 -31.030926)
		(end 114.180112 -31.396178)
		(stroke
			(width 0.06223)
			(type default)
		)
		(layer "B.Cu")
	)
	(gr_line
		(start 114.109754 -32.441642)
		(end 114.11839 -32.401256)
		(stroke
			(width 0.06223)
			(type default)
		)
		(layer "B.Cu")
	)
	(gr_line
		(start 114.109754 -32.360616)
		(end 114.11839 -32.401256)
		(stroke
			(width 0.06223)
			(type default)
		)
		(layer "B.Cu")
	)
	(gr_line
		(start 114.15522 -45.395388)
		(end 114.15522 -45.768768)
		(stroke
			(width 0.06223)
			(type default)
		)
		(layer "B.Cu")
	)
	(gr_line
		(start 114.309652 -27.732736)
		(end 114.480594 -28.536646)
		(stroke
			(width 0.06223)
			(type default)
		)
		(layer "B.Cu")
	)
	(gr_line
		(start 114.57686 -28.990036)
		(end 114.747802 -29.7942)
		(stroke
			(width 0.06223)
			(type default)
		)
		(layer "B.Cu")
	)
	(gr_arc
		(start 114.681 -4.296918)
		(mid 114.726656 -4.287801)
		(end 114.765328 -4.261866)
		(stroke
			(width 0.06223)
			(type default)
		)
		(layer "B.Cu")
	)
	(gr_line
		(start 114.700812 -27.606244)
		(end 115.017296 -27.811984)
		(stroke
			(width 0.06223)
			(type default)
		)
		(layer "B.Cu")
	)
	(gr_line
		(start 114.71275 -50.869088)
		(end 114.779552 -50.93589)
		(stroke
			(width 0.04445)
			(type default)
		)
		(layer "B.Cu")
	)
	(gr_line
		(start 114.71275 -50.84699)
		(end 114.71275 -50.869088)
		(stroke
			(width 0.04445)
			(type default)
		)
		(layer "B.Cu")
	)
	(gr_line
		(start 114.71275 -50.686208)
		(end 114.71275 -50.84699)
		(stroke
			(width 0.06223)
			(type default)
		)
		(layer "B.Cu")
	)
	(gr_arc
		(start 114.765328 -4.73837)
		(mid 114.726655 -4.712455)
		(end 114.681 -4.703318)
		(stroke
			(width 0.06223)
			(type default)
		)
		(layer "B.Cu")
	)
	(gr_arc
		(start 114.765328 -4.261866)
		(mid 114.791102 -4.223293)
		(end 114.800126 -4.177792)
		(stroke
			(width 0.06223)
			(type default)
		)
		(layer "B.Cu")
	)
	(gr_line
		(start 114.78133 -50.937668)
		(end 114.81308 -50.969418)
		(stroke
			(width 0.04445)
			(type default)
		)
		(layer "B.Cu")
	)
	(gr_arc
		(start 114.800126 -4.822444)
		(mid 114.791116 -4.776931)
		(end 114.765328 -4.73837)
		(stroke
			(width 0.06223)
			(type default)
		)
		(layer "B.Cu")
	)
	(gr_line
		(start 114.800126 -4.822444)
		(end 114.800126 -5.200142)
		(stroke
			(width 0.06223)
			(type default)
		)
		(layer "B.Cu")
	)
	(gr_line
		(start 114.800126 -3.800094)
		(end 114.800126 -4.177792)
		(stroke
			(width 0.06223)
			(type default)
		)
		(layer "B.Cu")
	)
	(gr_line
		(start 114.81308 -51.396392)
		(end 114.847116 -51.430428)
		(stroke
			(width 0.04445)
			(type default)
		)
		(layer "B.Cu")
	)
	(gr_line
		(start 114.844068 -30.246574)
		(end 115.01501 -31.050992)
		(stroke
			(width 0.06223)
			(type default)
		)
		(layer "B.Cu")
	)
	(gr_line
		(start 114.889534 -28.493466)
		(end 115.09502 -28.177236)
		(stroke
			(width 0.06223)
			(type default)
		)
		(layer "B.Cu")
	)
	(gr_line
		(start 114.935 -44.704)
		(end 114.938048 -44.707048)
		(stroke
			(width 0.06223)
			(type default)
		)
		(layer "B.Cu")
	)
	(gr_line
		(start 114.935 -44.5008)
		(end 114.935 -44.704)
		(stroke
			(width 0.06223)
			(type default)
		)
		(layer "B.Cu")
	)
	(gr_line
		(start 114.96802 -28.863544)
		(end 115.284504 -29.06903)
		(stroke
			(width 0.06223)
			(type default)
		)
		(layer "B.Cu")
	)
	(gr_line
		(start 115.00358 -50.984658)
		(end 115.00358 -51.14544)
		(stroke
			(width 0.04445)
			(type default)
		)
		(layer "B.Cu")
	)
	(gr_line
		(start 115.00358 -50.984658)
		(end 115.05057 -50.937668)
		(stroke
			(width 0.04445)
			(type default)
		)
		(layer "B.Cu")
	)
	(gr_line
		(start 115.0112 -45.544486)
		(end 115.0112 -45.638466)
		(stroke
			(width 0.06223)
			(type default)
		)
		(layer "B.Cu")
	)
	(gr_line
		(start 115.017296 -27.811984)
		(end 115.09502 -28.177236)
		(stroke
			(width 0.06223)
			(type default)
		)
		(layer "B.Cu")
	)
	(gr_line
		(start 115.052348 -50.93589)
		(end 115.11915 -50.869088)
		(stroke
			(width 0.04445)
			(type default)
		)
		(layer "B.Cu")
	)
	(gr_line
		(start 115.11915 -50.84699)
		(end 115.11915 -50.869088)
		(stroke
			(width 0.04445)
			(type default)
		)
		(layer "B.Cu")
	)
	(gr_line
		(start 115.156488 -29.750766)
		(end 115.362228 -29.434282)
		(stroke
			(width 0.06223)
			(type default)
		)
		(layer "B.Cu")
	)
	(gr_line
		(start 115.235228 -30.12059)
		(end 115.551712 -30.32633)
		(stroke
			(width 0.06223)
			(type default)
		)
		(layer "B.Cu")
	)
	(gr_line
		(start 115.284504 -29.06903)
		(end 115.362228 -29.434282)
		(stroke
			(width 0.06223)
			(type default)
		)
		(layer "B.Cu")
	)
	(gr_line
		(start 115.42014 -46.044866)
		(end 115.68684 -45.778166)
		(stroke
			(width 0.06223)
			(type default)
		)
		(layer "B.Cu")
	)
	(gr_line
		(start 115.42014 -45.138086)
		(end 115.68684 -45.404786)
		(stroke
			(width 0.06223)
			(type default)
		)
		(layer "B.Cu")
	)
	(gr_line
		(start 115.42395 -31.007812)
		(end 115.629436 -30.691582)
		(stroke
			(width 0.06223)
			(type default)
		)
		(layer "B.Cu")
	)
	(gr_line
		(start 115.4938 -44.5008)
		(end 115.4938 -44.7294)
		(stroke
			(width 0.06223)
			(type default)
		)
		(layer "B.Cu")
	)
	(gr_line
		(start 115.545616 -31.674308)
		(end 115.554252 -31.633414)
		(stroke
			(width 0.06223)
			(type default)
		)
		(layer "B.Cu")
	)
	(gr_line
		(start 115.545616 -31.592774)
		(end 115.554252 -31.633414)
		(stroke
			(width 0.06223)
			(type default)
		)
		(layer "B.Cu")
	)
	(gr_line
		(start 115.546378 -51.86045)
		(end 115.580414 -51.894486)
		(stroke
			(width 0.04445)
			(type default)
		)
		(layer "B.Cu")
	)
	(gr_line
		(start 115.551712 -30.32633)
		(end 115.629436 -30.691582)
		(stroke
			(width 0.06223)
			(type default)
		)
		(layer "B.Cu")
	)
	(gr_line
		(start 115.68684 -45.404786)
		(end 115.68684 -45.778166)
		(stroke
			(width 0.06223)
			(type default)
		)
		(layer "B.Cu")
	)
	(gr_line
		(start 115.688364 -27.05354)
		(end 115.858544 -27.855164)
		(stroke
			(width 0.06223)
			(type default)
		)
		(layer "B.Cu")
	)
	(gr_arc
		(start 115.911122 -55.40502)
		(mid 115.973977 -55.378975)
		(end 116.000022 -55.31612)
		(stroke
			(width 0.04445)
			(type default)
		)
		(layer "B.Cu")
	)
	(gr_line
		(start 115.955064 -28.30957)
		(end 116.126006 -29.114242)
		(stroke
			(width 0.06223)
			(type default)
		)
		(layer "B.Cu")
	)
	(gr_arc
		(start 116.000022 -55.68442)
		(mid 115.973984 -55.621558)
		(end 115.911122 -55.59552)
		(stroke
			(width 0.04445)
			(type default)
		)
		(layer "B.Cu")
	)
	(gr_line
		(start 116.000022 -55.68442)
		(end 116.000022 -56.000142)
		(stroke
			(width 0.04445)
			(type default)
		)
		(layer "B.Cu")
	)
	(gr_line
		(start 116.000022 -55.000144)
		(end 116.000022 -55.31612)
		(stroke
			(width 0.04445)
			(type default)
		)
		(layer "B.Cu")
	)
	(gr_line
		(start 116.079016 -26.926032)
		(end 116.3955 -27.131518)
		(stroke
			(width 0.06223)
			(type default)
		)
		(layer "B.Cu")
	)
	(gr_line
		(start 116.22278 -29.568648)
		(end 116.392706 -30.369256)
		(stroke
			(width 0.06223)
			(type default)
		)
		(layer "B.Cu")
	)
	(gr_line
		(start 116.267484 -27.813254)
		(end 116.473224 -27.49677)
		(stroke
			(width 0.06223)
			(type default)
		)
		(layer "B.Cu")
	)
	(gr_line
		(start 116.320062 -50.519584)
		(end 116.386864 -50.586386)
		(stroke
			(width 0.04445)
			(type default)
		)
		(layer "B.Cu")
	)
	(gr_line
		(start 116.320062 -50.497486)
		(end 116.320062 -50.519584)
		(stroke
			(width 0.04445)
			(type default)
		)
		(layer "B.Cu")
	)
	(gr_line
		(start 116.320062 -50.352706)
		(end 116.320062 -50.497486)
		(stroke
			(width 0.06223)
			(type default)
		)
		(layer "B.Cu")
	)
	(gr_line
		(start 116.346224 -28.183078)
		(end 116.662708 -28.388818)
		(stroke
			(width 0.06223)
			(type default)
		)
		(layer "B.Cu")
	)
	(gr_line
		(start 116.388642 -50.588164)
		(end 116.40439 -50.603912)
		(stroke
			(width 0.04445)
			(type default)
		)
		(layer "B.Cu")
	)
	(gr_line
		(start 116.3955 -27.131518)
		(end 116.473224 -27.49677)
		(stroke
			(width 0.06223)
			(type default)
		)
		(layer "B.Cu")
	)
	(gr_line
		(start 116.459 -44.5008)
		(end 116.459 -44.879768)
		(stroke
			(width 0.06223)
			(type default)
		)
		(layer "B.Cu")
	)
	(gr_arc
		(start 116.480844 -3.096768)
		(mid 116.5265 -3.087651)
		(end 116.565172 -3.061716)
		(stroke
			(width 0.06223)
			(type default)
		)
		(layer "B.Cu")
	)
	(gr_line
		(start 116.534692 -29.070554)
		(end 116.740178 -28.75407)
		(stroke
			(width 0.06223)
			(type default)
		)
		(layer "B.Cu")
	)
	(gr_arc
		(start 116.565172 -3.53822)
		(mid 116.526504 -3.51228)
		(end 116.480844 -3.503168)
		(stroke
			(width 0.06223)
			(type default)
		)
		(layer "B.Cu")
	)
	(gr_arc
		(start 116.565172 -3.061716)
		(mid 116.590946 -3.023143)
		(end 116.59997 -2.977642)
		(stroke
			(width 0.06223)
			(type default)
		)
		(layer "B.Cu")
	)
	(gr_line
		(start 116.59489 -50.651156)
		(end 116.59489 -50.795936)
		(stroke
			(width 0.04445)
			(type default)
		)
		(layer "B.Cu")
	)
	(gr_line
		(start 116.59489 -50.651156)
		(end 116.657882 -50.588164)
		(stroke
			(width 0.04445)
			(type default)
		)
		(layer "B.Cu")
	)
	(gr_arc
		(start 116.59997 -3.622294)
		(mid 116.590946 -3.576789)
		(end 116.565172 -3.53822)
		(stroke
			(width 0.06223)
			(type default)
		)
		(layer "B.Cu")
	)
	(gr_line
		(start 116.59997 -3.622294)
		(end 116.59997 -3.999992)
		(stroke
			(width 0.06223)
			(type default)
		)
		(layer "B.Cu")
	)
	(gr_line
		(start 116.59997 -2.600198)
		(end 116.59997 -2.977642)
		(stroke
			(width 0.06223)
			(type default)
		)
		(layer "B.Cu")
	)
	(gr_line
		(start 116.613432 -29.440632)
		(end 116.929662 -29.645864)
		(stroke
			(width 0.06223)
			(type default)
		)
		(layer "B.Cu")
	)
	(gr_line
		(start 116.65966 -50.586386)
		(end 116.726462 -50.519584)
		(stroke
			(width 0.04445)
			(type default)
		)
		(layer "B.Cu")
	)
	(gr_line
		(start 116.662708 -28.388818)
		(end 116.740178 -28.75407)
		(stroke
			(width 0.06223)
			(type default)
		)
		(layer "B.Cu")
	)
	(gr_line
		(start 116.726462 -50.497486)
		(end 116.726462 -50.519584)
		(stroke
			(width 0.04445)
			(type default)
		)
		(layer "B.Cu")
	)
	(gr_line
		(start 116.8019 -30.327346)
		(end 117.007386 -30.011116)
		(stroke
			(width 0.06223)
			(type default)
		)
		(layer "B.Cu")
	)
	(gr_arc
		(start 116.91112 -55.40502)
		(mid 116.973976 -55.378976)
		(end 117.00002 -55.31612)
		(stroke
			(width 0.04445)
			(type default)
		)
		(layer "B.Cu")
	)
	(gr_line
		(start 116.929662 -29.645864)
		(end 117.007386 -30.011116)
		(stroke
			(width 0.06223)
			(type default)
		)
		(layer "B.Cu")
	)
	(gr_arc
		(start 117.00002 -55.68442)
		(mid 116.973982 -55.621558)
		(end 116.91112 -55.59552)
		(stroke
			(width 0.04445)
			(type default)
		)
		(layer "B.Cu")
	)
	(gr_line
		(start 117.00002 -55.68442)
		(end 117.00002 -56.000142)
		(stroke
			(width 0.04445)
			(type default)
		)
		(layer "B.Cu")
	)
	(gr_line
		(start 117.00002 -55.000144)
		(end 117.00002 -55.31612)
		(stroke
			(width 0.04445)
			(type default)
		)
		(layer "B.Cu")
	)
	(gr_line
		(start 117.0178 -44.5008)
		(end 117.0178 -44.879768)
		(stroke
			(width 0.06223)
			(type default)
		)
		(layer "B.Cu")
	)
	(gr_line
		(start 117.0686 -48.720248)
		(end 117.0686 -48.911764)
		(stroke
			(width 0.06223)
			(type default)
		)
		(layer "B.Cu")
	)
	(gr_line
		(start 117.085872 -31.757112)
		(end 117.094508 -31.71698)
		(stroke
			(width 0.06223)
			(type default)
		)
		(layer "B.Cu")
	)
	(gr_line
		(start 117.085872 -31.67634)
		(end 117.094508 -31.71698)
		(stroke
			(width 0.06223)
			(type default)
		)
		(layer "B.Cu")
	)
	(gr_line
		(start 117.245892 -26.473658)
		(end 117.410738 -27.28087)
		(stroke
			(width 0.06223)
			(type default)
		)
		(layer "B.Cu")
	)
	(gr_line
		(start 117.308376 -50.383948)
		(end 117.375178 -50.45075)
		(stroke
			(width 0.04445)
			(type default)
		)
		(layer "B.Cu")
	)
	(gr_line
		(start 117.308376 -50.36185)
		(end 117.308376 -50.383948)
		(stroke
			(width 0.04445)
			(type default)
		)
		(layer "B.Cu")
	)
	(gr_line
		(start 117.308376 -50.205386)
		(end 117.308376 -50.36185)
		(stroke
			(width 0.06223)
			(type default)
		)
		(layer "B.Cu")
	)
	(gr_line
		(start 117.376956 -50.452528)
		(end 117.404388 -50.47996)
		(stroke
			(width 0.04445)
			(type default)
		)
		(layer "B.Cu")
	)
	(gr_line
		(start 117.47754 -49.318164)
		(end 117.793008 -49.002696)
		(stroke
			(width 0.06223)
			(type default)
		)
		(layer "B.Cu")
	)
	(gr_line
		(start 117.47754 -48.313848)
		(end 117.793008 -48.629316)
		(stroke
			(width 0.06223)
			(type default)
		)
		(layer "B.Cu")
	)
	(gr_line
		(start 117.503702 -27.734768)
		(end 117.66804 -28.538932)
		(stroke
			(width 0.06223)
			(type default)
		)
		(layer "B.Cu")
	)
	(gr_line
		(start 117.594888 -50.503836)
		(end 117.594888 -50.6603)
		(stroke
			(width 0.04445)
			(type default)
		)
		(layer "B.Cu")
	)
	(gr_line
		(start 117.594888 -50.503836)
		(end 117.646196 -50.452528)
		(stroke
			(width 0.04445)
			(type default)
		)
		(layer "B.Cu")
	)
	(gr_line
		(start 117.638322 -26.350976)
		(end 117.953028 -26.559256)
		(stroke
			(width 0.06223)
			(type default)
		)
		(layer "B.Cu")
	)
	(gr_line
		(start 117.647974 -50.45075)
		(end 117.714776 -50.383948)
		(stroke
			(width 0.04445)
			(type default)
		)
		(layer "B.Cu")
	)
	(gr_line
		(start 117.714776 -50.36185)
		(end 117.714776 -50.383948)
		(stroke
			(width 0.04445)
			(type default)
		)
		(layer "B.Cu")
	)
	(gr_line
		(start 117.76075 -28.993846)
		(end 117.924834 -29.797248)
		(stroke
			(width 0.06223)
			(type default)
		)
		(layer "B.Cu")
	)
	(gr_line
		(start 117.793008 -48.629316)
		(end 117.793008 -49.002696)
		(stroke
			(width 0.06223)
			(type default)
		)
		(layer "B.Cu")
	)
	(gr_line
		(start 117.819932 -27.239976)
		(end 118.027704 -26.925016)
		(stroke
			(width 0.06223)
			(type default)
		)
		(layer "B.Cu")
	)
	(gr_line
		(start 117.895624 -27.610562)
		(end 118.21033 -27.818588)
		(stroke
			(width 0.06223)
			(type default)
		)
		(layer "B.Cu")
	)
	(gr_arc
		(start 117.911118 -55.40502)
		(mid 117.973975 -55.378977)
		(end 118.000018 -55.31612)
		(stroke
			(width 0.04445)
			(type default)
		)
		(layer "B.Cu")
	)
	(gr_line
		(start 117.953028 -26.559256)
		(end 118.027704 -26.925016)
		(stroke
			(width 0.06223)
			(type default)
		)
		(layer "B.Cu")
	)
	(gr_line
		(start 117.983 -44.5008)
		(end 117.983 -44.752768)
		(stroke
			(width 0.06223)
			(type default)
		)
		(layer "B.Cu")
	)
	(gr_arc
		(start 118.000018 -55.68442)
		(mid 117.97398 -55.621558)
		(end 117.911118 -55.59552)
		(stroke
			(width 0.04445)
			(type default)
		)
		(layer "B.Cu")
	)
	(gr_line
		(start 118.000018 -55.68442)
		(end 118.000018 -56.000142)
		(stroke
			(width 0.04445)
			(type default)
		)
		(layer "B.Cu")
	)
	(gr_line
		(start 118.000018 -55.000144)
		(end 118.000018 -55.31612)
		(stroke
			(width 0.04445)
			(type default)
		)
		(layer "B.Cu")
	)
	(gr_line
		(start 118.07698 -28.499308)
		(end 118.285006 -28.184348)
		(stroke
			(width 0.06223)
			(type default)
		)
		(layer "B.Cu")
	)
	(gr_line
		(start 118.152672 -28.86964)
		(end 118.467632 -29.07792)
		(stroke
			(width 0.06223)
			(type default)
		)
		(layer "B.Cu")
	)
	(gr_line
		(start 118.21033 -27.818588)
		(end 118.285006 -28.184348)
		(stroke
			(width 0.06223)
			(type default)
		)
		(layer "B.Cu")
	)
	(gr_arc
		(start 118.280942 -4.296918)
		(mid 118.326598 -4.287801)
		(end 118.36527 -4.261866)
		(stroke
			(width 0.06223)
			(type default)
		)
		(layer "B.Cu")
	)
	(gr_line
		(start 118.296436 -50.388012)
		(end 118.363238 -50.454814)
		(stroke
			(width 0.04445)
			(type default)
		)
		(layer "B.Cu")
	)
	(gr_line
		(start 118.296436 -50.365914)
		(end 118.296436 -50.388012)
		(stroke
			(width 0.04445)
			(type default)
		)
		(layer "B.Cu")
	)
	(gr_line
		(start 118.296436 -48.347884)
		(end 118.296436 -48.566324)
		(stroke
			(width 0.06223)
			(type default)
		)
		(layer "B.Cu")
	)
	(gr_line
		(start 118.296436 -46.247558)
		(end 118.296436 -46.24832)
		(stroke
			(width 0.06223)
			(type default)
		)
		(layer "B.Cu")
	)
	(gr_line
		(start 118.334282 -29.75864)
		(end 118.542308 -29.44368)
		(stroke
			(width 0.06223)
			(type default)
		)
		(layer "B.Cu")
	)
	(gr_line
		(start 118.365016 -50.456592)
		(end 118.404386 -50.495962)
		(stroke
			(width 0.04445)
			(type default)
		)
		(layer "B.Cu")
	)
	(gr_arc
		(start 118.36527 -4.73837)
		(mid 118.326599 -4.712441)
		(end 118.280942 -4.703318)
		(stroke
			(width 0.06223)
			(type default)
		)
		(layer "B.Cu")
	)
	(gr_arc
		(start 118.36527 -4.261866)
		(mid 118.391044 -4.223293)
		(end 118.400068 -4.177792)
		(stroke
			(width 0.06223)
			(type default)
		)
		(layer "B.Cu")
	)
	(gr_arc
		(start 118.400068 -4.822444)
		(mid 118.39106 -4.776929)
		(end 118.36527 -4.73837)
		(stroke
			(width 0.06223)
			(type default)
		)
		(layer "B.Cu")
	)
	(gr_line
		(start 118.400068 -4.822444)
		(end 118.400068 -5.200142)
		(stroke
			(width 0.06223)
			(type default)
		)
		(layer "B.Cu")
	)
	(gr_line
		(start 118.400068 -3.800094)
		(end 118.400068 -4.177792)
		(stroke
			(width 0.06223)
			(type default)
		)
		(layer "B.Cu")
	)
	(gr_line
		(start 118.4656 -45.841158)
		(end 118.4656 -45.84192)
		(stroke
			(width 0.06223)
			(type default)
		)
		(layer "B.Cu")
	)
	(gr_line
		(start 118.467632 -29.07792)
		(end 118.542308 -29.44368)
		(stroke
			(width 0.06223)
			(type default)
		)
		(layer "B.Cu")
	)
	(gr_line
		(start 118.5418 -44.5008)
		(end 118.5418 -44.752768)
		(stroke
			(width 0.06223)
			(type default)
		)
		(layer "B.Cu")
	)
	(gr_line
		(start 118.586504 -31.006034)
		(end 118.59387 -31.042102)
		(stroke
			(width 0.06223)
			(type default)
		)
		(layer "B.Cu")
	)
	(gr_line
		(start 118.586758 -31.07817)
		(end 118.59387 -31.042102)
		(stroke
			(width 0.06223)
			(type default)
		)
		(layer "B.Cu")
	)
	(gr_line
		(start 118.594886 -50.495962)
		(end 118.634256 -50.456592)
		(stroke
			(width 0.04445)
			(type default)
		)
		(layer "B.Cu")
	)
	(gr_line
		(start 118.636034 -50.454814)
		(end 118.702836 -50.388012)
		(stroke
			(width 0.04445)
			(type default)
		)
		(layer "B.Cu")
	)
	(gr_line
		(start 118.702836 -50.365914)
		(end 118.702836 -50.388012)
		(stroke
			(width 0.04445)
			(type default)
		)
		(layer "B.Cu")
	)
	(gr_line
		(start 118.705376 -48.972724)
		(end 119.034306 -48.643794)
		(stroke
			(width 0.06223)
			(type default)
		)
		(layer "B.Cu")
	)
	(gr_line
		(start 118.705376 -47.941484)
		(end 119.034306 -48.270414)
		(stroke
			(width 0.06223)
			(type default)
		)
		(layer "B.Cu")
	)
	(gr_arc
		(start 118.911116 -55.40502)
		(mid 118.973975 -55.378977)
		(end 119.000016 -55.31612)
		(stroke
			(width 0.04445)
			(type default)
		)
		(layer "B.Cu")
	)
	(gr_arc
		(start 119.000016 -55.68442)
		(mid 118.973978 -55.621558)
		(end 118.911116 -55.59552)
		(stroke
			(width 0.04445)
			(type default)
		)
		(layer "B.Cu")
	)
	(gr_line
		(start 119.000016 -55.68442)
		(end 119.000016 -56.000142)
		(stroke
			(width 0.04445)
			(type default)
		)
		(layer "B.Cu")
	)
	(gr_line
		(start 119.000016 -55.000144)
		(end 119.000016 -55.31612)
		(stroke
			(width 0.04445)
			(type default)
		)
		(layer "B.Cu")
	)
	(gr_line
		(start 119.034306 -48.270414)
		(end 119.034306 -48.643794)
		(stroke
			(width 0.06223)
			(type default)
		)
		(layer "B.Cu")
	)
	(gr_line
		(start 119.069866 -26.531824)
		(end 119.241316 -27.339798)
		(stroke
			(width 0.06223)
			(type default)
		)
		(layer "B.Cu")
	)
	(gr_line
		(start 119.09679 -16.995394)
		(end 119.097044 -16.99514)
		(stroke
			(width 0.06223)
			(type default)
		)
		(layer "B.Cu")
	)
	(gr_line
		(start 119.09679 -16.995394)
		(end 119.097552 -16.998188)
		(stroke
			(width 0.06223)
			(type default)
		)
		(layer "B.Cu")
	)
	(gr_line
		(start 119.295164 -50.502312)
		(end 119.361966 -50.569114)
		(stroke
			(width 0.04445)
			(type default)
		)
		(layer "B.Cu")
	)
	(gr_line
		(start 119.295164 -50.480214)
		(end 119.295164 -50.502312)
		(stroke
			(width 0.04445)
			(type default)
		)
		(layer "B.Cu")
	)
	(gr_line
		(start 119.336058 -27.78633)
		(end 119.508016 -28.595574)
		(stroke
			(width 0.06223)
			(type default)
		)
		(layer "B.Cu")
	)
	(gr_line
		(start 119.363744 -50.570892)
		(end 119.403114 -50.610262)
		(stroke
			(width 0.04445)
			(type default)
		)
		(layer "B.Cu")
	)
	(gr_line
		(start 119.46128 -26.40584)
		(end 119.777764 -26.61158)
		(stroke
			(width 0.06223)
			(type default)
		)
		(layer "B.Cu")
	)
	(gr_line
		(start 119.507 -44.5008)
		(end 119.507 -44.919392)
		(stroke
			(width 0.06223)
			(type default)
		)
		(layer "B.Cu")
	)
	(gr_line
		(start 119.5832 -48.055276)
		(end 119.5832 -48.290988)
		(stroke
			(width 0.06223)
			(type default)
		)
		(layer "B.Cu")
	)
	(gr_line
		(start 119.593614 -50.610262)
		(end 119.632984 -50.570892)
		(stroke
			(width 0.04445)
			(type default)
		)
		(layer "B.Cu")
	)
	(gr_line
		(start 119.60352 -29.04617)
		(end 119.774462 -29.85135)
		(stroke
			(width 0.06223)
			(type default)
		)
		(layer "B.Cu")
	)
	(gr_line
		(start 119.634762 -50.569114)
		(end 119.701564 -50.502312)
		(stroke
			(width 0.04445)
			(type default)
		)
		(layer "B.Cu")
	)
	(gr_line
		(start 119.649748 -27.29357)
		(end 119.855488 -26.976832)
		(stroke
			(width 0.06223)
			(type default)
		)
		(layer "B.Cu")
	)
	(gr_line
		(start 119.701564 -50.480214)
		(end 119.701564 -50.502312)
		(stroke
			(width 0.04445)
			(type default)
		)
		(layer "B.Cu")
	)
	(gr_line
		(start 119.728234 -27.66314)
		(end 120.044464 -27.86888)
		(stroke
			(width 0.06223)
			(type default)
		)
		(layer "B.Cu")
	)
	(gr_line
		(start 119.777764 -26.61158)
		(end 119.855488 -26.976832)
		(stroke
			(width 0.06223)
			(type default)
		)
		(layer "B.Cu")
	)
	(gr_arc
		(start 119.911114 -55.40502)
		(mid 119.973974 -55.378978)
		(end 120.000014 -55.31612)
		(stroke
			(width 0.04445)
			(type default)
		)
		(layer "B.Cu")
	)
	(gr_line
		(start 119.916448 -28.550616)
		(end 120.122188 -28.234132)
		(stroke
			(width 0.06223)
			(type default)
		)
		(layer "B.Cu")
	)
	(gr_line
		(start 119.99214 -48.697388)
		(end 120.329706 -48.359822)
		(stroke
			(width 0.06223)
			(type default)
		)
		(layer "B.Cu")
	)
	(gr_line
		(start 119.99214 -47.648876)
		(end 120.329706 -47.986442)
		(stroke
			(width 0.06223)
			(type default)
		)
		(layer "B.Cu")
	)
	(gr_line
		(start 119.994934 -28.92044)
		(end 120.311164 -29.12618)
		(stroke
			(width 0.06223)
			(type default)
		)
		(layer "B.Cu")
	)
	(gr_arc
		(start 120.000014 -55.68442)
		(mid 119.973984 -55.62154)
		(end 119.911114 -55.59552)
		(stroke
			(width 0.04445)
			(type default)
		)
		(layer "B.Cu")
	)
	(gr_line
		(start 120.000014 -55.68442)
		(end 120.000014 -56.000142)
		(stroke
			(width 0.04445)
			(type default)
		)
		(layer "B.Cu")
	)
	(gr_line
		(start 120.000014 -55.000144)
		(end 120.000014 -55.31612)
		(stroke
			(width 0.04445)
			(type default)
		)
		(layer "B.Cu")
	)
	(gr_line
		(start 120.044464 -27.86888)
		(end 120.122188 -28.234132)
		(stroke
			(width 0.06223)
			(type default)
		)
		(layer "B.Cu")
	)
	(gr_line
		(start 120.0658 -44.5008)
		(end 120.0658 -44.9072)
		(stroke
			(width 0.06223)
			(type default)
		)
		(layer "B.Cu")
	)
	(gr_arc
		(start 120.08104 -3.096768)
		(mid 120.126697 -3.087658)
		(end 120.165368 -3.061716)
		(stroke
			(width 0.06223)
			(type default)
		)
		(layer "B.Cu")
	)
	(gr_arc
		(start 120.165368 -3.061716)
		(mid 120.191115 -3.023134)
		(end 120.200166 -2.977642)
		(stroke
			(width 0.06223)
			(type default)
		)
		(layer "B.Cu")
	)
	(gr_line
		(start 120.183148 -29.807662)
		(end 120.388888 -29.491432)
		(stroke
			(width 0.06223)
			(type default)
		)
		(layer "B.Cu")
	)
	(gr_arc
		(start 120.200166 -3.622294)
		(mid 120.191117 -3.576804)
		(end 120.165368 -3.53822)
		(stroke
			(width 0.06223)
			(type default)
		)
		(layer "B.Cu")
	)
	(gr_line
		(start 120.200166 -3.622294)
		(end 120.200166 -3.999992)
		(stroke
			(width 0.06223)
			(type default)
		)
		(layer "B.Cu")
	)
	(gr_line
		(start 120.200166 -2.600198)
		(end 120.200166 -2.977642)
		(stroke
			(width 0.06223)
			(type default)
		)
		(layer "B.Cu")
	)
	(gr_line
		(start 120.273064 -30.324552)
		(end 120.273064 -30.32506)
		(stroke
			(width 0.06223)
			(type default)
		)
		(layer "B.Cu")
	)
	(gr_line
		(start 120.273064 -30.324298)
		(end 120.2817 -30.283658)
		(stroke
			(width 0.06223)
			(type default)
		)
		(layer "B.Cu")
	)
	(gr_line
		(start 120.273064 -30.24378)
		(end 120.2817 -30.283658)
		(stroke
			(width 0.06223)
			(type default)
		)
		(layer "B.Cu")
	)
	(gr_line
		(start 120.29821 -50.388012)
		(end 120.365012 -50.454814)
		(stroke
			(width 0.04445)
			(type default)
		)
		(layer "B.Cu")
	)
	(gr_line
		(start 120.29821 -50.365914)
		(end 120.29821 -50.388012)
		(stroke
			(width 0.04445)
			(type default)
		)
		(layer "B.Cu")
	)
	(gr_line
		(start 120.311164 -29.12618)
		(end 120.388888 -29.491432)
		(stroke
			(width 0.06223)
			(type default)
		)
		(layer "B.Cu")
	)
	(gr_line
		(start 120.329706 -47.986442)
		(end 120.329706 -48.359822)
		(stroke
			(width 0.06223)
			(type default)
		)
		(layer "B.Cu")
	)
	(gr_line
		(start 120.36679 -50.456592)
		(end 120.40616 -50.495962)
		(stroke
			(width 0.04445)
			(type default)
		)
		(layer "B.Cu")
	)
	(gr_line
		(start 120.59666 -50.495962)
		(end 120.63603 -50.456592)
		(stroke
			(width 0.04445)
			(type default)
		)
		(layer "B.Cu")
	)
	(gr_line
		(start 120.637808 -50.454814)
		(end 120.70461 -50.388012)
		(stroke
			(width 0.04445)
			(type default)
		)
		(layer "B.Cu")
	)
	(gr_line
		(start 120.70461 -50.365914)
		(end 120.70461 -50.388012)
		(stroke
			(width 0.04445)
			(type default)
		)
		(layer "B.Cu")
	)
	(gr_line
		(start 120.74271 -107.923076)
		(end 120.773444 -107.916472)
		(stroke
			(width 0.06223)
			(type default)
		)
		(layer "B.Cu")
	)
	(gr_line
		(start 120.773444 -107.916472)
		(end 120.79986 -107.899454)
		(stroke
			(width 0.06223)
			(type default)
		)
		(layer "B.Cu")
	)
	(gr_line
		(start 120.853962 -25.263094)
		(end 121.024904 -26.067004)
		(stroke
			(width 0.06223)
			(type default)
		)
		(layer "B.Cu")
	)
	(gr_arc
		(start 120.911112 -55.40502)
		(mid 120.973973 -55.378979)
		(end 121.000012 -55.31612)
		(stroke
			(width 0.04445)
			(type default)
		)
		(layer "B.Cu")
	)
	(gr_arc
		(start 121.000012 -55.68442)
		(mid 120.973974 -55.621558)
		(end 120.911112 -55.59552)
		(stroke
			(width 0.04445)
			(type default)
		)
		(layer "B.Cu")
	)
	(gr_line
		(start 121.000012 -55.68442)
		(end 121.000012 -56.000142)
		(stroke
			(width 0.04445)
			(type default)
		)
		(layer "B.Cu")
	)
	(gr_line
		(start 121.000012 -55.000144)
		(end 121.000012 -55.31612)
		(stroke
			(width 0.04445)
			(type default)
		)
		(layer "B.Cu")
	)
	(gr_line
		(start 121.120662 -26.518616)
		(end 121.292366 -27.325828)
		(stroke
			(width 0.06223)
			(type default)
		)
		(layer "B.Cu")
	)
	(gr_line
		(start 121.245122 -25.136094)
		(end 121.561606 -25.341326)
		(stroke
			(width 0.06223)
			(type default)
		)
		(layer "B.Cu")
	)
	(gr_line
		(start 121.297446 -50.388012)
		(end 121.364248 -50.454814)
		(stroke
			(width 0.04445)
			(type default)
		)
		(layer "B.Cu")
	)
	(gr_line
		(start 121.297446 -50.365914)
		(end 121.297446 -50.388012)
		(stroke
			(width 0.04445)
			(type default)
		)
		(layer "B.Cu")
	)
	(gr_line
		(start 121.35485 -109.244384)
		(end 121.38787 -109.237272)
		(stroke
			(width 0.06223)
			(type default)
		)
		(layer "B.Cu")
	)
	(gr_line
		(start 121.366026 -50.456592)
		(end 121.405396 -50.495962)
		(stroke
			(width 0.04445)
			(type default)
		)
		(layer "B.Cu")
	)
	(gr_line
		(start 121.38787 -109.237272)
		(end 121.416064 -109.218984)
		(stroke
			(width 0.06223)
			(type default)
		)
		(layer "B.Cu")
	)
	(gr_line
		(start 121.388632 -27.777694)
		(end 121.55932 -28.581858)
		(stroke
			(width 0.06223)
			(type default)
		)
		(layer "B.Cu")
	)
	(gr_line
		(start 121.43359 -26.023062)
		(end 121.639076 -25.706578)
		(stroke
			(width 0.06223)
			(type default)
		)
		(layer "B.Cu")
	)
	(gr_line
		(start 121.4374 -39.9796)
		(end 121.453148 -39.995348)
		(stroke
			(width 0.06223)
			(type default)
		)
		(layer "B.Cu")
	)
	(gr_line
		(start 121.4374 -39.751)
		(end 121.4374 -39.9796)
		(stroke
			(width 0.06223)
			(type default)
		)
		(layer "B.Cu")
	)
	(gr_line
		(start 121.4374 -39.1922)
		(end 121.440448 -39.189152)
		(stroke
			(width 0.06223)
			(type default)
		)
		(layer "B.Cu")
	)
	(gr_line
		(start 121.51233 -26.39314)
		(end 121.828814 -26.598626)
		(stroke
			(width 0.06223)
			(type default)
		)
		(layer "B.Cu")
	)
	(gr_line
		(start 121.5136 -40.860472)
		(end 121.5136 -40.9829)
		(stroke
			(width 0.06223)
			(type default)
		)
		(layer "B.Cu")
	)
	(gr_line
		(start 121.561606 -25.341326)
		(end 121.639076 -25.706578)
		(stroke
			(width 0.06223)
			(type default)
		)
		(layer "B.Cu")
	)
	(gr_line
		(start 121.595896 -50.495962)
		(end 121.635266 -50.456592)
		(stroke
			(width 0.04445)
			(type default)
		)
		(layer "B.Cu")
	)
	(gr_line
		(start 121.59615 -110.551468)
		(end 121.628408 -110.54461)
		(stroke
			(width 0.06223)
			(type default)
		)
		(layer "B.Cu")
	)
	(gr_line
		(start 121.628408 -110.54461)
		(end 121.654824 -110.527338)
		(stroke
			(width 0.06223)
			(type default)
		)
		(layer "B.Cu")
	)
	(gr_line
		(start 121.637044 -50.454814)
		(end 121.703846 -50.388012)
		(stroke
			(width 0.04445)
			(type default)
		)
		(layer "B.Cu")
	)
	(gr_line
		(start 121.700798 -27.280362)
		(end 121.906284 -26.963878)
		(stroke
			(width 0.06223)
			(type default)
		)
		(layer "B.Cu")
	)
	(gr_line
		(start 121.703846 -50.365914)
		(end 121.703846 -50.388012)
		(stroke
			(width 0.04445)
			(type default)
		)
		(layer "B.Cu")
	)
	(gr_line
		(start 121.779538 -27.65044)
		(end 122.095768 -27.855672)
		(stroke
			(width 0.06223)
			(type default)
		)
		(layer "B.Cu")
	)
	(gr_line
		(start 121.828814 -26.598626)
		(end 121.906284 -26.963878)
		(stroke
			(width 0.06223)
			(type default)
		)
		(layer "B.Cu")
	)
	(gr_arc
		(start 121.880884 -4.296918)
		(mid 121.926556 -4.287829)
		(end 121.965212 -4.261866)
		(stroke
			(width 0.06223)
			(type default)
		)
		(layer "B.Cu")
	)
	(gr_arc
		(start 121.91111 -55.40502)
		(mid 121.973972 -55.378979)
		(end 122.00001 -55.31612)
		(stroke
			(width 0.04445)
			(type default)
		)
		(layer "B.Cu")
	)
	(gr_line
		(start 121.92254 -41.3893)
		(end 122.203464 -41.108376)
		(stroke
			(width 0.06223)
			(type default)
		)
		(layer "B.Cu")
	)
	(gr_line
		(start 121.92254 -40.454072)
		(end 122.203464 -40.734996)
		(stroke
			(width 0.06223)
			(type default)
		)
		(layer "B.Cu")
	)
	(gr_line
		(start 121.959624 -111.794798)
		(end 121.992644 -111.787686)
		(stroke
			(width 0.06223)
			(type default)
		)
		(layer "B.Cu")
	)
	(gr_arc
		(start 121.965212 -4.261866)
		(mid 121.990954 -4.223284)
		(end 122.00001 -4.177792)
		(stroke
			(width 0.06223)
			(type default)
		)
		(layer "B.Cu")
	)
	(gr_line
		(start 121.968006 -28.537408)
		(end 122.173492 -28.220924)
		(stroke
			(width 0.06223)
			(type default)
		)
		(layer "B.Cu")
	)
	(gr_line
		(start 121.992644 -111.787686)
		(end 122.020838 -111.769398)
		(stroke
			(width 0.06223)
			(type default)
		)
		(layer "B.Cu")
	)
	(gr_arc
		(start 122.00001 -55.68442)
		(mid 121.973972 -55.621558)
		(end 121.91111 -55.59552)
		(stroke
			(width 0.04445)
			(type default)
		)
		(layer "B.Cu")
	)
	(gr_line
		(start 122.00001 -55.68442)
		(end 122.00001 -56.000142)
		(stroke
			(width 0.04445)
			(type default)
		)
		(layer "B.Cu")
	)
	(gr_line
		(start 122.00001 -55.000144)
		(end 122.00001 -55.31612)
		(stroke
			(width 0.04445)
			(type default)
		)
		(layer "B.Cu")
	)
	(gr_arc
		(start 122.00001 -4.822444)
		(mid 121.990961 -4.776954)
		(end 121.965212 -4.73837)
		(stroke
			(width 0.06223)
			(type default)
		)
		(layer "B.Cu")
	)
	(gr_line
		(start 122.00001 -4.822444)
		(end 122.00001 -5.200142)
		(stroke
			(width 0.06223)
			(type default)
		)
		(layer "B.Cu")
	)
	(gr_line
		(start 122.00001 -3.800094)
		(end 122.00001 -4.177792)
		(stroke
			(width 0.06223)
			(type default)
		)
		(layer "B.Cu")
	)
	(gr_line
		(start 122.018552 -39.189152)
		(end 122.0216 -39.1922)
		(stroke
			(width 0.06223)
			(type default)
		)
		(layer "B.Cu")
	)
	(gr_line
		(start 122.0216 -39.751)
		(end 122.0216 -40.005)
		(stroke
			(width 0.06223)
			(type default)
		)
		(layer "B.Cu")
	)
	(gr_line
		(start 122.03684 -28.954222)
		(end 122.045476 -28.913582)
		(stroke
			(width 0.06223)
			(type default)
		)
		(layer "B.Cu")
	)
	(gr_line
		(start 122.03684 -28.872688)
		(end 122.045476 -28.913582)
		(stroke
			(width 0.06223)
			(type default)
		)
		(layer "B.Cu")
	)
	(gr_line
		(start 122.095768 -27.855672)
		(end 122.173492 -28.220924)
		(stroke
			(width 0.06223)
			(type default)
		)
		(layer "B.Cu")
	)
	(gr_line
		(start 122.197114 -48.131984)
		(end 122.197114 -48.379888)
		(stroke
			(width 0.06223)
			(type default)
		)
		(layer "B.Cu")
	)
	(gr_line
		(start 122.203464 -40.734996)
		(end 122.203464 -41.108376)
		(stroke
			(width 0.06223)
			(type default)
		)
		(layer "B.Cu")
	)
	(gr_line
		(start 122.296682 -50.388012)
		(end 122.363484 -50.454814)
		(stroke
			(width 0.04445)
			(type default)
		)
		(layer "B.Cu")
	)
	(gr_line
		(start 122.296682 -50.365914)
		(end 122.296682 -50.388012)
		(stroke
			(width 0.04445)
			(type default)
		)
		(layer "B.Cu")
	)
	(gr_line
		(start 122.365262 -50.456592)
		(end 122.404632 -50.495962)
		(stroke
			(width 0.04445)
			(type default)
		)
		(layer "B.Cu")
	)
	(gr_line
		(start 122.487436 -24.231346)
		(end 122.658378 -25.035256)
		(stroke
			(width 0.06223)
			(type default)
		)
		(layer "B.Cu")
	)
	(gr_line
		(start 122.595132 -50.495962)
		(end 122.634502 -50.456592)
		(stroke
			(width 0.04445)
			(type default)
		)
		(layer "B.Cu")
	)
	(gr_line
		(start 122.606054 -48.786288)
		(end 122.949716 -48.442626)
		(stroke
			(width 0.06223)
			(type default)
		)
		(layer "B.Cu")
	)
	(gr_line
		(start 122.606054 -47.725584)
		(end 122.949716 -48.069246)
		(stroke
			(width 0.06223)
			(type default)
		)
		(layer "B.Cu")
	)
	(gr_line
		(start 122.63628 -50.454814)
		(end 122.703082 -50.388012)
		(stroke
			(width 0.04445)
			(type default)
		)
		(layer "B.Cu")
	)
	(gr_line
		(start 122.703082 -50.365914)
		(end 122.703082 -50.388012)
		(stroke
			(width 0.04445)
			(type default)
		)
		(layer "B.Cu")
	)
	(gr_line
		(start 122.754644 -25.488646)
		(end 122.925586 -26.293064)
		(stroke
			(width 0.06223)
			(type default)
		)
		(layer "B.Cu")
	)
	(gr_line
		(start 122.878596 -24.104854)
		(end 123.19508 -24.310594)
		(stroke
			(width 0.06223)
			(type default)
		)
		(layer "B.Cu")
	)
	(gr_arc
		(start 122.911108 -55.40502)
		(mid 122.973972 -55.37898)
		(end 123.000008 -55.31612)
		(stroke
			(width 0.04445)
			(type default)
		)
		(layer "B.Cu")
	)
	(gr_line
		(start 122.949716 -48.069246)
		(end 122.949716 -48.442626)
		(stroke
			(width 0.06223)
			(type default)
		)
		(layer "B.Cu")
	)
	(gr_arc
		(start 123.000008 -55.68442)
		(mid 122.97397 -55.621558)
		(end 122.911108 -55.59552)
		(stroke
			(width 0.04445)
			(type default)
		)
		(layer "B.Cu")
	)
	(gr_line
		(start 123.000008 -55.68442)
		(end 123.000008 -56.000142)
		(stroke
			(width 0.04445)
			(type default)
		)
		(layer "B.Cu")
	)
	(gr_line
		(start 123.000008 -55.000144)
		(end 123.000008 -55.31612)
		(stroke
			(width 0.04445)
			(type default)
		)
		(layer "B.Cu")
	)
	(gr_line
		(start 123.021852 -26.745184)
		(end 123.192794 -27.549094)
		(stroke
			(width 0.06223)
			(type default)
		)
		(layer "B.Cu")
	)
	(gr_line
		(start 123.067318 -24.992076)
		(end 123.272804 -24.675846)
		(stroke
			(width 0.06223)
			(type default)
		)
		(layer "B.Cu")
	)
	(gr_line
		(start 123.145804 -25.362154)
		(end 123.462288 -25.56764)
		(stroke
			(width 0.06223)
			(type default)
		)
		(layer "B.Cu")
	)
	(gr_line
		(start 123.19508 -24.310594)
		(end 123.272804 -24.675846)
		(stroke
			(width 0.06223)
			(type default)
		)
		(layer "B.Cu")
	)
	(gr_line
		(start 123.2154 -39.9542)
		(end 123.218448 -39.957248)
		(stroke
			(width 0.06223)
			(type default)
		)
		(layer "B.Cu")
	)
	(gr_line
		(start 123.2154 -39.751)
		(end 123.2154 -39.9542)
		(stroke
			(width 0.06223)
			(type default)
		)
		(layer "B.Cu")
	)
	(gr_line
		(start 123.2154 -39.1922)
		(end 123.218448 -39.189152)
		(stroke
			(width 0.06223)
			(type default)
		)
		(layer "B.Cu")
	)
	(gr_line
		(start 123.334272 -26.249376)
		(end 123.540012 -25.932892)
		(stroke
			(width 0.06223)
			(type default)
		)
		(layer "B.Cu")
	)
	(gr_line
		(start 123.413012 -26.6192)
		(end 123.729496 -26.82494)
		(stroke
			(width 0.06223)
			(type default)
		)
		(layer "B.Cu")
	)
	(gr_line
		(start 123.42622 -48.081946)
		(end 123.42622 -48.305466)
		(stroke
			(width 0.06223)
			(type default)
		)
		(layer "B.Cu")
	)
	(gr_line
		(start 123.462288 -25.56764)
		(end 123.540012 -25.932892)
		(stroke
			(width 0.06223)
			(type default)
		)
		(layer "B.Cu")
	)
	(gr_line
		(start 123.601734 -27.506422)
		(end 123.80722 -27.190192)
		(stroke
			(width 0.06223)
			(type default)
		)
		(layer "B.Cu")
	)
	(gr_arc
		(start 123.680982 -3.096768)
		(mid 123.726652 -3.087677)
		(end 123.76531 -3.061716)
		(stroke
			(width 0.06223)
			(type default)
		)
		(layer "B.Cu")
	)
	(gr_line
		(start 123.729496 -26.82494)
		(end 123.80722 -27.190192)
		(stroke
			(width 0.06223)
			(type default)
		)
		(layer "B.Cu")
	)
	(gr_line
		(start 123.736608 -28.23464)
		(end 123.745244 -28.194)
		(stroke
			(width 0.06223)
			(type default)
		)
		(layer "B.Cu")
	)
	(gr_line
		(start 123.736608 -28.15336)
		(end 123.745244 -28.194)
		(stroke
			(width 0.06223)
			(type default)
		)
		(layer "B.Cu")
	)
	(gr_arc
		(start 123.76531 -3.061716)
		(mid 123.791069 -3.023137)
		(end 123.800108 -2.977642)
		(stroke
			(width 0.06223)
			(type default)
		)
		(layer "B.Cu")
	)
	(gr_line
		(start 123.796552 -39.957248)
		(end 123.7996 -39.9542)
		(stroke
			(width 0.06223)
			(type default)
		)
		(layer "B.Cu")
	)
	(gr_line
		(start 123.796552 -39.189152)
		(end 123.7996 -39.1922)
		(stroke
			(width 0.06223)
			(type default)
		)
		(layer "B.Cu")
	)
	(gr_line
		(start 123.7996 -39.751)
		(end 123.7996 -39.9542)
		(stroke
			(width 0.06223)
			(type default)
		)
		(layer "B.Cu")
	)
	(gr_arc
		(start 123.800108 -3.622294)
		(mid 123.791059 -3.576804)
		(end 123.76531 -3.53822)
		(stroke
			(width 0.06223)
			(type default)
		)
		(layer "B.Cu")
	)
	(gr_line
		(start 123.800108 -3.622294)
		(end 123.800108 -3.999992)
		(stroke
			(width 0.06223)
			(type default)
		)
		(layer "B.Cu")
	)
	(gr_line
		(start 123.800108 -2.600198)
		(end 123.800108 -2.977642)
		(stroke
			(width 0.06223)
			(type default)
		)
		(layer "B.Cu")
	)
	(gr_line
		(start 123.83516 -48.711866)
		(end 124.16663 -48.380396)
		(stroke
			(width 0.06223)
			(type default)
		)
		(layer "B.Cu")
	)
	(gr_line
		(start 123.83516 -47.675546)
		(end 124.16663 -48.007016)
		(stroke
			(width 0.06223)
			(type default)
		)
		(layer "B.Cu")
	)
	(gr_arc
		(start 123.911106 -55.40502)
		(mid 123.973971 -55.378981)
		(end 124.000006 -55.31612)
		(stroke
			(width 0.04445)
			(type default)
		)
		(layer "B.Cu")
	)
	(gr_line
		(start 123.971558 -50.05705)
		(end 123.971558 -50.129948)
		(stroke
			(width 0.04445)
			(type default)
		)
		(layer "B.Cu")
	)
	(gr_line
		(start 123.971558 -50.05705)
		(end 123.987306 -50.041302)
		(stroke
			(width 0.04445)
			(type default)
		)
		(layer "B.Cu")
	)
	(gr_arc
		(start 124.000006 -55.68442)
		(mid 123.973968 -55.621558)
		(end 123.911106 -55.59552)
		(stroke
			(width 0.04445)
			(type default)
		)
		(layer "B.Cu")
	)
	(gr_line
		(start 124.000006 -55.68442)
		(end 124.000006 -56.000142)
		(stroke
			(width 0.04445)
			(type default)
		)
		(layer "B.Cu")
	)
	(gr_line
		(start 124.000006 -55.000144)
		(end 124.000006 -55.31612)
		(stroke
			(width 0.04445)
			(type default)
		)
		(layer "B.Cu")
	)
	(gr_line
		(start 124.030232 -50.344324)
		(end 124.259086 -50.344324)
		(stroke
			(width 0.04445)
			(type default)
		)
		(layer "B.Cu")
	)
	(gr_line
		(start 124.10313 -42.539412)
		(end 124.109734 -42.508678)
		(stroke
			(width 0.06223)
			(type default)
		)
		(layer "B.Cu")
	)
	(gr_line
		(start 124.109734 -42.508678)
		(end 124.126752 -42.482262)
		(stroke
			(width 0.06223)
			(type default)
		)
		(layer "B.Cu")
	)
	(gr_line
		(start 124.16663 -48.007016)
		(end 124.16663 -48.380396)
		(stroke
			(width 0.06223)
			(type default)
		)
		(layer "B.Cu")
	)
	(gr_line
		(start 124.259086 -50.344324)
		(end 124.27458 -50.32883)
		(stroke
			(width 0.04445)
			(type default)
		)
		(layer "B.Cu")
	)
	(gr_line
		(start 124.419106 -22.811994)
		(end 124.590048 -23.615904)
		(stroke
			(width 0.06223)
			(type default)
		)
		(layer "B.Cu")
	)
	(gr_line
		(start 124.686314 -24.069548)
		(end 124.857256 -24.87422)
		(stroke
			(width 0.06223)
			(type default)
		)
		(layer "B.Cu")
	)
	(gr_line
		(start 124.810266 -22.685502)
		(end 125.12675 -22.891242)
		(stroke
			(width 0.06223)
			(type default)
		)
		(layer "B.Cu")
	)
	(gr_line
		(start 124.95276 -25.324054)
		(end 125.124464 -26.132028)
		(stroke
			(width 0.06223)
			(type default)
		)
		(layer "B.Cu")
	)
	(gr_line
		(start 124.9934 -39.751)
		(end 124.9934 -40.005)
		(stroke
			(width 0.06223)
			(type default)
		)
		(layer "B.Cu")
	)
	(gr_line
		(start 124.9934 -39.1922)
		(end 124.996448 -39.189152)
		(stroke
			(width 0.06223)
			(type default)
		)
		(layer "B.Cu")
	)
	(gr_line
		(start 124.998988 -23.572724)
		(end 125.204474 -23.256494)
		(stroke
			(width 0.06223)
			(type default)
		)
		(layer "B.Cu")
	)
	(gr_line
		(start 125.077474 -23.942802)
		(end 125.393958 -24.148288)
		(stroke
			(width 0.06223)
			(type default)
		)
		(layer "B.Cu")
	)
	(gr_line
		(start 125.12675 -22.891242)
		(end 125.204474 -23.256494)
		(stroke
			(width 0.06223)
			(type default)
		)
		(layer "B.Cu")
	)
	(gr_line
		(start 125.265942 -24.830024)
		(end 125.471682 -24.51354)
		(stroke
			(width 0.06223)
			(type default)
		)
		(layer "B.Cu")
	)
	(gr_line
		(start 125.344682 -25.199848)
		(end 125.661166 -25.405588)
		(stroke
			(width 0.06223)
			(type default)
		)
		(layer "B.Cu")
	)
	(gr_line
		(start 125.393958 -24.148288)
		(end 125.471682 -24.51354)
		(stroke
			(width 0.06223)
			(type default)
		)
		(layer "B.Cu")
	)
	(gr_line
		(start 125.435614 -41.213024)
		(end 125.476 -41.151302)
		(stroke
			(width 0.06223)
			(type default)
		)
		(layer "B.Cu")
	)
	(gr_arc
		(start 125.48108 -4.296918)
		(mid 125.526753 -4.287831)
		(end 125.565408 -4.261866)
		(stroke
			(width 0.06223)
			(type default)
		)
		(layer "B.Cu")
	)
	(gr_line
		(start 125.53315 -26.087324)
		(end 125.738636 -25.77084)
		(stroke
			(width 0.06223)
			(type default)
		)
		(layer "B.Cu")
	)
	(gr_line
		(start 125.561852 -39.995348)
		(end 125.5776 -39.9796)
		(stroke
			(width 0.06223)
			(type default)
		)
		(layer "B.Cu")
	)
	(gr_arc
		(start 125.565408 -4.261866)
		(mid 125.591151 -4.223285)
		(end 125.600206 -4.177792)
		(stroke
			(width 0.06223)
			(type default)
		)
		(layer "B.Cu")
	)
	(gr_line
		(start 125.574552 -39.189152)
		(end 125.5776 -39.1922)
		(stroke
			(width 0.06223)
			(type default)
		)
		(layer "B.Cu")
	)
	(gr_line
		(start 125.5776 -39.751)
		(end 125.5776 -39.9796)
		(stroke
			(width 0.06223)
			(type default)
		)
		(layer "B.Cu")
	)
	(gr_arc
		(start 125.600206 -4.822444)
		(mid 125.591157 -4.776954)
		(end 125.565408 -4.73837)
		(stroke
			(width 0.06223)
			(type default)
		)
		(layer "B.Cu")
	)
	(gr_line
		(start 125.600206 -4.822444)
		(end 125.600206 -5.200142)
		(stroke
			(width 0.06223)
			(type default)
		)
		(layer "B.Cu")
	)
	(gr_line
		(start 125.600206 -3.800094)
		(end 125.600206 -4.177792)
		(stroke
			(width 0.06223)
			(type default)
		)
		(layer "B.Cu")
	)
	(gr_line
		(start 125.622304 -26.599388)
		(end 125.63094 -26.558748)
		(stroke
			(width 0.06223)
			(type default)
		)
		(layer "B.Cu")
	)
	(gr_line
		(start 125.622304 -26.517854)
		(end 125.63094 -26.558748)
		(stroke
			(width 0.06223)
			(type default)
		)
		(layer "B.Cu")
	)
	(gr_line
		(start 125.661166 -25.405588)
		(end 125.738636 -25.77084)
		(stroke
			(width 0.06223)
			(type default)
		)
		(layer "B.Cu")
	)
	(gr_line
		(start 125.673104 -48.469804)
		(end 125.690122 -48.443388)
		(stroke
			(width 0.06223)
			(type default)
		)
		(layer "B.Cu")
	)
	(gr_line
		(start 125.690122 -48.443388)
		(end 125.696726 -48.412654)
		(stroke
			(width 0.06223)
			(type default)
		)
		(layer "B.Cu")
	)
	(gr_line
		(start 126.000002 -77.0001)
		(end 126.315724 -77.0001)
		(stroke
			(width 0.04445)
			(type default)
		)
		(layer "B.Cu")
	)
	(gr_line
		(start 126.000002 -76.000102)
		(end 126.315724 -76.000102)
		(stroke
			(width 0.04445)
			(type default)
		)
		(layer "B.Cu")
	)
	(gr_line
		(start 126.000002 -75.000104)
		(end 126.315724 -75.000104)
		(stroke
			(width 0.04445)
			(type default)
		)
		(layer "B.Cu")
	)
	(gr_line
		(start 126.000002 -74.000106)
		(end 126.315724 -74.000106)
		(stroke
			(width 0.04445)
			(type default)
		)
		(layer "B.Cu")
	)
	(gr_line
		(start 126.000002 -73.000108)
		(end 126.304802 -73.000108)
		(stroke
			(width 0.04445)
			(type default)
		)
		(layer "B.Cu")
	)
	(gr_line
		(start 126.000002 -72.00011)
		(end 126.304802 -72.00011)
		(stroke
			(width 0.04445)
			(type default)
		)
		(layer "B.Cu")
	)
	(gr_line
		(start 126.000002 -71.000112)
		(end 126.304802 -71.000112)
		(stroke
			(width 0.04445)
			(type default)
		)
		(layer "B.Cu")
	)
	(gr_line
		(start 126.000002 -70.000114)
		(end 126.304802 -70.000114)
		(stroke
			(width 0.04445)
			(type default)
		)
		(layer "B.Cu")
	)
	(gr_line
		(start 126.000002 -69.000116)
		(end 126.304802 -69.000116)
		(stroke
			(width 0.04445)
			(type default)
		)
		(layer "B.Cu")
	)
	(gr_line
		(start 126.000002 -68.000118)
		(end 126.304802 -68.000118)
		(stroke
			(width 0.04445)
			(type default)
		)
		(layer "B.Cu")
	)
	(gr_line
		(start 126.000002 -66.000122)
		(end 126.304802 -66.000122)
		(stroke
			(width 0.04445)
			(type default)
		)
		(layer "B.Cu")
	)
	(gr_line
		(start 126.000002 -65.000124)
		(end 126.304802 -65.000124)
		(stroke
			(width 0.04445)
			(type default)
		)
		(layer "B.Cu")
	)
	(gr_line
		(start 126.000002 -64.000126)
		(end 126.304802 -64.000126)
		(stroke
			(width 0.04445)
			(type default)
		)
		(layer "B.Cu")
	)
	(gr_line
		(start 126.000002 -63.000128)
		(end 126.304802 -63.000128)
		(stroke
			(width 0.04445)
			(type default)
		)
		(layer "B.Cu")
	)
	(gr_line
		(start 126.000002 -62.00013)
		(end 126.304802 -62.00013)
		(stroke
			(width 0.04445)
			(type default)
		)
		(layer "B.Cu")
	)
	(gr_line
		(start 126.000002 -61.000132)
		(end 126.304802 -61.000132)
		(stroke
			(width 0.04445)
			(type default)
		)
		(layer "B.Cu")
	)
	(gr_line
		(start 126.10592 -22.46249)
		(end 126.277878 -23.270718)
		(stroke
			(width 0.06223)
			(type default)
		)
		(layer "B.Cu")
	)
	(gr_arc
		(start 126.304802 -73.000108)
		(mid 126.375381 -72.970869)
		(end 126.404624 -72.900286)
		(stroke
			(width 0.04445)
			(type default)
		)
		(layer "B.Cu")
	)
	(gr_arc
		(start 126.304802 -72.00011)
		(mid 126.375381 -71.970871)
		(end 126.404624 -71.900288)
		(stroke
			(width 0.04445)
			(type default)
		)
		(layer "B.Cu")
	)
	(gr_arc
		(start 126.304802 -71.000112)
		(mid 126.375382 -70.970873)
		(end 126.404624 -70.90029)
		(stroke
			(width 0.04445)
			(type default)
		)
		(layer "B.Cu")
	)
	(gr_arc
		(start 126.304802 -70.000114)
		(mid 126.375383 -69.970876)
		(end 126.404624 -69.900292)
		(stroke
			(width 0.04445)
			(type default)
		)
		(layer "B.Cu")
	)
	(gr_arc
		(start 126.304802 -69.000116)
		(mid 126.375383 -68.970878)
		(end 126.404624 -68.900294)
		(stroke
			(width 0.04445)
			(type default)
		)
		(layer "B.Cu")
	)
	(gr_arc
		(start 126.304802 -68.000118)
		(mid 126.375384 -67.97088)
		(end 126.404624 -67.900296)
		(stroke
			(width 0.04445)
			(type default)
		)
		(layer "B.Cu")
	)
	(gr_arc
		(start 126.304802 -66.000122)
		(mid 126.375386 -65.970884)
		(end 126.404624 -65.9003)
		(stroke
			(width 0.04445)
			(type default)
		)
		(layer "B.Cu")
	)
	(gr_arc
		(start 126.304802 -65.000124)
		(mid 126.375387 -64.970887)
		(end 126.404624 -64.900302)
		(stroke
			(width 0.04445)
			(type default)
		)
		(layer "B.Cu")
	)
	(gr_arc
		(start 126.304802 -64.000126)
		(mid 126.375387 -63.970888)
		(end 126.404624 -63.900304)
		(stroke
			(width 0.04445)
			(type default)
		)
		(layer "B.Cu")
	)
	(gr_arc
		(start 126.304802 -63.000128)
		(mid 126.375387 -62.970891)
		(end 126.404624 -62.900306)
		(stroke
			(width 0.04445)
			(type default)
		)
		(layer "B.Cu")
	)
	(gr_arc
		(start 126.304802 -62.00013)
		(mid 126.375388 -61.970893)
		(end 126.404624 -61.900308)
		(stroke
			(width 0.04445)
			(type default)
		)
		(layer "B.Cu")
	)
	(gr_arc
		(start 126.304802 -61.000132)
		(mid 126.375389 -60.970895)
		(end 126.404624 -60.90031)
		(stroke
			(width 0.04445)
			(type default)
		)
		(layer "B.Cu")
	)
	(gr_line
		(start 126.373382 -23.71979)
		(end 126.544832 -24.52624)
		(stroke
			(width 0.06223)
			(type default)
		)
		(layer "B.Cu")
	)
	(gr_arc
		(start 126.404624 -77.089)
		(mid 126.378586 -77.026138)
		(end 126.315724 -77.0001)
		(stroke
			(width 0.04445)
			(type default)
		)
		(layer "B.Cu")
	)
	(gr_arc
		(start 126.404624 -76.089002)
		(mid 126.378588 -76.02613)
		(end 126.315724 -76.000102)
		(stroke
			(width 0.04445)
			(type default)
		)
		(layer "B.Cu")
	)
	(gr_arc
		(start 126.404624 -75.089004)
		(mid 126.378586 -75.026142)
		(end 126.315724 -75.000104)
		(stroke
			(width 0.04445)
			(type default)
		)
		(layer "B.Cu")
	)
	(gr_arc
		(start 126.404624 -74.089006)
		(mid 126.378586 -74.026144)
		(end 126.315724 -74.000106)
		(stroke
			(width 0.04445)
			(type default)
		)
		(layer "B.Cu")
	)
	(gr_line
		(start 126.497588 -22.337776)
		(end 126.814326 -22.543516)
		(stroke
			(width 0.06223)
			(type default)
		)
		(layer "B.Cu")
	)
	(gr_arc
		(start 126.595124 -72.900032)
		(mid 126.624436 -72.970796)
		(end 126.6952 -73.000108)
		(stroke
			(width 0.04445)
			(type default)
		)
		(layer "B.Cu")
	)
	(gr_arc
		(start 126.595124 -71.900034)
		(mid 126.624436 -71.970798)
		(end 126.6952 -72.00011)
		(stroke
			(width 0.04445)
			(type default)
		)
		(layer "B.Cu")
	)
	(gr_arc
		(start 126.595124 -70.900036)
		(mid 126.624436 -70.9708)
		(end 126.6952 -71.000112)
		(stroke
			(width 0.04445)
			(type default)
		)
		(layer "B.Cu")
	)
	(gr_arc
		(start 126.595124 -69.900038)
		(mid 126.624436 -69.970802)
		(end 126.6952 -70.000114)
		(stroke
			(width 0.04445)
			(type default)
		)
		(layer "B.Cu")
	)
	(gr_arc
		(start 126.595124 -68.90004)
		(mid 126.624436 -68.970804)
		(end 126.6952 -69.000116)
		(stroke
			(width 0.04445)
			(type default)
		)
		(layer "B.Cu")
	)
	(gr_arc
		(start 126.595124 -67.900042)
		(mid 126.624436 -67.970806)
		(end 126.6952 -68.000118)
		(stroke
			(width 0.04445)
			(type default)
		)
		(layer "B.Cu")
	)
	(gr_arc
		(start 126.595124 -65.900046)
		(mid 126.624436 -65.97081)
		(end 126.6952 -66.000122)
		(stroke
			(width 0.04445)
			(type default)
		)
		(layer "B.Cu")
	)
	(gr_arc
		(start 126.595124 -64.900048)
		(mid 126.624453 -64.970781)
		(end 126.6952 -65.000124)
		(stroke
			(width 0.04445)
			(type default)
		)
		(layer "B.Cu")
	)
	(gr_arc
		(start 126.595124 -63.90005)
		(mid 126.624436 -63.970814)
		(end 126.6952 -64.000126)
		(stroke
			(width 0.04445)
			(type default)
		)
		(layer "B.Cu")
	)
	(gr_arc
		(start 126.595124 -62.900052)
		(mid 126.624419 -62.970847)
		(end 126.6952 -63.000128)
		(stroke
			(width 0.04445)
			(type default)
		)
		(layer "B.Cu")
	)
	(gr_arc
		(start 126.595124 -61.900054)
		(mid 126.624419 -61.970848)
		(end 126.6952 -62.00013)
		(stroke
			(width 0.04445)
			(type default)
		)
		(layer "B.Cu")
	)
	(gr_arc
		(start 126.595124 -60.900056)
		(mid 126.624436 -60.97082)
		(end 126.6952 -61.000132)
		(stroke
			(width 0.04445)
			(type default)
		)
		(layer "B.Cu")
	)
	(gr_line
		(start 126.641098 -24.978614)
		(end 126.81204 -25.78227)
		(stroke
			(width 0.06223)
			(type default)
		)
		(layer "B.Cu")
	)
	(gr_arc
		(start 126.684024 -77.0001)
		(mid 126.621147 -77.02613)
		(end 126.595124 -77.089)
		(stroke
			(width 0.04445)
			(type default)
		)
		(layer "B.Cu")
	)
	(gr_line
		(start 126.684024 -77.0001)
		(end 127 -77.0001)
		(stroke
			(width 0.04445)
			(type default)
		)
		(layer "B.Cu")
	)
	(gr_arc
		(start 126.684024 -76.000102)
		(mid 126.621162 -76.02614)
		(end 126.595124 -76.089002)
		(stroke
			(width 0.04445)
			(type default)
		)
		(layer "B.Cu")
	)
	(gr_line
		(start 126.684024 -76.000102)
		(end 127 -76.000102)
		(stroke
			(width 0.04445)
			(type default)
		)
		(layer "B.Cu")
	)
	(gr_arc
		(start 126.684024 -75.000104)
		(mid 126.621148 -75.026134)
		(end 126.595124 -75.089004)
		(stroke
			(width 0.04445)
			(type default)
		)
		(layer "B.Cu")
	)
	(gr_line
		(start 126.684024 -75.000104)
		(end 127 -75.000104)
		(stroke
			(width 0.04445)
			(type default)
		)
		(layer "B.Cu")
	)
	(gr_arc
		(start 126.684024 -74.000106)
		(mid 126.621149 -74.026136)
		(end 126.595124 -74.089006)
		(stroke
			(width 0.04445)
			(type default)
		)
		(layer "B.Cu")
	)
	(gr_line
		(start 126.684024 -74.000106)
		(end 127 -74.000106)
		(stroke
			(width 0.04445)
			(type default)
		)
		(layer "B.Cu")
	)
	(gr_line
		(start 126.68631 -23.225506)
		(end 126.89205 -22.908768)
		(stroke
			(width 0.06223)
			(type default)
		)
		(layer "B.Cu")
	)
	(gr_line
		(start 126.6952 -73.000108)
		(end 127 -73.000108)
		(stroke
			(width 0.04445)
			(type default)
		)
		(layer "B.Cu")
	)
	(gr_line
		(start 126.6952 -72.00011)
		(end 127 -72.00011)
		(stroke
			(width 0.04445)
			(type default)
		)
		(layer "B.Cu")
	)
	(gr_line
		(start 126.6952 -71.000112)
		(end 127 -71.000112)
		(stroke
			(width 0.04445)
			(type default)
		)
		(layer "B.Cu")
	)
	(gr_line
		(start 126.6952 -70.000114)
		(end 127 -70.000114)
		(stroke
			(width 0.04445)
			(type default)
		)
		(layer "B.Cu")
	)
	(gr_line
		(start 126.6952 -69.000116)
		(end 127 -69.000116)
		(stroke
			(width 0.04445)
			(type default)
		)
		(layer "B.Cu")
	)
	(gr_line
		(start 126.6952 -68.000118)
		(end 127 -68.000118)
		(stroke
			(width 0.04445)
			(type default)
		)
		(layer "B.Cu")
	)
	(gr_line
		(start 126.6952 -66.000122)
		(end 127 -66.000122)
		(stroke
			(width 0.04445)
			(type default)
		)
		(layer "B.Cu")
	)
	(gr_line
		(start 126.6952 -65.000124)
		(end 127 -65.000124)
		(stroke
			(width 0.04445)
			(type default)
		)
		(layer "B.Cu")
	)
	(gr_line
		(start 126.6952 -64.000126)
		(end 127 -64.000126)
		(stroke
			(width 0.04445)
			(type default)
		)
		(layer "B.Cu")
	)
	(gr_line
		(start 126.6952 -63.000128)
		(end 127 -63.000128)
		(stroke
			(width 0.04445)
			(type default)
		)
		(layer "B.Cu")
	)
	(gr_line
		(start 126.6952 -62.00013)
		(end 127 -62.00013)
		(stroke
			(width 0.04445)
			(type default)
		)
		(layer "B.Cu")
	)
	(gr_line
		(start 126.6952 -61.000132)
		(end 127 -61.000132)
		(stroke
			(width 0.04445)
			(type default)
		)
		(layer "B.Cu")
	)
	(gr_line
		(start 126.764796 -23.595076)
		(end 127.081534 -23.800562)
		(stroke
			(width 0.06223)
			(type default)
		)
		(layer "B.Cu")
	)
	(gr_line
		(start 126.814326 -22.543516)
		(end 126.89205 -22.908768)
		(stroke
			(width 0.06223)
			(type default)
		)
		(layer "B.Cu")
	)
	(gr_line
		(start 126.873 -39.751)
		(end 126.873 -39.9796)
		(stroke
			(width 0.06223)
			(type default)
		)
		(layer "B.Cu")
	)
	(gr_line
		(start 126.873 -39.1922)
		(end 126.876048 -39.189152)
		(stroke
			(width 0.06223)
			(type default)
		)
		(layer "B.Cu")
	)
	(gr_line
		(start 126.953518 -24.482298)
		(end 127.159258 -24.165814)
		(stroke
			(width 0.06223)
			(type default)
		)
		(layer "B.Cu")
	)
	(gr_line
		(start 127.032258 -24.852122)
		(end 127.348742 -25.057608)
		(stroke
			(width 0.06223)
			(type default)
		)
		(layer "B.Cu")
	)
	(gr_line
		(start 127.081534 -23.800562)
		(end 127.159258 -24.165814)
		(stroke
			(width 0.06223)
			(type default)
		)
		(layer "B.Cu")
	)
	(gr_line
		(start 127.22098 -25.73909)
		(end 127.426466 -25.42286)
		(stroke
			(width 0.06223)
			(type default)
		)
		(layer "B.Cu")
	)
	(gr_arc
		(start 127.280924 -3.096768)
		(mid 127.32658 -3.087651)
		(end 127.365252 -3.061716)
		(stroke
			(width 0.06223)
			(type default)
		)
		(layer "B.Cu")
	)
	(gr_line
		(start 127.288036 -26.14803)
		(end 127.296672 -26.10739)
		(stroke
			(width 0.06223)
			(type default)
		)
		(layer "B.Cu")
	)
	(gr_line
		(start 127.288036 -26.06675)
		(end 127.296672 -26.10739)
		(stroke
			(width 0.06223)
			(type default)
		)
		(layer "B.Cu")
	)
	(gr_line
		(start 127.348742 -25.057608)
		(end 127.426466 -25.42286)
		(stroke
			(width 0.06223)
			(type default)
		)
		(layer "B.Cu")
	)
	(gr_arc
		(start 127.365252 -3.53822)
		(mid 127.326583 -3.512287)
		(end 127.280924 -3.503168)
		(stroke
			(width 0.06223)
			(type default)
		)
		(layer "B.Cu")
	)
	(gr_arc
		(start 127.365252 -3.061716)
		(mid 127.391026 -3.023143)
		(end 127.40005 -2.977642)
		(stroke
			(width 0.06223)
			(type default)
		)
		(layer "B.Cu")
	)
	(gr_arc
		(start 127.40005 -3.622294)
		(mid 127.391025 -3.576791)
		(end 127.365252 -3.53822)
		(stroke
			(width 0.06223)
			(type default)
		)
		(layer "B.Cu")
	)
	(gr_line
		(start 127.40005 -3.622294)
		(end 127.40005 -3.999992)
		(stroke
			(width 0.06223)
			(type default)
		)
		(layer "B.Cu")
	)
	(gr_line
		(start 127.40005 -2.600198)
		(end 127.40005 -2.977642)
		(stroke
			(width 0.06223)
			(type default)
		)
		(layer "B.Cu")
	)
	(gr_line
		(start 127.441452 -39.969948)
		(end 127.4572 -39.9542)
		(stroke
			(width 0.06223)
			(type default)
		)
		(layer "B.Cu")
	)
	(gr_line
		(start 127.454152 -39.189152)
		(end 127.4572 -39.1922)
		(stroke
			(width 0.06223)
			(type default)
		)
		(layer "B.Cu")
	)
	(gr_line
		(start 127.4572 -39.751)
		(end 127.4572 -39.9542)
		(stroke
			(width 0.06223)
			(type default)
		)
		(layer "B.Cu")
	)
	(gr_line
		(start 127.636016 -22.259036)
		(end 127.807212 -23.064216)
		(stroke
			(width 0.06223)
			(type default)
		)
		(layer "B.Cu")
	)
	(gr_line
		(start 127.77724 -46.059344)
		(end 127.785876 -46.099984)
		(stroke
			(width 0.06223)
			(type default)
		)
		(layer "B.Cu")
	)
	(gr_line
		(start 127.77724 -46.059344)
		(end 127.785876 -46.01845)
		(stroke
			(width 0.06223)
			(type default)
		)
		(layer "B.Cu")
	)
	(gr_line
		(start 127.902716 -23.513542)
		(end 128.07442 -24.321516)
		(stroke
			(width 0.06223)
			(type default)
		)
		(layer "B.Cu")
	)
	(gr_line
		(start 128.027176 -22.132544)
		(end 128.343914 -22.33803)
		(stroke
			(width 0.06223)
			(type default)
		)
		(layer "B.Cu")
	)
	(gr_line
		(start 128.170686 -24.77262)
		(end 128.341628 -25.576276)
		(stroke
			(width 0.06223)
			(type default)
		)
		(layer "B.Cu")
	)
	(gr_line
		(start 128.215898 -23.019766)
		(end 128.421638 -22.703282)
		(stroke
			(width 0.06223)
			(type default)
		)
		(layer "B.Cu")
	)
	(gr_line
		(start 128.2192 -41.440862)
		(end 128.245362 -41.467024)
		(stroke
			(width 0.06223)
			(type default)
		)
		(layer "B.Cu")
	)
	(gr_line
		(start 128.2192 -41.148)
		(end 128.2192 -41.440862)
		(stroke
			(width 0.06223)
			(type default)
		)
		(layer "B.Cu")
	)
	(gr_line
		(start 128.2192 -40.5892)
		(end 128.222248 -40.586152)
		(stroke
			(width 0.06223)
			(type default)
		)
		(layer "B.Cu")
	)
	(gr_line
		(start 128.22809 -48.181768)
		(end 128.234694 -48.212502)
		(stroke
			(width 0.06223)
			(type default)
		)
		(layer "B.Cu")
	)
	(gr_line
		(start 128.234694 -48.212502)
		(end 128.251458 -48.238156)
		(stroke
			(width 0.06223)
			(type default)
		)
		(layer "B.Cu")
	)
	(gr_line
		(start 128.24968 -33.135062)
		(end 128.258316 -33.175702)
		(stroke
			(width 0.06223)
			(type default)
		)
		(layer "B.Cu")
	)
	(gr_line
		(start 128.24968 -33.135062)
		(end 128.258316 -33.094676)
		(stroke
			(width 0.06223)
			(type default)
		)
		(layer "B.Cu")
	)
	(gr_line
		(start 128.258316 -33.175956)
		(end 128.258316 -33.176464)
		(stroke
			(width 0.06223)
			(type default)
		)
		(layer "B.Cu")
	)
	(gr_line
		(start 128.294638 -23.38959)
		(end 128.611122 -23.595076)
		(stroke
			(width 0.06223)
			(type default)
		)
		(layer "B.Cu")
	)
	(gr_line
		(start 128.343914 -22.33803)
		(end 128.421638 -22.703282)
		(stroke
			(width 0.06223)
			(type default)
		)
		(layer "B.Cu")
	)
	(gr_line
		(start 128.483106 -24.276812)
		(end 128.688846 -23.960328)
		(stroke
			(width 0.06223)
			(type default)
		)
		(layer "B.Cu")
	)
	(gr_line
		(start 128.561846 -24.646636)
		(end 128.87833 -24.852122)
		(stroke
			(width 0.06223)
			(type default)
		)
		(layer "B.Cu")
	)
	(gr_line
		(start 128.611122 -23.595076)
		(end 128.688846 -23.960328)
		(stroke
			(width 0.06223)
			(type default)
		)
		(layer "B.Cu")
	)
	(gr_line
		(start 128.750568 -25.533604)
		(end 128.956054 -25.217374)
		(stroke
			(width 0.06223)
			(type default)
		)
		(layer "B.Cu")
	)
	(gr_line
		(start 128.800352 -40.586152)
		(end 128.8034 -40.5892)
		(stroke
			(width 0.06223)
			(type default)
		)
		(layer "B.Cu")
	)
	(gr_line
		(start 128.8034 -41.148)
		(end 128.8034 -41.487344)
		(stroke
			(width 0.06223)
			(type default)
		)
		(layer "B.Cu")
	)
	(gr_line
		(start 128.817624 -25.942544)
		(end 128.82626 -25.901904)
		(stroke
			(width 0.06223)
			(type default)
		)
		(layer "B.Cu")
	)
	(gr_line
		(start 128.817624 -25.861264)
		(end 128.82626 -25.901904)
		(stroke
			(width 0.06223)
			(type default)
		)
		(layer "B.Cu")
	)
	(gr_line
		(start 128.87833 -24.852122)
		(end 128.956054 -25.217374)
		(stroke
			(width 0.06223)
			(type default)
		)
		(layer "B.Cu")
	)
	(gr_line
		(start 128.912874 -49.257966)
		(end 128.93675 -49.294542)
		(stroke
			(width 0.06223)
			(type default)
		)
		(layer "B.Cu")
	)
	(gr_line
		(start 128.93675 -49.294542)
		(end 128.972564 -49.317656)
		(stroke
			(width 0.06223)
			(type default)
		)
		(layer "B.Cu")
	)
	(gr_arc
		(start 129.081022 -4.296918)
		(mid 129.126686 -4.287817)
		(end 129.16535 -4.261866)
		(stroke
			(width 0.06223)
			(type default)
		)
		(layer "B.Cu")
	)
	(gr_line
		(start 129.11201 -76.401422)
		(end 129.235708 -76.401422)
		(stroke
			(width 0.04445)
			(type default)
		)
		(layer "B.Cu")
	)
	(gr_line
		(start 129.13614 -77.405484)
		(end 129.144268 -77.405484)
		(stroke
			(width 0.04445)
			(type default)
		)
		(layer "B.Cu")
	)
	(gr_arc
		(start 129.16535 -4.261866)
		(mid 129.191084 -4.223282)
		(end 129.200148 -4.177792)
		(stroke
			(width 0.06223)
			(type default)
		)
		(layer "B.Cu")
	)
	(gr_line
		(start 129.179828 -75.402694)
		(end 129.299716 -75.402694)
		(stroke
			(width 0.04445)
			(type default)
		)
		(layer "B.Cu")
	)
	(gr_line
		(start 129.199894 -21.30552)
		(end 129.370836 -22.10943)
		(stroke
			(width 0.06223)
			(type default)
		)
		(layer "B.Cu")
	)
	(gr_arc
		(start 129.200148 -4.822444)
		(mid 129.191099 -4.776954)
		(end 129.16535 -4.73837)
		(stroke
			(width 0.06223)
			(type default)
		)
		(layer "B.Cu")
	)
	(gr_line
		(start 129.200148 -4.822444)
		(end 129.200148 -5.200142)
		(stroke
			(width 0.06223)
			(type default)
		)
		(layer "B.Cu")
	)
	(gr_line
		(start 129.200148 -3.800094)
		(end 129.200148 -4.177792)
		(stroke
			(width 0.06223)
			(type default)
		)
		(layer "B.Cu")
	)
	(gr_line
		(start 129.238248 -76.398882)
		(end 129.388362 -76.248768)
		(stroke
			(width 0.04445)
			(type default)
		)
		(layer "B.Cu")
	)
	(gr_line
		(start 129.302256 -75.400154)
		(end 129.45618 -75.24623)
		(stroke
			(width 0.04445)
			(type default)
		)
		(layer "B.Cu")
	)
	(gr_line
		(start 129.325116 -76.591922)
		(end 129.388362 -76.655168)
		(stroke
			(width 0.04445)
			(type default)
		)
		(layer "B.Cu")
	)
	(gr_line
		(start 129.32664 -77.492606)
		(end 129.334768 -77.492606)
		(stroke
			(width 0.04445)
			(type default)
		)
		(layer "B.Cu")
	)
	(gr_line
		(start 129.346706 -77.302106)
		(end 129.466594 -77.302106)
		(stroke
			(width 0.04445)
			(type default)
		)
		(layer "B.Cu")
	)
	(gr_line
		(start 129.37871 -74.108818)
		(end 129.495042 -74.108818)
		(stroke
			(width 0.04445)
			(type default)
		)
		(layer "B.Cu")
	)
	(gr_line
		(start 129.388362 -76.655168)
		(end 129.41046 -76.655168)
		(stroke
			(width 0.04445)
			(type default)
		)
		(layer "B.Cu")
	)
	(gr_line
		(start 129.388362 -76.248768)
		(end 129.41046 -76.248768)
		(stroke
			(width 0.04445)
			(type default)
		)
		(layer "B.Cu")
	)
	(gr_line
		(start 129.396744 -75.593194)
		(end 129.45618 -75.65263)
		(stroke
			(width 0.04445)
			(type default)
		)
		(layer "B.Cu")
	)
	(gr_line
		(start 129.406396 -36.702238)
		(end 129.415032 -36.662106)
		(stroke
			(width 0.06223)
			(type default)
		)
		(layer "B.Cu")
	)
	(gr_line
		(start 129.406396 -36.621466)
		(end 129.415032 -36.662106)
		(stroke
			(width 0.06223)
			(type default)
		)
		(layer "B.Cu")
	)
	(gr_line
		(start 129.41046 -76.655168)
		(end 129.534158 -76.655168)
		(stroke
			(width 0.06223)
			(type default)
		)
		(layer "B.Cu")
	)
	(gr_line
		(start 129.45618 -75.65263)
		(end 129.478278 -75.65263)
		(stroke
			(width 0.04445)
			(type default)
		)
		(layer "B.Cu")
	)
	(gr_line
		(start 129.45618 -75.24623)
		(end 129.478278 -75.24623)
		(stroke
			(width 0.04445)
			(type default)
		)
		(layer "B.Cu")
	)
	(gr_line
		(start 129.466594 -22.561042)
		(end 129.638298 -23.368254)
		(stroke
			(width 0.06223)
			(type default)
		)
		(layer "B.Cu")
	)
	(gr_line
		(start 129.469134 -77.299566)
		(end 129.623058 -77.145642)
		(stroke
			(width 0.04445)
			(type default)
		)
		(layer "B.Cu")
	)
	(gr_line
		(start 129.478278 -75.65263)
		(end 129.598166 -75.65263)
		(stroke
			(width 0.06223)
			(type default)
		)
		(layer "B.Cu")
	)
	(gr_line
		(start 129.497582 -74.106278)
		(end 129.655062 -73.948798)
		(stroke
			(width 0.04445)
			(type default)
		)
		(layer "B.Cu")
	)
	(gr_line
		(start 129.563622 -77.492606)
		(end 129.623058 -77.552042)
		(stroke
			(width 0.04445)
			(type default)
		)
		(layer "B.Cu")
	)
	(gr_line
		(start 129.590038 -33.104074)
		(end 129.598674 -33.144968)
		(stroke
			(width 0.06223)
			(type default)
		)
		(layer "B.Cu")
	)
	(gr_line
		(start 129.590038 -33.104074)
		(end 129.598674 -33.063434)
		(stroke
			(width 0.06223)
			(type default)
		)
		(layer "B.Cu")
	)
	(gr_line
		(start 129.591054 -21.17852)
		(end 129.907284 -21.383752)
		(stroke
			(width 0.06223)
			(type default)
		)
		(layer "B.Cu")
	)
	(gr_line
		(start 129.599182 -74.299318)
		(end 129.655062 -74.355198)
		(stroke
			(width 0.04445)
			(type default)
		)
		(layer "B.Cu")
	)
	(gr_line
		(start 129.623058 -77.552042)
		(end 129.645156 -77.552042)
		(stroke
			(width 0.04445)
			(type default)
		)
		(layer "B.Cu")
	)
	(gr_line
		(start 129.623058 -77.145642)
		(end 129.645156 -77.145642)
		(stroke
			(width 0.04445)
			(type default)
		)
		(layer "B.Cu")
	)
	(gr_line
		(start 129.645156 -77.552042)
		(end 129.765044 -77.552042)
		(stroke
			(width 0.06223)
			(type default)
		)
		(layer "B.Cu")
	)
	(gr_line
		(start 129.655062 -74.355198)
		(end 129.67716 -74.355198)
		(stroke
			(width 0.04445)
			(type default)
		)
		(layer "B.Cu")
	)
	(gr_line
		(start 129.655062 -73.948798)
		(end 129.67716 -73.948798)
		(stroke
			(width 0.04445)
			(type default)
		)
		(layer "B.Cu")
	)
	(gr_line
		(start 129.67716 -74.355198)
		(end 129.793492 -74.355198)
		(stroke
			(width 0.06223)
			(type default)
		)
		(layer "B.Cu")
	)
	(gr_line
		(start 129.734056 -23.819358)
		(end 129.904998 -24.62276)
		(stroke
			(width 0.06223)
			(type default)
		)
		(layer "B.Cu")
	)
	(gr_line
		(start 129.779522 -22.065488)
		(end 129.985008 -21.749004)
		(stroke
			(width 0.06223)
			(type default)
		)
		(layer "B.Cu")
	)
	(gr_line
		(start 129.858262 -22.435312)
		(end 130.174492 -22.641052)
		(stroke
			(width 0.06223)
			(type default)
		)
		(layer "B.Cu")
	)
	(gr_line
		(start 129.907284 -21.383752)
		(end 129.985008 -21.749004)
		(stroke
			(width 0.06223)
			(type default)
		)
		(layer "B.Cu")
	)
	(gr_line
		(start 130.04673 -23.322788)
		(end 130.252216 -23.006304)
		(stroke
			(width 0.06223)
			(type default)
		)
		(layer "B.Cu")
	)
	(gr_line
		(start 130.05308 -73.946258)
		(end 130.32994 -73.669398)
		(stroke
			(width 0.06223)
			(type default)
		)
		(layer "B.Cu")
	)
	(gr_line
		(start 130.072638 -67.594734)
		(end 130.221482 -67.594734)
		(stroke
			(width 0.04445)
			(type default)
		)
		(layer "B.Cu")
	)
	(gr_line
		(start 130.12547 -23.692866)
		(end 130.4417 -23.898098)
		(stroke
			(width 0.06223)
			(type default)
		)
		(layer "B.Cu")
	)
	(gr_line
		(start 130.174492 -22.641052)
		(end 130.252216 -23.006304)
		(stroke
			(width 0.06223)
			(type default)
		)
		(layer "B.Cu")
	)
	(gr_line
		(start 130.221482 -67.594734)
		(end 130.28041 -67.653662)
		(stroke
			(width 0.04445)
			(type default)
		)
		(layer "B.Cu")
	)
	(gr_line
		(start 130.260598 -67.404234)
		(end 130.28041 -67.384422)
		(stroke
			(width 0.04445)
			(type default)
		)
		(layer "B.Cu")
	)
	(gr_line
		(start 130.282188 -67.65544)
		(end 130.34899 -67.722242)
		(stroke
			(width 0.04445)
			(type default)
		)
		(layer "B.Cu")
	)
	(gr_line
		(start 130.282188 -67.382644)
		(end 130.34899 -67.315842)
		(stroke
			(width 0.04445)
			(type default)
		)
		(layer "B.Cu")
	)
	(gr_line
		(start 130.313938 -24.57958)
		(end 130.519424 -24.26335)
		(stroke
			(width 0.06223)
			(type default)
		)
		(layer "B.Cu")
	)
	(gr_line
		(start 130.32994 -73.669398)
		(end 130.70332 -73.669398)
		(stroke
			(width 0.06223)
			(type default)
		)
		(layer "B.Cu")
	)
	(gr_line
		(start 130.34899 -67.722242)
		(end 130.371088 -67.722242)
		(stroke
			(width 0.04445)
			(type default)
		)
		(layer "B.Cu")
	)
	(gr_line
		(start 130.34899 -67.315842)
		(end 130.371088 -67.315842)
		(stroke
			(width 0.04445)
			(type default)
		)
		(layer "B.Cu")
	)
	(gr_line
		(start 130.371088 -67.315842)
		(end 130.519932 -67.315842)
		(stroke
			(width 0.06223)
			(type default)
		)
		(layer "B.Cu")
	)
	(gr_line
		(start 130.38582 -25.011126)
		(end 130.394456 -24.970486)
		(stroke
			(width 0.06223)
			(type default)
		)
		(layer "B.Cu")
	)
	(gr_line
		(start 130.38582 -24.929846)
		(end 130.394456 -24.970486)
		(stroke
			(width 0.06223)
			(type default)
		)
		(layer "B.Cu")
	)
	(gr_line
		(start 130.4417 -23.898098)
		(end 130.519424 -24.26335)
		(stroke
			(width 0.06223)
			(type default)
		)
		(layer "B.Cu")
	)
	(gr_line
		(start 130.45948 -74.355198)
		(end 130.57378 -74.355198)
		(stroke
			(width 0.06223)
			(type default)
		)
		(layer "B.Cu")
	)
	(gr_line
		(start 130.4798 -59.280298)
		(end 130.546602 -59.3471)
		(stroke
			(width 0.04445)
			(type default)
		)
		(layer "B.Cu")
	)
	(gr_line
		(start 130.4798 -59.2582)
		(end 130.4798 -59.280298)
		(stroke
			(width 0.04445)
			(type default)
		)
		(layer "B.Cu")
	)
	(gr_line
		(start 130.4798 -57.0992)
		(end 130.566922 -57.012078)
		(stroke
			(width 0.06223)
			(type default)
		)
		(layer "B.Cu")
	)
	(gr_line
		(start 130.54838 -59.348878)
		(end 130.58775 -59.388248)
		(stroke
			(width 0.04445)
			(type default)
		)
		(layer "B.Cu")
	)
	(gr_line
		(start 130.565398 -49.867312)
		(end 130.600196 -49.889918)
		(stroke
			(width 0.06223)
			(type default)
		)
		(layer "B.Cu")
	)
	(gr_line
		(start 130.600196 -49.889918)
		(end 130.622802 -49.924716)
		(stroke
			(width 0.06223)
			(type default)
		)
		(layer "B.Cu")
	)
	(gr_line
		(start 130.62966 -46.590966)
		(end 130.646932 -46.510194)
		(stroke
			(width 0.06223)
			(type default)
		)
		(layer "B.Cu")
	)
	(gr_line
		(start 130.62966 -46.590966)
		(end 130.661918 -46.666912)
		(stroke
			(width 0.06223)
			(type default)
		)
		(layer "B.Cu")
	)
	(gr_line
		(start 130.70332 -73.669398)
		(end 130.98018 -73.946258)
		(stroke
			(width 0.06223)
			(type default)
		)
		(layer "B.Cu")
	)
	(gr_line
		(start 130.744214 -60.266072)
		(end 130.77825 -60.232036)
		(stroke
			(width 0.04445)
			(type default)
		)
		(layer "B.Cu")
	)
	(gr_line
		(start 130.77825 -59.388248)
		(end 130.81762 -59.348878)
		(stroke
			(width 0.04445)
			(type default)
		)
		(layer "B.Cu")
	)
	(gr_line
		(start 130.819398 -59.3471)
		(end 130.8862 -59.280298)
		(stroke
			(width 0.04445)
			(type default)
		)
		(layer "B.Cu")
	)
	(gr_line
		(start 130.82397 -44.89577)
		(end 130.828034 -44.899834)
		(stroke
			(width 0.06223)
			(type default)
		)
		(layer "B.Cu")
	)
	(gr_line
		(start 130.82397 -44.658788)
		(end 130.82397 -44.89577)
		(stroke
			(width 0.06223)
			(type default)
		)
		(layer "B.Cu")
	)
	(gr_arc
		(start 130.880866 -3.096768)
		(mid 130.926539 -3.087682)
		(end 130.965194 -3.061716)
		(stroke
			(width 0.06223)
			(type default)
		)
		(layer "B.Cu")
	)
	(gr_line
		(start 130.8862 -59.2582)
		(end 130.8862 -59.280298)
		(stroke
			(width 0.04445)
			(type default)
		)
		(layer "B.Cu")
	)
	(gr_line
		(start 130.896868 -19.667474)
		(end 131.06781 -20.471892)
		(stroke
			(width 0.06223)
			(type default)
		)
		(layer "B.Cu")
	)
	(gr_arc
		(start 130.965194 -3.061716)
		(mid 130.990935 -3.023133)
		(end 130.999992 -2.977642)
		(stroke
			(width 0.06223)
			(type default)
		)
		(layer "B.Cu")
	)
	(gr_line
		(start 130.984498 -32.407606)
		(end 130.993134 -32.447738)
		(stroke
			(width 0.06223)
			(type default)
		)
		(layer "B.Cu")
	)
	(gr_line
		(start 130.984498 -32.407606)
		(end 130.993134 -32.366966)
		(stroke
			(width 0.06223)
			(type default)
		)
		(layer "B.Cu")
	)
	(gr_arc
		(start 130.999992 -3.622294)
		(mid 130.990943 -3.576804)
		(end 130.965194 -3.53822)
		(stroke
			(width 0.06223)
			(type default)
		)
		(layer "B.Cu")
	)
	(gr_line
		(start 130.999992 -3.622294)
		(end 130.999992 -3.999992)
		(stroke
			(width 0.06223)
			(type default)
		)
		(layer "B.Cu")
	)
	(gr_line
		(start 130.999992 -2.600198)
		(end 130.999992 -2.977642)
		(stroke
			(width 0.06223)
			(type default)
		)
		(layer "B.Cu")
	)
	(gr_line
		(start 131.01066 -71.597266)
		(end 131.147566 -71.597266)
		(stroke
			(width 0.04445)
			(type default)
		)
		(layer "B.Cu")
	)
	(gr_line
		(start 131.0132 -72.595232)
		(end 131.169918 -72.595232)
		(stroke
			(width 0.04445)
			(type default)
		)
		(layer "B.Cu")
	)
	(gr_line
		(start 131.094734 -65.597024)
		(end 131.219956 -65.597024)
		(stroke
			(width 0.04445)
			(type default)
		)
		(layer "B.Cu")
	)
	(gr_line
		(start 131.12877 -69.594222)
		(end 131.285488 -69.594222)
		(stroke
			(width 0.04445)
			(type default)
		)
		(layer "B.Cu")
	)
	(gr_line
		(start 131.147566 -71.597266)
		(end 131.218432 -71.668132)
		(stroke
			(width 0.04445)
			(type default)
		)
		(layer "B.Cu")
	)
	(gr_line
		(start 131.163568 -20.92325)
		(end 131.335018 -21.730462)
		(stroke
			(width 0.06223)
			(type default)
		)
		(layer "B.Cu")
	)
	(gr_line
		(start 131.169918 -72.595232)
		(end 131.220972 -72.646286)
		(stroke
			(width 0.04445)
			(type default)
		)
		(layer "B.Cu")
	)
	(gr_line
		(start 131.193286 -72.404732)
		(end 131.220972 -72.377046)
		(stroke
			(width 0.04445)
			(type default)
		)
		(layer "B.Cu")
	)
	(gr_line
		(start 131.210558 -71.406766)
		(end 131.218432 -71.398892)
		(stroke
			(width 0.04445)
			(type default)
		)
		(layer "B.Cu")
	)
	(gr_line
		(start 131.211574 -68.594732)
		(end 131.250944 -68.634102)
		(stroke
			(width 0.04445)
			(type default)
		)
		(layer "B.Cu")
	)
	(gr_line
		(start 131.211574 -68.404232)
		(end 131.250944 -68.364862)
		(stroke
			(width 0.04445)
			(type default)
		)
		(layer "B.Cu")
	)
	(gr_line
		(start 131.22021 -71.66991)
		(end 131.287012 -71.736712)
		(stroke
			(width 0.04445)
			(type default)
		)
		(layer "B.Cu")
	)
	(gr_line
		(start 131.22021 -71.397114)
		(end 131.287012 -71.330312)
		(stroke
			(width 0.04445)
			(type default)
		)
		(layer "B.Cu")
	)
	(gr_line
		(start 131.222496 -65.599564)
		(end 131.371086 -65.748154)
		(stroke
			(width 0.04445)
			(type default)
		)
		(layer "B.Cu")
	)
	(gr_line
		(start 131.22275 -72.648064)
		(end 131.289552 -72.714866)
		(stroke
			(width 0.04445)
			(type default)
		)
		(layer "B.Cu")
	)
	(gr_line
		(start 131.22275 -72.375268)
		(end 131.289552 -72.308466)
		(stroke
			(width 0.04445)
			(type default)
		)
		(layer "B.Cu")
	)
	(gr_line
		(start 131.23799 -64.404494)
		(end 131.347972 -64.404494)
		(stroke
			(width 0.04445)
			(type default)
		)
		(layer "B.Cu")
	)
	(gr_line
		(start 131.252722 -68.63588)
		(end 131.319524 -68.702682)
		(stroke
			(width 0.04445)
			(type default)
		)
		(layer "B.Cu")
	)
	(gr_line
		(start 131.252722 -68.363084)
		(end 131.319524 -68.296282)
		(stroke
			(width 0.04445)
			(type default)
		)
		(layer "B.Cu")
	)
	(gr_line
		(start 131.2545 -31.138368)
		(end 131.425188 -30.334458)
		(stroke
			(width 0.06223)
			(type default)
		)
		(layer "B.Cu")
	)
	(gr_line
		(start 131.267962 -63.403988)
		(end 131.369054 -63.403988)
		(stroke
			(width 0.04445)
			(type default)
		)
		(layer "B.Cu")
	)
	(gr_line
		(start 131.285488 -69.594222)
		(end 131.336542 -69.645276)
		(stroke
			(width 0.04445)
			(type default)
		)
		(layer "B.Cu")
	)
	(gr_line
		(start 131.287012 -71.736712)
		(end 131.30911 -71.736712)
		(stroke
			(width 0.04445)
			(type default)
		)
		(layer "B.Cu")
	)
	(gr_line
		(start 131.287012 -71.330312)
		(end 131.30911 -71.330312)
		(stroke
			(width 0.04445)
			(type default)
		)
		(layer "B.Cu")
	)
	(gr_line
		(start 131.288028 -19.540982)
		(end 131.604766 -19.746722)
		(stroke
			(width 0.06223)
			(type default)
		)
		(layer "B.Cu")
	)
	(gr_line
		(start 131.289552 -72.714866)
		(end 131.31165 -72.714866)
		(stroke
			(width 0.04445)
			(type default)
		)
		(layer "B.Cu")
	)
	(gr_line
		(start 131.289552 -72.308466)
		(end 131.31165 -72.308466)
		(stroke
			(width 0.04445)
			(type default)
		)
		(layer "B.Cu")
	)
	(gr_line
		(start 131.306316 -65.406524)
		(end 131.371086 -65.341754)
		(stroke
			(width 0.04445)
			(type default)
		)
		(layer "B.Cu")
	)
	(gr_line
		(start 131.308856 -69.403722)
		(end 131.336542 -69.376036)
		(stroke
			(width 0.04445)
			(type default)
		)
		(layer "B.Cu")
	)
	(gr_line
		(start 131.30911 -71.330312)
		(end 131.446016 -71.330312)
		(stroke
			(width 0.06223)
			(type default)
		)
		(layer "B.Cu")
	)
	(gr_line
		(start 131.31165 -72.308466)
		(end 131.468368 -72.308466)
		(stroke
			(width 0.06223)
			(type default)
		)
		(layer "B.Cu")
	)
	(gr_line
		(start 131.319524 -68.702682)
		(end 131.341622 -68.702682)
		(stroke
			(width 0.04445)
			(type default)
		)
		(layer "B.Cu")
	)
	(gr_line
		(start 131.319524 -68.296282)
		(end 131.341622 -68.296282)
		(stroke
			(width 0.04445)
			(type default)
		)
		(layer "B.Cu")
	)
	(gr_line
		(start 131.33832 -69.647054)
		(end 131.405122 -69.713856)
		(stroke
			(width 0.04445)
			(type default)
		)
		(layer "B.Cu")
	)
	(gr_line
		(start 131.33832 -69.374258)
		(end 131.405122 -69.307456)
		(stroke
			(width 0.04445)
			(type default)
		)
		(layer "B.Cu")
	)
	(gr_line
		(start 131.345178 -61.358526)
		(end 131.460494 -61.24321)
		(stroke
			(width 0.04445)
			(type default)
		)
		(layer "B.Cu")
	)
	(gr_line
		(start 131.350512 -64.401954)
		(end 131.514342 -64.238124)
		(stroke
			(width 0.04445)
			(type default)
		)
		(layer "B.Cu")
	)
	(gr_line
		(start 131.371086 -65.748154)
		(end 131.393184 -65.748154)
		(stroke
			(width 0.04445)
			(type default)
		)
		(layer "B.Cu")
	)
	(gr_line
		(start 131.371086 -65.341754)
		(end 131.393184 -65.341754)
		(stroke
			(width 0.04445)
			(type default)
		)
		(layer "B.Cu")
	)
	(gr_line
		(start 131.371594 -63.401448)
		(end 131.544314 -63.228728)
		(stroke
			(width 0.04445)
			(type default)
		)
		(layer "B.Cu")
	)
	(gr_line
		(start 131.38277 -44.658788)
		(end 131.38277 -44.923456)
		(stroke
			(width 0.06223)
			(type default)
		)
		(layer "B.Cu")
	)
	(gr_line
		(start 131.393184 -65.341754)
		(end 131.518406 -65.341754)
		(stroke
			(width 0.06223)
			(type default)
		)
		(layer "B.Cu")
	)
	(gr_line
		(start 131.405122 -69.713856)
		(end 131.42722 -69.713856)
		(stroke
			(width 0.04445)
			(type default)
		)
		(layer "B.Cu")
	)
	(gr_line
		(start 131.405122 -69.307456)
		(end 131.42722 -69.307456)
		(stroke
			(width 0.04445)
			(type default)
		)
		(layer "B.Cu")
	)
	(gr_line
		(start 131.42722 -69.307456)
		(end 131.583938 -69.307456)
		(stroke
			(width 0.06223)
			(type default)
		)
		(layer "B.Cu")
	)
	(gr_line
		(start 131.43103 -22.18182)
		(end 131.602226 -22.986746)
		(stroke
			(width 0.06223)
			(type default)
		)
		(layer "B.Cu")
	)
	(gr_line
		(start 131.460494 -61.179964)
		(end 131.460494 -61.24321)
		(stroke
			(width 0.04445)
			(type default)
		)
		(layer "B.Cu")
	)
	(gr_line
		(start 131.460494 -61.08319)
		(end 131.460494 -61.177424)
		(stroke
			(width 0.04445)
			(type default)
		)
		(layer "B.Cu")
	)
	(gr_line
		(start 131.460494 -61.08319)
		(end 131.475988 -61.067696)
		(stroke
			(width 0.04445)
			(type default)
		)
		(layer "B.Cu")
	)
	(gr_line
		(start 131.464558 -64.594994)
		(end 131.514088 -64.644524)
		(stroke
			(width 0.04445)
			(type default)
		)
		(layer "B.Cu")
	)
	(gr_line
		(start 131.47675 -20.428204)
		(end 131.682236 -20.111974)
		(stroke
			(width 0.06223)
			(type default)
		)
		(layer "B.Cu")
	)
	(gr_line
		(start 131.503674 -63.594488)
		(end 131.544314 -63.635128)
		(stroke
			(width 0.04445)
			(type default)
		)
		(layer "B.Cu")
	)
	(gr_line
		(start 131.503928 -49.339754)
		(end 131.645152 -48.989996)
		(stroke
			(width 0.06223)
			(type default)
		)
		(layer "B.Cu")
	)
	(gr_line
		(start 131.503928 -49.339754)
		(end 131.649724 -49.68367)
		(stroke
			(width 0.06223)
			(type default)
		)
		(layer "B.Cu")
	)
	(gr_line
		(start 131.514088 -64.644524)
		(end 131.53644 -64.644524)
		(stroke
			(width 0.04445)
			(type default)
		)
		(layer "B.Cu")
	)
	(gr_line
		(start 131.514342 -64.238124)
		(end 131.53644 -64.238124)
		(stroke
			(width 0.04445)
			(type default)
		)
		(layer "B.Cu")
	)
	(gr_line
		(start 131.521708 -29.881322)
		(end 131.692396 -29.077412)
		(stroke
			(width 0.06223)
			(type default)
		)
		(layer "B.Cu")
	)
	(gr_line
		(start 131.53644 -64.644524)
		(end 131.646422 -64.644524)
		(stroke
			(width 0.06223)
			(type default)
		)
		(layer "B.Cu")
	)
	(gr_line
		(start 131.544314 -63.635128)
		(end 131.566412 -63.635128)
		(stroke
			(width 0.04445)
			(type default)
		)
		(layer "B.Cu")
	)
	(gr_line
		(start 131.544314 -63.228728)
		(end 131.566412 -63.228728)
		(stroke
			(width 0.04445)
			(type default)
		)
		(layer "B.Cu")
	)
	(gr_line
		(start 131.555236 -20.798282)
		(end 131.87172 -21.004022)
		(stroke
			(width 0.06223)
			(type default)
		)
		(layer "B.Cu")
	)
	(gr_line
		(start 131.566412 -63.635128)
		(end 131.667504 -63.635128)
		(stroke
			(width 0.06223)
			(type default)
		)
		(layer "B.Cu")
	)
	(gr_line
		(start 131.602734 -61.370464)
		(end 131.650994 -61.370464)
		(stroke
			(width 0.04445)
			(type default)
		)
		(layer "B.Cu")
	)
	(gr_line
		(start 131.604766 -19.746722)
		(end 131.682236 -20.111974)
		(stroke
			(width 0.06223)
			(type default)
		)
		(layer "B.Cu")
	)
	(gr_line
		(start 131.62915 -70.596506)
		(end 131.66852 -70.635876)
		(stroke
			(width 0.04445)
			(type default)
		)
		(layer "B.Cu")
	)
	(gr_line
		(start 131.62915 -70.406006)
		(end 131.66852 -70.366636)
		(stroke
			(width 0.04445)
			(type default)
		)
		(layer "B.Cu")
	)
	(gr_line
		(start 131.645406 -31.265622)
		(end 131.961636 -31.06039)
		(stroke
			(width 0.06223)
			(type default)
		)
		(layer "B.Cu")
	)
	(gr_line
		(start 131.649724 -49.68367)
		(end 131.999736 -49.824894)
		(stroke
			(width 0.06223)
			(type default)
		)
		(layer "B.Cu")
	)
	(gr_line
		(start 131.653534 -61.370464)
		(end 131.748022 -61.370464)
		(stroke
			(width 0.04445)
			(type default)
		)
		(layer "B.Cu")
	)
	(gr_line
		(start 131.670298 -70.637654)
		(end 131.7371 -70.704456)
		(stroke
			(width 0.04445)
			(type default)
		)
		(layer "B.Cu")
	)
	(gr_line
		(start 131.670298 -70.364858)
		(end 131.7371 -70.298056)
		(stroke
			(width 0.04445)
			(type default)
		)
		(layer "B.Cu")
	)
	(gr_line
		(start 131.678426 -65.750694)
		(end 131.955286 -66.027554)
		(stroke
			(width 0.06223)
			(type default)
		)
		(layer "B.Cu")
	)
	(gr_line
		(start 131.689348 -62.279022)
		(end 131.689348 -62.334648)
		(stroke
			(width 0.04445)
			(type default)
		)
		(layer "B.Cu")
	)
	(gr_line
		(start 131.689348 -62.182248)
		(end 131.689348 -62.276482)
		(stroke
			(width 0.04445)
			(type default)
		)
		(layer "B.Cu")
	)
	(gr_line
		(start 131.689348 -62.182248)
		(end 131.704842 -62.166754)
		(stroke
			(width 0.04445)
			(type default)
		)
		(layer "B.Cu")
	)
	(gr_line
		(start 131.704842 -62.588648)
		(end 131.823968 -62.469522)
		(stroke
			(width 0.04445)
			(type default)
		)
		(layer "B.Cu")
	)
	(gr_line
		(start 131.704842 -62.166754)
		(end 131.823968 -62.047628)
		(stroke
			(width 0.06223)
			(type default)
		)
		(layer "B.Cu")
	)
	(gr_line
		(start 131.710176 -56.44388)
		(end 131.711446 -56.44261)
		(stroke
			(width 0.06223)
			(type default)
		)
		(layer "B.Cu")
	)
	(gr_line
		(start 131.711446 -56.44261)
		(end 131.712462 -56.441086)
		(stroke
			(width 0.06223)
			(type default)
		)
		(layer "B.Cu")
	)
	(gr_line
		(start 131.71932 -57.983882)
		(end 131.760214 -57.92089)
		(stroke
			(width 0.06223)
			(type default)
		)
		(layer "B.Cu")
	)
	(gr_line
		(start 131.7371 -70.704456)
		(end 131.759198 -70.704456)
		(stroke
			(width 0.04445)
			(type default)
		)
		(layer "B.Cu")
	)
	(gr_line
		(start 131.7371 -70.298056)
		(end 131.759198 -70.298056)
		(stroke
			(width 0.04445)
			(type default)
		)
		(layer "B.Cu")
	)
	(gr_line
		(start 131.738878 -41.340786)
		(end 131.747514 -41.299892)
		(stroke
			(width 0.06223)
			(type default)
		)
		(layer "B.Cu")
	)
	(gr_line
		(start 131.738878 -41.259252)
		(end 131.747514 -41.299892)
		(stroke
			(width 0.06223)
			(type default)
		)
		(layer "B.Cu")
	)
	(gr_line
		(start 131.743704 -21.685758)
		(end 131.949444 -21.36902)
		(stroke
			(width 0.06223)
			(type default)
		)
		(layer "B.Cu")
	)
	(gr_line
		(start 131.748022 -61.370464)
		(end 131.763516 -61.35497)
		(stroke
			(width 0.04445)
			(type default)
		)
		(layer "B.Cu")
	)
	(gr_line
		(start 131.763516 -61.35497)
		(end 131.878832 -61.239654)
		(stroke
			(width 0.06223)
			(type default)
		)
		(layer "B.Cu")
	)
	(gr_line
		(start 131.781804 -77.133958)
		(end 131.86283 -77.214984)
		(stroke
			(width 0.06223)
			(type default)
		)
		(layer "B.Cu")
	)
	(gr_line
		(start 131.783582 -76.557378)
		(end 132.17525 -76.557378)
		(stroke
			(width 0.06223)
			(type default)
		)
		(layer "B.Cu")
	)
	(gr_line
		(start 131.788408 -28.6258)
		(end 131.959604 -27.82062)
		(stroke
			(width 0.06223)
			(type default)
		)
		(layer "B.Cu")
	)
	(gr_line
		(start 131.822444 -22.055582)
		(end 132.138928 -22.261068)
		(stroke
			(width 0.06223)
			(type default)
		)
		(layer "B.Cu")
	)
	(gr_line
		(start 131.823968 -62.469522)
		(end 131.879848 -62.469522)
		(stroke
			(width 0.04445)
			(type default)
		)
		(layer "B.Cu")
	)
	(gr_line
		(start 131.833874 -30.3784)
		(end 132.03936 -30.695138)
		(stroke
			(width 0.06223)
			(type default)
		)
		(layer "B.Cu")
	)
	(gr_line
		(start 131.87172 -21.004022)
		(end 131.949444 -21.36902)
		(stroke
			(width 0.06223)
			(type default)
		)
		(layer "B.Cu")
	)
	(gr_line
		(start 131.882388 -62.469522)
		(end 131.976876 -62.469522)
		(stroke
			(width 0.04445)
			(type default)
		)
		(layer "B.Cu")
	)
	(gr_line
		(start 131.912614 -30.008576)
		(end 132.229098 -29.80309)
		(stroke
			(width 0.06223)
			(type default)
		)
		(layer "B.Cu")
	)
	(gr_line
		(start 131.955286 -66.027554)
		(end 132.328666 -66.027554)
		(stroke
			(width 0.06223)
			(type default)
		)
		(layer "B.Cu")
	)
	(gr_line
		(start 131.961636 -31.06039)
		(end 132.03936 -30.695138)
		(stroke
			(width 0.06223)
			(type default)
		)
		(layer "B.Cu")
	)
	(gr_line
		(start 131.976876 -62.469522)
		(end 131.99237 -62.454028)
		(stroke
			(width 0.04445)
			(type default)
		)
		(layer "B.Cu")
	)
	(gr_line
		(start 132.010912 -22.942804)
		(end 132.216398 -22.62632)
		(stroke
			(width 0.06223)
			(type default)
		)
		(layer "B.Cu")
	)
	(gr_line
		(start 132.028946 -52.089304)
		(end 132.045964 -52.11572)
		(stroke
			(width 0.06223)
			(type default)
		)
		(layer "B.Cu")
	)
	(gr_line
		(start 132.037836 -48.868076)
		(end 132.359654 -49.62652)
		(stroke
			(width 0.06223)
			(type default)
		)
		(layer "B.Cu")
	)
	(gr_line
		(start 132.045964 -52.11572)
		(end 132.052568 -52.146454)
		(stroke
			(width 0.06223)
			(type default)
		)
		(layer "B.Cu")
	)
	(gr_line
		(start 132.076952 -79.292196)
		(end 132.157978 -79.373222)
		(stroke
			(width 0.06223)
			(type default)
		)
		(layer "B.Cu")
	)
	(gr_line
		(start 132.077968 -23.351744)
		(end 132.086604 -23.31085)
		(stroke
			(width 0.06223)
			(type default)
		)
		(layer "B.Cu")
	)
	(gr_line
		(start 132.077968 -23.27021)
		(end 132.086604 -23.31085)
		(stroke
			(width 0.06223)
			(type default)
		)
		(layer "B.Cu")
	)
	(gr_line
		(start 132.07873 -78.715616)
		(end 132.470398 -78.715616)
		(stroke
			(width 0.06223)
			(type default)
		)
		(layer "B.Cu")
	)
	(gr_line
		(start 132.084826 -65.341754)
		(end 132.199126 -65.341754)
		(stroke
			(width 0.06223)
			(type default)
		)
		(layer "B.Cu")
	)
	(gr_line
		(start 132.08635 -66.75374)
		(end 132.36321 -67.0306)
		(stroke
			(width 0.06223)
			(type default)
		)
		(layer "B.Cu")
	)
	(gr_line
		(start 132.101082 -29.121354)
		(end 132.306568 -29.437838)
		(stroke
			(width 0.06223)
			(type default)
		)
		(layer "B.Cu")
	)
	(gr_line
		(start 132.104638 -55.82031)
		(end 132.119878 -55.79618)
		(stroke
			(width 0.06223)
			(type default)
		)
		(layer "B.Cu")
	)
	(gr_line
		(start 132.119878 -55.79618)
		(end 132.125466 -55.769002)
		(stroke
			(width 0.06223)
			(type default)
		)
		(layer "B.Cu")
	)
	(gr_line
		(start 132.135118 -70.706996)
		(end 132.411978 -70.983856)
		(stroke
			(width 0.06223)
			(type default)
		)
		(layer "B.Cu")
	)
	(gr_line
		(start 132.138928 -22.261068)
		(end 132.216398 -22.62632)
		(stroke
			(width 0.06223)
			(type default)
		)
		(layer "B.Cu")
	)
	(gr_line
		(start 132.17525 -76.557378)
		(end 132.43941 -76.821538)
		(stroke
			(width 0.06223)
			(type default)
		)
		(layer "B.Cu")
	)
	(gr_line
		(start 132.179822 -28.75153)
		(end 132.496306 -28.546044)
		(stroke
			(width 0.06223)
			(type default)
		)
		(layer "B.Cu")
	)
	(gr_line
		(start 132.225034 -75.691492)
		(end 132.30606 -75.772518)
		(stroke
			(width 0.06223)
			(type default)
		)
		(layer "B.Cu")
	)
	(gr_line
		(start 132.226812 -75.114912)
		(end 132.61848 -75.114912)
		(stroke
			(width 0.06223)
			(type default)
		)
		(layer "B.Cu")
	)
	(gr_line
		(start 132.229098 -29.80309)
		(end 132.306568 -29.437838)
		(stroke
			(width 0.06223)
			(type default)
		)
		(layer "B.Cu")
	)
	(gr_line
		(start 132.278628 -69.476874)
		(end 132.555488 -69.753734)
		(stroke
			(width 0.06223)
			(type default)
		)
		(layer "B.Cu")
	)
	(gr_line
		(start 132.328666 -66.027554)
		(end 132.605526 -65.750694)
		(stroke
			(width 0.06223)
			(type default)
		)
		(layer "B.Cu")
	)
	(gr_line
		(start 132.36321 -67.0306)
		(end 132.73659 -67.0306)
		(stroke
			(width 0.06223)
			(type default)
		)
		(layer "B.Cu")
	)
	(gr_line
		(start 132.36829 -27.864562)
		(end 132.573776 -28.180792)
		(stroke
			(width 0.06223)
			(type default)
		)
		(layer "B.Cu")
	)
	(gr_line
		(start 132.411978 -70.983856)
		(end 132.785358 -70.983856)
		(stroke
			(width 0.06223)
			(type default)
		)
		(layer "B.Cu")
	)
	(gr_line
		(start 132.43941 -76.821538)
		(end 132.43941 -77.213206)
		(stroke
			(width 0.06223)
			(type default)
		)
		(layer "B.Cu")
	)
	(gr_line
		(start 132.465318 -54.169564)
		(end 132.473954 -54.128924)
		(stroke
			(width 0.06223)
			(type default)
		)
		(layer "B.Cu")
	)
	(gr_line
		(start 132.465318 -54.088792)
		(end 132.473954 -54.128924)
		(stroke
			(width 0.06223)
			(type default)
		)
		(layer "B.Cu")
	)
	(gr_line
		(start 132.470398 -78.715616)
		(end 132.734558 -78.979776)
		(stroke
			(width 0.06223)
			(type default)
		)
		(layer "B.Cu")
	)
	(gr_line
		(start 132.475478 -32.716216)
		(end 132.484114 -32.756348)
		(stroke
			(width 0.06223)
			(type default)
		)
		(layer "B.Cu")
	)
	(gr_line
		(start 132.475478 -32.716216)
		(end 132.484114 -32.675576)
		(stroke
			(width 0.06223)
			(type default)
		)
		(layer "B.Cu")
	)
	(gr_line
		(start 132.49275 -66.3448)
		(end 132.60705 -66.3448)
		(stroke
			(width 0.06223)
			(type default)
		)
		(layer "B.Cu")
	)
	(gr_line
		(start 132.496306 -28.546044)
		(end 132.573776 -28.180792)
		(stroke
			(width 0.06223)
			(type default)
		)
		(layer "B.Cu")
	)
	(gr_line
		(start 132.541518 -70.298056)
		(end 132.655818 -70.298056)
		(stroke
			(width 0.06223)
			(type default)
		)
		(layer "B.Cu")
	)
	(gr_line
		(start 132.555488 -69.753734)
		(end 132.928868 -69.753734)
		(stroke
			(width 0.06223)
			(type default)
		)
		(layer "B.Cu")
	)
	(gr_line
		(start 132.571236 -71.736712)
		(end 132.60832 -71.736712)
		(stroke
			(width 0.06223)
			(type default)
		)
		(layer "B.Cu")
	)
	(gr_line
		(start 132.579872 -32.224218)
		(end 132.751322 -31.41726)
		(stroke
			(width 0.06223)
			(type default)
		)
		(layer "B.Cu")
	)
	(gr_line
		(start 132.604002 -58.538618)
		(end 132.64515 -58.475372)
		(stroke
			(width 0.06223)
			(type default)
		)
		(layer "B.Cu")
	)
	(gr_line
		(start 132.61848 -75.114912)
		(end 132.88264 -75.379072)
		(stroke
			(width 0.06223)
			(type default)
		)
		(layer "B.Cu")
	)
	(gr_arc
		(start 132.680964 -4.296918)
		(mid 132.72664 -4.287836)
		(end 132.765292 -4.261866)
		(stroke
			(width 0.06223)
			(type default)
		)
		(layer "B.Cu")
	)
	(gr_line
		(start 132.685028 -69.067934)
		(end 132.799328 -69.067934)
		(stroke
			(width 0.06223)
			(type default)
		)
		(layer "B.Cu")
	)
	(gr_line
		(start 132.734558 -78.979776)
		(end 132.734558 -79.371444)
		(stroke
			(width 0.06223)
			(type default)
		)
		(layer "B.Cu")
	)
	(gr_line
		(start 132.73659 -67.0306)
		(end 133.01345 -66.75374)
		(stroke
			(width 0.06223)
			(type default)
		)
		(layer "B.Cu")
	)
	(gr_arc
		(start 132.765292 -4.261866)
		(mid 132.791017 -4.22328)
		(end 132.80009 -4.177792)
		(stroke
			(width 0.06223)
			(type default)
		)
		(layer "B.Cu")
	)
	(gr_line
		(start 132.77088 -67.990212)
		(end 133.04774 -68.267072)
		(stroke
			(width 0.06223)
			(type default)
		)
		(layer "B.Cu")
	)
	(gr_line
		(start 132.777484 -57.100724)
		(end 132.794502 -57.074308)
		(stroke
			(width 0.06223)
			(type default)
		)
		(layer "B.Cu")
	)
	(gr_line
		(start 132.785358 -70.983856)
		(end 133.062218 -70.706996)
		(stroke
			(width 0.06223)
			(type default)
		)
		(layer "B.Cu")
	)
	(gr_line
		(start 132.794502 -57.074308)
		(end 132.801106 -57.043574)
		(stroke
			(width 0.06223)
			(type default)
		)
		(layer "B.Cu")
	)
	(gr_arc
		(start 132.80009 -4.822444)
		(mid 132.791041 -4.776954)
		(end 132.765292 -4.73837)
		(stroke
			(width 0.06223)
			(type default)
		)
		(layer "B.Cu")
	)
	(gr_line
		(start 132.80009 -4.822444)
		(end 132.80009 -5.200142)
		(stroke
			(width 0.06223)
			(type default)
		)
		(layer "B.Cu")
	)
	(gr_line
		(start 132.80009 -3.800094)
		(end 132.80009 -4.177792)
		(stroke
			(width 0.06223)
			(type default)
		)
		(layer "B.Cu")
	)
	(gr_line
		(start 132.847588 -30.966156)
		(end 133.01853 -30.160976)
		(stroke
			(width 0.06223)
			(type default)
		)
		(layer "B.Cu")
	)
	(gr_line
		(start 132.88264 -75.379072)
		(end 132.88264 -75.77074)
		(stroke
			(width 0.06223)
			(type default)
		)
		(layer "B.Cu")
	)
	(gr_line
		(start 132.928868 -69.753734)
		(end 133.205728 -69.476874)
		(stroke
			(width 0.06223)
			(type default)
		)
		(layer "B.Cu")
	)
	(gr_line
		(start 132.97154 -32.349186)
		(end 133.288024 -32.1437)
		(stroke
			(width 0.06223)
			(type default)
		)
		(layer "B.Cu")
	)
	(gr_line
		(start 132.977636 -71.531226)
		(end 133.01472 -71.531226)
		(stroke
			(width 0.06223)
			(type default)
		)
		(layer "B.Cu")
	)
	(gr_line
		(start 133.04774 -68.267072)
		(end 133.42112 -68.267072)
		(stroke
			(width 0.06223)
			(type default)
		)
		(layer "B.Cu")
	)
	(gr_line
		(start 133.11505 -29.708348)
		(end 133.285738 -28.904438)
		(stroke
			(width 0.06223)
			(type default)
		)
		(layer "B.Cu")
	)
	(gr_line
		(start 133.160262 -31.462218)
		(end 133.365494 -31.778448)
		(stroke
			(width 0.06223)
			(type default)
		)
		(layer "B.Cu")
	)
	(gr_line
		(start 133.17728 -67.581272)
		(end 133.29158 -67.581272)
		(stroke
			(width 0.06223)
			(type default)
		)
		(layer "B.Cu")
	)
	(gr_line
		(start 133.238748 -31.09214)
		(end 133.555232 -30.886654)
		(stroke
			(width 0.06223)
			(type default)
		)
		(layer "B.Cu")
	)
	(gr_line
		(start 133.2738 -45.0723)
		(end 133.280912 -45.079412)
		(stroke
			(width 0.06223)
			(type default)
		)
		(layer "B.Cu")
	)
	(gr_line
		(start 133.2738 -44.6786)
		(end 133.2738 -45.0723)
		(stroke
			(width 0.06223)
			(type default)
		)
		(layer "B.Cu")
	)
	(gr_line
		(start 133.288024 -32.1437)
		(end 133.365494 -31.778448)
		(stroke
			(width 0.06223)
			(type default)
		)
		(layer "B.Cu")
	)
	(gr_line
		(start 133.337808 -50.39868)
		(end 133.346444 -50.43932)
		(stroke
			(width 0.06223)
			(type default)
		)
		(layer "B.Cu")
	)
	(gr_line
		(start 133.337808 -50.39868)
		(end 133.346444 -50.357786)
		(stroke
			(width 0.06223)
			(type default)
		)
		(layer "B.Cu")
	)
	(gr_line
		(start 133.4008 -48.807624)
		(end 133.47827 -48.442372)
		(stroke
			(width 0.06223)
			(type default)
		)
		(layer "B.Cu")
	)
	(gr_line
		(start 133.4008 -48.807624)
		(end 133.606286 -49.124108)
		(stroke
			(width 0.06223)
			(type default)
		)
		(layer "B.Cu")
	)
	(gr_line
		(start 133.42112 -68.267072)
		(end 133.69798 -67.990212)
		(stroke
			(width 0.06223)
			(type default)
		)
		(layer "B.Cu")
	)
	(gr_line
		(start 133.42747 -30.205172)
		(end 133.632702 -30.521402)
		(stroke
			(width 0.06223)
			(type default)
		)
		(layer "B.Cu")
	)
	(gr_line
		(start 133.430772 -54.082442)
		(end 133.439408 -54.04231)
		(stroke
			(width 0.06223)
			(type default)
		)
		(layer "B.Cu")
	)
	(gr_line
		(start 133.430772 -54.002178)
		(end 133.439408 -54.04231)
		(stroke
			(width 0.06223)
			(type default)
		)
		(layer "B.Cu")
	)
	(gr_line
		(start 133.43636 -71.940166)
		(end 133.71322 -72.217026)
		(stroke
			(width 0.06223)
			(type default)
		)
		(layer "B.Cu")
	)
	(gr_line
		(start 133.46811 -22.679152)
		(end 133.476746 -22.63902)
		(stroke
			(width 0.06223)
			(type default)
		)
		(layer "B.Cu")
	)
	(gr_line
		(start 133.46811 -22.59838)
		(end 133.476746 -22.63902)
		(stroke
			(width 0.06223)
			(type default)
		)
		(layer "B.Cu")
	)
	(gr_line
		(start 133.469888 -63.263272)
		(end 133.736588 -62.996572)
		(stroke
			(width 0.06223)
			(type default)
		)
		(layer "B.Cu")
	)
	(gr_line
		(start 133.47827 -48.442372)
		(end 133.794754 -48.236886)
		(stroke
			(width 0.06223)
			(type default)
		)
		(layer "B.Cu")
	)
	(gr_line
		(start 133.505956 -29.835094)
		(end 133.82244 -29.629608)
		(stroke
			(width 0.06223)
			(type default)
		)
		(layer "B.Cu")
	)
	(gr_line
		(start 133.509258 -60.659772)
		(end 133.775958 -60.926472)
		(stroke
			(width 0.06223)
			(type default)
		)
		(layer "B.Cu")
	)
	(gr_line
		(start 133.509258 -60.286392)
		(end 133.509258 -60.659772)
		(stroke
			(width 0.06223)
			(type default)
		)
		(layer "B.Cu")
	)
	(gr_line
		(start 133.509258 -60.286392)
		(end 133.775958 -60.019692)
		(stroke
			(width 0.06223)
			(type default)
		)
		(layer "B.Cu")
	)
	(gr_line
		(start 133.555232 -30.886654)
		(end 133.632702 -30.521402)
		(stroke
			(width 0.06223)
			(type default)
		)
		(layer "B.Cu")
	)
	(gr_line
		(start 133.582664 -73.47966)
		(end 133.859524 -73.75652)
		(stroke
			(width 0.06223)
			(type default)
		)
		(layer "B.Cu")
	)
	(gr_line
		(start 133.590284 -57.767982)
		(end 133.60781 -57.741058)
		(stroke
			(width 0.06223)
			(type default)
		)
		(layer "B.Cu")
	)
	(gr_line
		(start 133.60781 -57.741058)
		(end 133.61416 -57.710324)
		(stroke
			(width 0.06223)
			(type default)
		)
		(layer "B.Cu")
	)
	(gr_line
		(start 133.694678 -28.947872)
		(end 133.89991 -29.264356)
		(stroke
			(width 0.06223)
			(type default)
		)
		(layer "B.Cu")
	)
	(gr_line
		(start 133.71322 -72.217026)
		(end 134.0866 -72.217026)
		(stroke
			(width 0.06223)
			(type default)
		)
		(layer "B.Cu")
	)
	(gr_line
		(start 133.736588 -62.996572)
		(end 134.109968 -62.996572)
		(stroke
			(width 0.06223)
			(type default)
		)
		(layer "B.Cu")
	)
	(gr_line
		(start 133.82244 -29.629608)
		(end 133.89991 -29.264356)
		(stroke
			(width 0.06223)
			(type default)
		)
		(layer "B.Cu")
	)
	(gr_line
		(start 133.8326 -44.6786)
		(end 133.8326 -45.105828)
		(stroke
			(width 0.06223)
			(type default)
		)
		(layer "B.Cu")
	)
	(gr_line
		(start 133.84276 -71.531226)
		(end 133.95706 -71.531226)
		(stroke
			(width 0.06223)
			(type default)
		)
		(layer "B.Cu")
	)
	(gr_line
		(start 133.859524 -73.75652)
		(end 134.232904 -73.75652)
		(stroke
			(width 0.06223)
			(type default)
		)
		(layer "B.Cu")
	)
	(gr_line
		(start 133.876288 -63.672212)
		(end 133.970268 -63.672212)
		(stroke
			(width 0.06223)
			(type default)
		)
		(layer "B.Cu")
	)
	(gr_line
		(start 133.91515 -33.458658)
		(end 133.923786 -33.49879)
		(stroke
			(width 0.06223)
			(type default)
		)
		(layer "B.Cu")
	)
	(gr_line
		(start 133.91515 -33.458658)
		(end 133.923786 -33.418018)
		(stroke
			(width 0.06223)
			(type default)
		)
		(layer "B.Cu")
	)
	(gr_line
		(start 133.989064 -73.07072)
		(end 134.103364 -73.07072)
		(stroke
			(width 0.06223)
			(type default)
		)
		(layer "B.Cu")
	)
	(gr_line
		(start 134.014972 -49.168558)
		(end 134.186422 -48.3616)
		(stroke
			(width 0.06223)
			(type default)
		)
		(layer "B.Cu")
	)
	(gr_line
		(start 134.0866 -72.217026)
		(end 134.36346 -71.940166)
		(stroke
			(width 0.06223)
			(type default)
		)
		(layer "B.Cu")
	)
	(gr_line
		(start 134.109968 -62.996572)
		(end 134.376668 -63.263272)
		(stroke
			(width 0.06223)
			(type default)
		)
		(layer "B.Cu")
	)
	(gr_line
		(start 134.184898 -60.426092)
		(end 134.184898 -60.520072)
		(stroke
			(width 0.06223)
			(type default)
		)
		(layer "B.Cu")
	)
	(gr_line
		(start 134.232904 -73.75652)
		(end 134.509764 -73.47966)
		(stroke
			(width 0.06223)
			(type default)
		)
		(layer "B.Cu")
	)
	(gr_line
		(start 134.25932 -47.93742)
		(end 134.267956 -47.97806)
		(stroke
			(width 0.06223)
			(type default)
		)
		(layer "B.Cu")
	)
	(gr_line
		(start 134.45236 -53.767736)
		(end 134.460996 -53.727604)
		(stroke
			(width 0.06223)
			(type default)
		)
		(layer "B.Cu")
	)
	(gr_line
		(start 134.45236 -53.686964)
		(end 134.460996 -53.727604)
		(stroke
			(width 0.06223)
			(type default)
		)
		(layer "B.Cu")
	)
	(gr_arc
		(start 134.481062 -3.096768)
		(mid 134.526718 -3.087651)
		(end 134.56539 -3.061716)
		(stroke
			(width 0.06223)
			(type default)
		)
		(layer "B.Cu")
	)
	(gr_arc
		(start 134.56539 -3.53822)
		(mid 134.526723 -3.512274)
		(end 134.481062 -3.503168)
		(stroke
			(width 0.06223)
			(type default)
		)
		(layer "B.Cu")
	)
	(gr_arc
		(start 134.56539 -3.061716)
		(mid 134.591164 -3.023143)
		(end 134.600188 -2.977642)
		(stroke
			(width 0.06223)
			(type default)
		)
		(layer "B.Cu")
	)
	(gr_arc
		(start 134.600188 -3.622294)
		(mid 134.591159 -3.576794)
		(end 134.56539 -3.53822)
		(stroke
			(width 0.06223)
			(type default)
		)
		(layer "B.Cu")
	)
	(gr_line
		(start 134.600188 -3.622294)
		(end 134.600188 -3.999992)
		(stroke
			(width 0.06223)
			(type default)
		)
		(layer "B.Cu")
	)
	(gr_line
		(start 134.600188 -2.600198)
		(end 134.600188 -2.977642)
		(stroke
			(width 0.06223)
			(type default)
		)
		(layer "B.Cu")
	)
	(gr_line
		(start 134.649464 -50.232818)
		(end 134.6581 -50.27295)
		(stroke
			(width 0.06223)
			(type default)
		)
		(layer "B.Cu")
	)
	(gr_line
		(start 134.649464 -50.232818)
		(end 134.6581 -50.192178)
		(stroke
			(width 0.06223)
			(type default)
		)
		(layer "B.Cu")
	)
	(gr_line
		(start 134.772654 -65.066418)
		(end 135.009382 -65.066418)
		(stroke
			(width 0.06223)
			(type default)
		)
		(layer "B.Cu")
	)
	(gr_line
		(start 134.772654 -64.507618)
		(end 134.992618 -64.507618)
		(stroke
			(width 0.06223)
			(type default)
		)
		(layer "B.Cu")
	)
	(gr_line
		(start 134.846822 -56.762142)
		(end 134.996682 -56.912002)
		(stroke
			(width 0.06223)
			(type default)
		)
		(layer "B.Cu")
	)
	(gr_line
		(start 134.846822 -56.659018)
		(end 134.846822 -56.762142)
		(stroke
			(width 0.06223)
			(type default)
		)
		(layer "B.Cu")
	)
	(gr_line
		(start 134.846822 -56.100218)
		(end 134.996682 -55.950358)
		(stroke
			(width 0.06223)
			(type default)
		)
		(layer "B.Cu")
	)
	(gr_line
		(start 135.022082 -61.584078)
		(end 135.171942 -61.733938)
		(stroke
			(width 0.06223)
			(type default)
		)
		(layer "B.Cu")
	)
	(gr_line
		(start 135.148574 -22.09546)
		(end 135.15721 -22.054566)
		(stroke
			(width 0.06223)
			(type default)
		)
		(layer "B.Cu")
	)
	(gr_line
		(start 135.148574 -22.013926)
		(end 135.15721 -22.054566)
		(stroke
			(width 0.06223)
			(type default)
		)
		(layer "B.Cu")
	)
	(gr_line
		(start 135.22198 -33.360106)
		(end 135.230616 -33.401)
		(stroke
			(width 0.06223)
			(type default)
		)
		(layer "B.Cu")
	)
	(gr_line
		(start 135.22198 -33.360106)
		(end 135.230616 -33.319466)
		(stroke
			(width 0.06223)
			(type default)
		)
		(layer "B.Cu")
	)
	(gr_line
		(start 135.511032 -76.1492)
		(end 135.89 -76.1492)
		(stroke
			(width 0.06223)
			(type default)
		)
		(layer "B.Cu")
	)
	(gr_line
		(start 135.511032 -75.5904)
		(end 135.89 -75.5904)
		(stroke
			(width 0.06223)
			(type default)
		)
		(layer "B.Cu")
	)
	(gr_line
		(start 135.536432 -78.0542)
		(end 135.9154 -78.0542)
		(stroke
			(width 0.06223)
			(type default)
		)
		(layer "B.Cu")
	)
	(gr_line
		(start 135.536432 -77.4954)
		(end 135.9154 -77.4954)
		(stroke
			(width 0.06223)
			(type default)
		)
		(layer "B.Cu")
	)
	(gr_line
		(start 135.561832 -79.6036)
		(end 135.9408 -79.6036)
		(stroke
			(width 0.06223)
			(type default)
		)
		(layer "B.Cu")
	)
	(gr_line
		(start 135.561832 -79.0448)
		(end 135.9408 -79.0448)
		(stroke
			(width 0.06223)
			(type default)
		)
		(layer "B.Cu")
	)
	(gr_line
		(start 135.587232 -81.1276)
		(end 135.9662 -81.1276)
		(stroke
			(width 0.06223)
			(type default)
		)
		(layer "B.Cu")
	)
	(gr_line
		(start 135.587232 -80.5688)
		(end 135.9662 -80.5688)
		(stroke
			(width 0.06223)
			(type default)
		)
		(layer "B.Cu")
	)
	(gr_line
		(start 135.621776 -64.994536)
		(end 135.70966 -64.906652)
		(stroke
			(width 0.06223)
			(type default)
		)
		(layer "B.Cu")
	)
	(gr_line
		(start 135.831326 -46.628304)
		(end 135.839962 -46.588172)
		(stroke
			(width 0.06223)
			(type default)
		)
		(layer "B.Cu")
	)
	(gr_line
		(start 135.831326 -46.547532)
		(end 135.839962 -46.588172)
		(stroke
			(width 0.06223)
			(type default)
		)
		(layer "B.Cu")
	)
	(gr_line
		(start 135.904224 -50.230278)
		(end 135.91286 -50.271172)
		(stroke
			(width 0.06223)
			(type default)
		)
		(layer "B.Cu")
	)
	(gr_line
		(start 135.904224 -50.230278)
		(end 135.91286 -50.189638)
		(stroke
			(width 0.06223)
			(type default)
		)
		(layer "B.Cu")
	)
	(gr_line
		(start 135.997442 -50.669698)
		(end 136.169146 -51.478688)
		(stroke
			(width 0.06223)
			(type default)
		)
		(layer "B.Cu")
	)
	(gr_line
		(start 136.263888 -51.925474)
		(end 136.436354 -52.73675)
		(stroke
			(width 0.06223)
			(type default)
		)
		(layer "B.Cu")
	)
	(gr_arc
		(start 136.280906 -4.296918)
		(mid 136.326562 -4.287801)
		(end 136.365234 -4.261866)
		(stroke
			(width 0.06223)
			(type default)
		)
		(layer "B.Cu")
	)
	(gr_arc
		(start 136.365234 -4.73837)
		(mid 136.326561 -4.712453)
		(end 136.280906 -4.703318)
		(stroke
			(width 0.06223)
			(type default)
		)
		(layer "B.Cu")
	)
	(gr_arc
		(start 136.365234 -4.261866)
		(mid 136.391008 -4.223293)
		(end 136.400032 -4.177792)
		(stroke
			(width 0.06223)
			(type default)
		)
		(layer "B.Cu")
	)
	(gr_line
		(start 136.38911 -50.54473)
		(end 136.705594 -50.75047)
		(stroke
			(width 0.06223)
			(type default)
		)
		(layer "B.Cu")
	)
	(gr_arc
		(start 136.400032 -4.822444)
		(mid 136.391022 -4.776931)
		(end 136.365234 -4.73837)
		(stroke
			(width 0.06223)
			(type default)
		)
		(layer "B.Cu")
	)
	(gr_line
		(start 136.400032 -4.822444)
		(end 136.400032 -5.200142)
		(stroke
			(width 0.06223)
			(type default)
		)
		(layer "B.Cu")
	)
	(gr_line
		(start 136.400032 -3.800094)
		(end 136.400032 -4.177792)
		(stroke
			(width 0.06223)
			(type default)
		)
		(layer "B.Cu")
	)
	(gr_line
		(start 136.4488 -76.1492)
		(end 136.827768 -76.1492)
		(stroke
			(width 0.06223)
			(type default)
		)
		(layer "B.Cu")
	)
	(gr_line
		(start 136.4488 -75.5904)
		(end 136.827768 -75.5904)
		(stroke
			(width 0.06223)
			(type default)
		)
		(layer "B.Cu")
	)
	(gr_line
		(start 136.4742 -78.0542)
		(end 136.853168 -78.0542)
		(stroke
			(width 0.06223)
			(type default)
		)
		(layer "B.Cu")
	)
	(gr_line
		(start 136.4742 -77.4954)
		(end 136.853168 -77.4954)
		(stroke
			(width 0.06223)
			(type default)
		)
		(layer "B.Cu")
	)
	(gr_line
		(start 136.4996 -79.6036)
		(end 136.878568 -79.6036)
		(stroke
			(width 0.06223)
			(type default)
		)
		(layer "B.Cu")
	)
	(gr_line
		(start 136.4996 -79.0448)
		(end 136.878568 -79.0448)
		(stroke
			(width 0.06223)
			(type default)
		)
		(layer "B.Cu")
	)
	(gr_line
		(start 136.516364 -58.807096)
		(end 136.532366 -58.732166)
		(stroke
			(width 0.06223)
			(type default)
		)
		(layer "B.Cu")
	)
	(gr_line
		(start 136.525 -81.1276)
		(end 136.903968 -81.1276)
		(stroke
			(width 0.06223)
			(type default)
		)
		(layer "B.Cu")
	)
	(gr_line
		(start 136.525 -80.5688)
		(end 136.903968 -80.5688)
		(stroke
			(width 0.06223)
			(type default)
		)
		(layer "B.Cu")
	)
	(gr_line
		(start 136.53135 -53.18379)
		(end 136.703054 -53.99278)
		(stroke
			(width 0.06223)
			(type default)
		)
		(layer "B.Cu")
	)
	(gr_line
		(start 136.577578 -51.43246)
		(end 136.783064 -51.115722)
		(stroke
			(width 0.06223)
			(type default)
		)
		(layer "B.Cu")
	)
	(gr_line
		(start 136.609328 -32.936434)
		(end 136.617964 -32.977328)
		(stroke
			(width 0.06223)
			(type default)
		)
		(layer "B.Cu")
	)
	(gr_line
		(start 136.609328 -32.936434)
		(end 136.617964 -32.895794)
		(stroke
			(width 0.06223)
			(type default)
		)
		(layer "B.Cu")
	)
	(gr_line
		(start 136.656064 -51.80203)
		(end 136.972548 -52.00777)
		(stroke
			(width 0.06223)
			(type default)
		)
		(layer "B.Cu")
	)
	(gr_line
		(start 136.705594 -50.75047)
		(end 136.783064 -51.115722)
		(stroke
			(width 0.06223)
			(type default)
		)
		(layer "B.Cu")
	)
	(gr_line
		(start 136.73836 -22.131528)
		(end 136.746996 -22.091396)
		(stroke
			(width 0.06223)
			(type default)
		)
		(layer "B.Cu")
	)
	(gr_line
		(start 136.73836 -22.050756)
		(end 136.746996 -22.091396)
		(stroke
			(width 0.06223)
			(type default)
		)
		(layer "B.Cu")
	)
	(gr_line
		(start 136.747758 -63.540132)
		(end 136.764776 -63.51397)
		(stroke
			(width 0.06223)
			(type default)
		)
		(layer "B.Cu")
	)
	(gr_line
		(start 136.755632 -74.5998)
		(end 137.1346 -74.5998)
		(stroke
			(width 0.06223)
			(type default)
		)
		(layer "B.Cu")
	)
	(gr_line
		(start 136.755632 -74.041)
		(end 137.1346 -74.041)
		(stroke
			(width 0.06223)
			(type default)
		)
		(layer "B.Cu")
	)
	(gr_line
		(start 136.764776 -63.51397)
		(end 136.77138 -63.483236)
		(stroke
			(width 0.06223)
			(type default)
		)
		(layer "B.Cu")
	)
	(gr_line
		(start 136.806432 -72.9996)
		(end 137.1854 -72.9996)
		(stroke
			(width 0.06223)
			(type default)
		)
		(layer "B.Cu")
	)
	(gr_line
		(start 136.806432 -72.4408)
		(end 137.1854 -72.4408)
		(stroke
			(width 0.06223)
			(type default)
		)
		(layer "B.Cu")
	)
	(gr_line
		(start 136.806432 -70.8914)
		(end 137.1854 -70.8914)
		(stroke
			(width 0.06223)
			(type default)
		)
		(layer "B.Cu")
	)
	(gr_line
		(start 136.806432 -69.9008)
		(end 137.1854 -69.9008)
		(stroke
			(width 0.06223)
			(type default)
		)
		(layer "B.Cu")
	)
	(gr_line
		(start 136.806432 -69.342)
		(end 137.1854 -69.342)
		(stroke
			(width 0.06223)
			(type default)
		)
		(layer "B.Cu")
	)
	(gr_line
		(start 136.806432 -67.7926)
		(end 137.1854 -67.7926)
		(stroke
			(width 0.06223)
			(type default)
		)
		(layer "B.Cu")
	)
	(gr_line
		(start 136.831832 -66.8274)
		(end 137.1854 -66.8274)
		(stroke
			(width 0.06223)
			(type default)
		)
		(layer "B.Cu")
	)
	(gr_line
		(start 136.831832 -66.2686)
		(end 137.1854 -66.2686)
		(stroke
			(width 0.06223)
			(type default)
		)
		(layer "B.Cu")
	)
	(gr_line
		(start 136.838436 -71.437754)
		(end 136.850882 -71.4502)
		(stroke
			(width 0.06223)
			(type default)
		)
		(layer "B.Cu")
	)
	(gr_line
		(start 136.844532 -52.68976)
		(end 137.050018 -52.373022)
		(stroke
			(width 0.06223)
			(type default)
		)
		(layer "B.Cu")
	)
	(gr_line
		(start 136.850882 -71.4502)
		(end 137.1854 -71.4502)
		(stroke
			(width 0.06223)
			(type default)
		)
		(layer "B.Cu")
	)
	(gr_line
		(start 136.872726 -68.30441)
		(end 136.919716 -68.3514)
		(stroke
			(width 0.06223)
			(type default)
		)
		(layer "B.Cu")
	)
	(gr_line
		(start 136.919716 -68.3514)
		(end 137.1854 -68.3514)
		(stroke
			(width 0.06223)
			(type default)
		)
		(layer "B.Cu")
	)
	(gr_line
		(start 136.922764 -53.05933)
		(end 137.239502 -53.26507)
		(stroke
			(width 0.06223)
			(type default)
		)
		(layer "B.Cu")
	)
	(gr_line
		(start 136.972548 -52.00777)
		(end 137.050018 -52.373022)
		(stroke
			(width 0.06223)
			(type default)
		)
		(layer "B.Cu")
	)
	(gr_line
		(start 137.09904 -46.56328)
		(end 137.107676 -46.522386)
		(stroke
			(width 0.06223)
			(type default)
		)
		(layer "B.Cu")
	)
	(gr_line
		(start 137.09904 -46.481746)
		(end 137.107676 -46.522386)
		(stroke
			(width 0.06223)
			(type default)
		)
		(layer "B.Cu")
	)
	(gr_line
		(start 137.111232 -53.94706)
		(end 137.316972 -53.630322)
		(stroke
			(width 0.06223)
			(type default)
		)
		(layer "B.Cu")
	)
	(gr_line
		(start 137.239502 -53.26507)
		(end 137.316972 -53.630322)
		(stroke
			(width 0.06223)
			(type default)
		)
		(layer "B.Cu")
	)
	(gr_line
		(start 137.314432 -49.456594)
		(end 137.323068 -49.496726)
		(stroke
			(width 0.06223)
			(type default)
		)
		(layer "B.Cu")
	)
	(gr_line
		(start 137.314432 -49.456594)
		(end 137.323068 -49.415954)
		(stroke
			(width 0.06223)
			(type default)
		)
		(layer "B.Cu")
	)
	(gr_line
		(start 137.320782 -55.02656)
		(end 137.329418 -54.986174)
		(stroke
			(width 0.06223)
			(type default)
		)
		(layer "B.Cu")
	)
	(gr_line
		(start 137.320782 -54.94528)
		(end 137.329418 -54.986174)
		(stroke
			(width 0.06223)
			(type default)
		)
		(layer "B.Cu")
	)
	(gr_line
		(start 137.6934 -74.5998)
		(end 138.072368 -74.5998)
		(stroke
			(width 0.06223)
			(type default)
		)
		(layer "B.Cu")
	)
	(gr_line
		(start 137.6934 -74.041)
		(end 138.072368 -74.041)
		(stroke
			(width 0.06223)
			(type default)
		)
		(layer "B.Cu")
	)
	(gr_line
		(start 137.7442 -72.9996)
		(end 138.123168 -72.9996)
		(stroke
			(width 0.06223)
			(type default)
		)
		(layer "B.Cu")
	)
	(gr_line
		(start 137.7442 -72.4408)
		(end 138.123168 -72.4408)
		(stroke
			(width 0.06223)
			(type default)
		)
		(layer "B.Cu")
	)
	(gr_line
		(start 137.7442 -71.4502)
		(end 138.123168 -71.4502)
		(stroke
			(width 0.06223)
			(type default)
		)
		(layer "B.Cu")
	)
	(gr_line
		(start 137.7442 -70.8914)
		(end 138.123168 -70.8914)
		(stroke
			(width 0.06223)
			(type default)
		)
		(layer "B.Cu")
	)
	(gr_line
		(start 137.7442 -69.9008)
		(end 138.123168 -69.9008)
		(stroke
			(width 0.06223)
			(type default)
		)
		(layer "B.Cu")
	)
	(gr_line
		(start 137.7442 -69.342)
		(end 138.123168 -69.342)
		(stroke
			(width 0.06223)
			(type default)
		)
		(layer "B.Cu")
	)
	(gr_line
		(start 137.7442 -68.3514)
		(end 138.123168 -68.3514)
		(stroke
			(width 0.06223)
			(type default)
		)
		(layer "B.Cu")
	)
	(gr_line
		(start 137.7442 -67.7926)
		(end 138.123168 -67.7926)
		(stroke
			(width 0.06223)
			(type default)
		)
		(layer "B.Cu")
	)
	(gr_line
		(start 137.7442 -66.8274)
		(end 138.123168 -66.8274)
		(stroke
			(width 0.06223)
			(type default)
		)
		(layer "B.Cu")
	)
	(gr_line
		(start 137.7442 -66.2686)
		(end 138.123168 -66.2686)
		(stroke
			(width 0.06223)
			(type default)
		)
		(layer "B.Cu")
	)
	(gr_line
		(start 137.91692 -32.822134)
		(end 137.925556 -32.862266)
		(stroke
			(width 0.06223)
			(type default)
		)
		(layer "B.Cu")
	)
	(gr_line
		(start 137.91692 -32.822134)
		(end 137.925556 -32.781494)
		(stroke
			(width 0.06223)
			(type default)
		)
		(layer "B.Cu")
	)
	(gr_arc
		(start 138.081004 -3.096768)
		(mid 138.12666 -3.087651)
		(end 138.165332 -3.061716)
		(stroke
			(width 0.06223)
			(type default)
		)
		(layer "B.Cu")
	)
	(gr_arc
		(start 138.165332 -3.53822)
		(mid 138.126662 -3.512293)
		(end 138.081004 -3.503168)
		(stroke
			(width 0.06223)
			(type default)
		)
		(layer "B.Cu")
	)
	(gr_arc
		(start 138.165332 -3.061716)
		(mid 138.191106 -3.023143)
		(end 138.20013 -2.977642)
		(stroke
			(width 0.06223)
			(type default)
		)
		(layer "B.Cu")
	)
	(gr_arc
		(start 138.20013 -3.622294)
		(mid 138.191104 -3.576792)
		(end 138.165332 -3.53822)
		(stroke
			(width 0.06223)
			(type default)
		)
		(layer "B.Cu")
	)
	(gr_line
		(start 138.20013 -3.622294)
		(end 138.20013 -3.999992)
		(stroke
			(width 0.06223)
			(type default)
		)
		(layer "B.Cu")
	)
	(gr_line
		(start 138.20013 -2.600198)
		(end 138.20013 -2.977642)
		(stroke
			(width 0.06223)
			(type default)
		)
		(layer "B.Cu")
	)
	(gr_line
		(start 138.385804 -46.372018)
		(end 138.39444 -46.331886)
		(stroke
			(width 0.06223)
			(type default)
		)
		(layer "B.Cu")
	)
	(gr_line
		(start 138.385804 -46.291246)
		(end 138.39444 -46.331886)
		(stroke
			(width 0.06223)
			(type default)
		)
		(layer "B.Cu")
	)
	(gr_line
		(start 138.387836 -20.421346)
		(end 138.396472 -20.381214)
		(stroke
			(width 0.06223)
			(type default)
		)
		(layer "B.Cu")
	)
	(gr_line
		(start 138.387836 -20.340574)
		(end 138.396472 -20.381214)
		(stroke
			(width 0.06223)
			(type default)
		)
		(layer "B.Cu")
	)
	(gr_line
		(start 138.571478 -49.466754)
		(end 138.580114 -49.507648)
		(stroke
			(width 0.06223)
			(type default)
		)
		(layer "B.Cu")
	)
	(gr_line
		(start 138.571478 -49.466754)
		(end 138.580114 -49.426114)
		(stroke
			(width 0.06223)
			(type default)
		)
		(layer "B.Cu")
	)
	(gr_line
		(start 138.732514 -54.25313)
		(end 138.74115 -54.212236)
		(stroke
			(width 0.06223)
			(type default)
		)
		(layer "B.Cu")
	)
	(gr_line
		(start 138.732514 -54.171596)
		(end 138.74115 -54.212236)
		(stroke
			(width 0.06223)
			(type default)
		)
		(layer "B.Cu")
	)
	(gr_line
		(start 139.24407 -32.67583)
		(end 139.252706 -32.716724)
		(stroke
			(width 0.06223)
			(type default)
		)
		(layer "B.Cu")
	)
	(gr_line
		(start 139.24407 -32.67583)
		(end 139.252706 -32.63519)
		(stroke
			(width 0.06223)
			(type default)
		)
		(layer "B.Cu")
	)
	(gr_line
		(start 139.406122 -66.726308)
		(end 139.406884 -66.726054)
		(stroke
			(width 0.06223)
			(type default)
		)
		(layer "B.Cu")
	)
	(gr_line
		(start 139.635484 -54.475126)
		(end 139.642088 -54.50586)
		(stroke
			(width 0.06223)
			(type default)
		)
		(layer "B.Cu")
	)
	(gr_line
		(start 139.642088 -54.50586)
		(end 139.659106 -54.532276)
		(stroke
			(width 0.06223)
			(type default)
		)
		(layer "B.Cu")
	)
	(gr_line
		(start 139.754102 -45.857922)
		(end 139.762738 -45.81779)
		(stroke
			(width 0.06223)
			(type default)
		)
		(layer "B.Cu")
	)
	(gr_line
		(start 139.754102 -45.77715)
		(end 139.762738 -45.81779)
		(stroke
			(width 0.06223)
			(type default)
		)
		(layer "B.Cu")
	)
	(gr_arc
		(start 139.880848 -4.296918)
		(mid 139.926504 -4.287801)
		(end 139.965176 -4.261866)
		(stroke
			(width 0.06223)
			(type default)
		)
		(layer "B.Cu")
	)
	(gr_arc
		(start 139.965176 -4.73837)
		(mid 139.926506 -4.712439)
		(end 139.880848 -4.703318)
		(stroke
			(width 0.06223)
			(type default)
		)
		(layer "B.Cu")
	)
	(gr_arc
		(start 139.965176 -4.261866)
		(mid 139.99095 -4.223293)
		(end 139.999974 -4.177792)
		(stroke
			(width 0.06223)
			(type default)
		)
		(layer "B.Cu")
	)
	(gr_line
		(start 139.978384 -19.038824)
		(end 139.98702 -18.99793)
		(stroke
			(width 0.06223)
			(type default)
		)
		(layer "B.Cu")
	)
	(gr_line
		(start 139.978384 -18.95729)
		(end 139.98702 -18.99793)
		(stroke
			(width 0.06223)
			(type default)
		)
		(layer "B.Cu")
	)
	(gr_line
		(start 139.983718 -48.782732)
		(end 139.992354 -48.822864)
		(stroke
			(width 0.06223)
			(type default)
		)
		(layer "B.Cu")
	)
	(gr_line
		(start 139.983718 -48.782732)
		(end 139.992354 -48.742092)
		(stroke
			(width 0.06223)
			(type default)
		)
		(layer "B.Cu")
	)
	(gr_arc
		(start 139.999974 -4.822444)
		(mid 139.990961 -4.776934)
		(end 139.965176 -4.73837)
		(stroke
			(width 0.06223)
			(type default)
		)
		(layer "B.Cu")
	)
	(gr_line
		(start 139.999974 -4.822444)
		(end 139.999974 -5.200142)
		(stroke
			(width 0.06223)
			(type default)
		)
		(layer "B.Cu")
	)
	(gr_line
		(start 139.999974 -3.800094)
		(end 139.999974 -4.177792)
		(stroke
			(width 0.06223)
			(type default)
		)
		(layer "B.Cu")
	)
	(gr_line
		(start 140.568934 -32.673544)
		(end 140.57757 -32.714438)
		(stroke
			(width 0.06223)
			(type default)
		)
		(layer "B.Cu")
	)
	(gr_line
		(start 140.568934 -32.673544)
		(end 140.57757 -32.632904)
		(stroke
			(width 0.06223)
			(type default)
		)
		(layer "B.Cu")
	)
	(gr_line
		(start 140.660628 -95.001588)
		(end 140.695426 -94.978982)
		(stroke
			(width 0.06223)
			(type default)
		)
		(layer "B.Cu")
	)
	(gr_line
		(start 140.695426 -94.978982)
		(end 140.718032 -94.944184)
		(stroke
			(width 0.06223)
			(type default)
		)
		(layer "B.Cu")
	)
	(gr_line
		(start 140.695934 -15.269464)
		(end 140.695934 -15.269718)
		(stroke
			(width 0.06223)
			(type default)
		)
		(layer "B.Cu")
	)
	(gr_line
		(start 140.805662 -67.925696)
		(end 140.836396 -67.919092)
		(stroke
			(width 0.06223)
			(type default)
		)
		(layer "B.Cu")
	)
	(gr_line
		(start 140.831824 -66.397378)
		(end 140.857986 -66.391282)
		(stroke
			(width 0.06223)
			(type default)
		)
		(layer "B.Cu")
	)
	(gr_line
		(start 140.836396 -67.919092)
		(end 140.862812 -67.902074)
		(stroke
			(width 0.06223)
			(type default)
		)
		(layer "B.Cu")
	)
	(gr_line
		(start 140.857986 -66.391282)
		(end 140.880084 -66.376804)
		(stroke
			(width 0.06223)
			(type default)
		)
		(layer "B.Cu")
	)
	(gr_line
		(start 140.96619 -80.815942)
		(end 140.996924 -80.822546)
		(stroke
			(width 0.06223)
			(type default)
		)
		(layer "B.Cu")
	)
	(gr_line
		(start 140.996924 -80.822546)
		(end 141.023086 -80.839564)
		(stroke
			(width 0.06223)
			(type default)
		)
		(layer "B.Cu")
	)
	(gr_line
		(start 141.053566 -45.70476)
		(end 141.062202 -45.664628)
		(stroke
			(width 0.06223)
			(type default)
		)
		(layer "B.Cu")
	)
	(gr_line
		(start 141.053566 -45.623988)
		(end 141.062202 -45.664628)
		(stroke
			(width 0.06223)
			(type default)
		)
		(layer "B.Cu")
	)
	(gr_line
		(start 141.118844 -69.386196)
		(end 141.149578 -69.379592)
		(stroke
			(width 0.06223)
			(type default)
		)
		(layer "B.Cu")
	)
	(gr_line
		(start 141.149578 -69.379592)
		(end 141.17574 -69.362574)
		(stroke
			(width 0.06223)
			(type default)
		)
		(layer "B.Cu")
	)
	(gr_line
		(start 141.19987 -72.567546)
		(end 141.230604 -72.560942)
		(stroke
			(width 0.06223)
			(type default)
		)
		(layer "B.Cu")
	)
	(gr_line
		(start 141.214856 -54.57444)
		(end 141.22146 -54.605174)
		(stroke
			(width 0.06223)
			(type default)
		)
		(layer "B.Cu")
	)
	(gr_line
		(start 141.22146 -54.605174)
		(end 141.238478 -54.63159)
		(stroke
			(width 0.06223)
			(type default)
		)
		(layer "B.Cu")
	)
	(gr_line
		(start 141.230604 -72.560942)
		(end 141.25702 -72.543924)
		(stroke
			(width 0.06223)
			(type default)
		)
		(layer "B.Cu")
	)
	(gr_line
		(start 141.303502 -96.302576)
		(end 141.3383 -96.27997)
		(stroke
			(width 0.06223)
			(type default)
		)
		(layer "B.Cu")
	)
	(gr_line
		(start 141.3383 -96.27997)
		(end 141.360906 -96.245172)
		(stroke
			(width 0.06223)
			(type default)
		)
		(layer "B.Cu")
	)
	(gr_line
		(start 141.360906 -73.937114)
		(end 141.39164 -73.93051)
		(stroke
			(width 0.06223)
			(type default)
		)
		(layer "B.Cu")
	)
	(gr_line
		(start 141.381734 -48.188372)
		(end 141.39037 -48.229266)
		(stroke
			(width 0.06223)
			(type default)
		)
		(layer "B.Cu")
	)
	(gr_line
		(start 141.381734 -48.188372)
		(end 141.39037 -48.147732)
		(stroke
			(width 0.06223)
			(type default)
		)
		(layer "B.Cu")
	)
	(gr_line
		(start 141.39164 -73.93051)
		(end 141.418056 -73.913492)
		(stroke
			(width 0.06223)
			(type default)
		)
		(layer "B.Cu")
	)
	(gr_line
		(start 141.46149 -75.795124)
		(end 141.492224 -75.801728)
		(stroke
			(width 0.06223)
			(type default)
		)
		(layer "B.Cu")
	)
	(gr_line
		(start 141.483588 -79.273146)
		(end 141.558518 -79.289148)
		(stroke
			(width 0.06223)
			(type default)
		)
		(layer "B.Cu")
	)
	(gr_line
		(start 141.492224 -75.801728)
		(end 141.518386 -75.818746)
		(stroke
			(width 0.06223)
			(type default)
		)
		(layer "B.Cu")
	)
	(gr_line
		(start 141.558518 -79.289148)
		(end 141.612874 -79.343504)
		(stroke
			(width 0.06223)
			(type default)
		)
		(layer "B.Cu")
	)
	(gr_line
		(start 141.56436 -17.61744)
		(end 141.56436 -17.617694)
		(stroke
			(width 0.06223)
			(type default)
		)
		(layer "B.Cu")
	)
	(gr_line
		(start 141.56436 -17.61744)
		(end 141.572488 -17.579086)
		(stroke
			(width 0.06223)
			(type default)
		)
		(layer "B.Cu")
	)
	(gr_line
		(start 141.564868 -17.540732)
		(end 141.572488 -17.579086)
		(stroke
			(width 0.06223)
			(type default)
		)
		(layer "B.Cu")
	)
	(gr_line
		(start 141.643862 -77.716634)
		(end 141.674596 -77.722984)
		(stroke
			(width 0.06223)
			(type default)
		)
		(layer "B.Cu")
	)
	(gr_line
		(start 141.647672 -70.8025)
		(end 141.678406 -70.795896)
		(stroke
			(width 0.06223)
			(type default)
		)
		(layer "B.Cu")
	)
	(gr_line
		(start 141.674596 -77.722984)
		(end 141.701012 -77.740256)
		(stroke
			(width 0.06223)
			(type default)
		)
		(layer "B.Cu")
	)
	(gr_line
		(start 141.678406 -70.795896)
		(end 141.704822 -70.778878)
		(stroke
			(width 0.06223)
			(type default)
		)
		(layer "B.Cu")
	)
	(gr_arc
		(start 141.680946 -3.096768)
		(mid 141.726602 -3.087651)
		(end 141.765274 -3.061716)
		(stroke
			(width 0.06223)
			(type default)
		)
		(layer "B.Cu")
	)
	(gr_line
		(start 141.686788 -81.270856)
		(end 141.721586 -81.293462)
		(stroke
			(width 0.06223)
			(type default)
		)
		(layer "B.Cu")
	)
	(gr_line
		(start 141.721586 -81.293462)
		(end 141.744192 -81.32826)
		(stroke
			(width 0.06223)
			(type default)
		)
		(layer "B.Cu")
	)
	(gr_arc
		(start 141.765274 -3.53822)
		(mid 141.726606 -3.512279)
		(end 141.680946 -3.503168)
		(stroke
			(width 0.06223)
			(type default)
		)
		(layer "B.Cu")
	)
	(gr_arc
		(start 141.765274 -3.061716)
		(mid 141.791048 -3.023143)
		(end 141.800072 -2.977642)
		(stroke
			(width 0.06223)
			(type default)
		)
		(layer "B.Cu")
	)
	(gr_arc
		(start 141.800072 -3.622294)
		(mid 141.791042 -3.576795)
		(end 141.765274 -3.53822)
		(stroke
			(width 0.06223)
			(type default)
		)
		(layer "B.Cu")
	)
	(gr_line
		(start 141.800072 -3.622294)
		(end 141.800072 -3.999992)
		(stroke
			(width 0.06223)
			(type default)
		)
		(layer "B.Cu")
	)
	(gr_line
		(start 141.800072 -2.600198)
		(end 141.800072 -2.977642)
		(stroke
			(width 0.06223)
			(type default)
		)
		(layer "B.Cu")
	)
	(gr_line
		(start 141.81201 -65.771522)
		(end 141.847824 -65.748408)
		(stroke
			(width 0.06223)
			(type default)
		)
		(layer "B.Cu")
	)
	(gr_line
		(start 141.847824 -65.748408)
		(end 141.871446 -65.711832)
		(stroke
			(width 0.06223)
			(type default)
		)
		(layer "B.Cu")
	)
	(gr_line
		(start 141.897862 -32.621982)
		(end 141.906498 -32.662114)
		(stroke
			(width 0.06223)
			(type default)
		)
		(layer "B.Cu")
	)
	(gr_line
		(start 141.897862 -32.621982)
		(end 141.906498 -32.581342)
		(stroke
			(width 0.06223)
			(type default)
		)
		(layer "B.Cu")
	)
	(gr_line
		(start 142.005304 -83.528154)
		(end 142.083028 -83.893406)
		(stroke
			(width 0.06223)
			(type default)
		)
		(layer "B.Cu")
	)
	(gr_line
		(start 142.005304 -83.528154)
		(end 142.211044 -83.211416)
		(stroke
			(width 0.06223)
			(type default)
		)
		(layer "B.Cu")
	)
	(gr_line
		(start 142.083028 -83.893406)
		(end 142.399766 -84.099146)
		(stroke
			(width 0.06223)
			(type default)
		)
		(layer "B.Cu")
	)
	(gr_line
		(start 142.249652 -97.153222)
		(end 142.28445 -97.130616)
		(stroke
			(width 0.06223)
			(type default)
		)
		(layer "B.Cu")
	)
	(gr_line
		(start 142.28445 -97.130616)
		(end 142.307056 -97.095818)
		(stroke
			(width 0.06223)
			(type default)
		)
		(layer "B.Cu")
	)
	(gr_line
		(start 142.313152 -57.87136)
		(end 142.33017 -57.897776)
		(stroke
			(width 0.06223)
			(type default)
		)
		(layer "B.Cu")
	)
	(gr_line
		(start 142.33017 -57.897776)
		(end 142.336774 -57.92851)
		(stroke
			(width 0.06223)
			(type default)
		)
		(layer "B.Cu")
	)
	(gr_line
		(start 142.36827 -45.502068)
		(end 142.376906 -45.461936)
		(stroke
			(width 0.06223)
			(type default)
		)
		(layer "B.Cu")
	)
	(gr_line
		(start 142.36827 -45.420534)
		(end 142.376906 -45.461936)
		(stroke
			(width 0.06223)
			(type default)
		)
		(layer "B.Cu")
	)
	(gr_line
		(start 142.447264 -82.410554)
		(end 142.464282 -82.436716)
		(stroke
			(width 0.06223)
			(type default)
		)
		(layer "B.Cu")
	)
	(gr_line
		(start 142.464282 -82.436716)
		(end 142.470632 -82.46745)
		(stroke
			(width 0.06223)
			(type default)
		)
		(layer "B.Cu")
	)
	(gr_line
		(start 142.619222 -83.16468)
		(end 142.791434 -83.97494)
		(stroke
			(width 0.06223)
			(type default)
		)
		(layer "B.Cu")
	)
	(gr_line
		(start 142.62481 -64.551306)
		(end 142.641828 -64.52489)
		(stroke
			(width 0.06223)
			(type default)
		)
		(layer "B.Cu")
	)
	(gr_line
		(start 142.641828 -64.52489)
		(end 142.648432 -64.494156)
		(stroke
			(width 0.06223)
			(type default)
		)
		(layer "B.Cu")
	)
	(gr_line
		(start 142.706598 -66.704464)
		(end 142.741396 -66.681858)
		(stroke
			(width 0.06223)
			(type default)
		)
		(layer "B.Cu")
	)
	(gr_line
		(start 142.741396 -66.681858)
		(end 142.764002 -66.64706)
		(stroke
			(width 0.06223)
			(type default)
		)
		(layer "B.Cu")
	)
	(gr_line
		(start 142.743682 -54.596792)
		(end 142.750286 -54.627526)
		(stroke
			(width 0.06223)
			(type default)
		)
		(layer "B.Cu")
	)
	(gr_line
		(start 142.750286 -54.627526)
		(end 142.767304 -54.653942)
		(stroke
			(width 0.06223)
			(type default)
		)
		(layer "B.Cu")
	)
	(gr_line
		(start 142.783052 -47.616872)
		(end 142.791688 -47.657766)
		(stroke
			(width 0.06223)
			(type default)
		)
		(layer "B.Cu")
	)
	(gr_line
		(start 142.783052 -47.616872)
		(end 142.791688 -47.576232)
		(stroke
			(width 0.06223)
			(type default)
		)
		(layer "B.Cu")
	)
	(gr_line
		(start 143.076676 -91.312238)
		(end 143.092678 -91.287854)
		(stroke
			(width 0.06223)
			(type default)
		)
		(layer "B.Cu")
	)
	(gr_line
		(start 143.092678 -91.287854)
		(end 143.093186 -91.287854)
		(stroke
			(width 0.06223)
			(type default)
		)
		(layer "B.Cu")
	)
	(gr_line
		(start 143.093186 -91.287854)
		(end 143.099536 -91.257628)
		(stroke
			(width 0.06223)
			(type default)
		)
		(layer "B.Cu")
	)
	(gr_line
		(start 143.134588 -98.057462)
		(end 143.169386 -98.034856)
		(stroke
			(width 0.06223)
			(type default)
		)
		(layer "B.Cu")
	)
	(gr_line
		(start 143.169386 -98.034856)
		(end 143.191992 -98.000058)
		(stroke
			(width 0.06223)
			(type default)
		)
		(layer "B.Cu")
	)
	(gr_line
		(start 143.181578 -61.983874)
		(end 143.190214 -61.94298)
		(stroke
			(width 0.06223)
			(type default)
		)
		(layer "B.Cu")
	)
	(gr_line
		(start 143.181578 -61.90234)
		(end 143.190214 -61.94298)
		(stroke
			(width 0.06223)
			(type default)
		)
		(layer "B.Cu")
	)
	(gr_line
		(start 143.236696 -32.183832)
		(end 143.245332 -32.223964)
		(stroke
			(width 0.06223)
			(type default)
		)
		(layer "B.Cu")
	)
	(gr_line
		(start 143.236696 -32.183832)
		(end 143.245332 -32.143192)
		(stroke
			(width 0.06223)
			(type default)
		)
		(layer "B.Cu")
	)
	(gr_line
		(start 143.44523 -67.887596)
		(end 143.480028 -67.86499)
		(stroke
			(width 0.06223)
			(type default)
		)
		(layer "B.Cu")
	)
	(gr_line
		(start 143.480028 -67.86499)
		(end 143.502634 -67.830192)
		(stroke
			(width 0.06223)
			(type default)
		)
		(layer "B.Cu")
	)
	(gr_arc
		(start 143.481044 -4.296918)
		(mid 143.5267 -4.287801)
		(end 143.565372 -4.261866)
		(stroke
			(width 0.06223)
			(type default)
		)
		(layer "B.Cu")
	)
	(gr_line
		(start 143.55699 -57.454546)
		(end 143.574008 -57.480962)
		(stroke
			(width 0.06223)
			(type default)
		)
		(layer "B.Cu")
	)
	(gr_arc
		(start 143.565372 -4.73837)
		(mid 143.526701 -4.712441)
		(end 143.481044 -4.703318)
		(stroke
			(width 0.06223)
			(type default)
		)
		(layer "B.Cu")
	)
	(gr_arc
		(start 143.565372 -4.261866)
		(mid 143.591146 -4.223293)
		(end 143.60017 -4.177792)
		(stroke
			(width 0.06223)
			(type default)
		)
		(layer "B.Cu")
	)
	(gr_line
		(start 143.574008 -57.480962)
		(end 143.580612 -57.511696)
		(stroke
			(width 0.06223)
			(type default)
		)
		(layer "B.Cu")
	)
	(gr_arc
		(start 143.60017 -4.822444)
		(mid 143.591162 -4.776929)
		(end 143.565372 -4.73837)
		(stroke
			(width 0.06223)
			(type default)
		)
		(layer "B.Cu")
	)
	(gr_line
		(start 143.60017 -4.822444)
		(end 143.60017 -5.200142)
		(stroke
			(width 0.06223)
			(type default)
		)
		(layer "B.Cu")
	)
	(gr_line
		(start 143.60017 -3.800094)
		(end 143.60017 -4.177792)
		(stroke
			(width 0.06223)
			(type default)
		)
		(layer "B.Cu")
	)
	(gr_line
		(start 143.671036 -45.394118)
		(end 143.679672 -45.353986)
		(stroke
			(width 0.06223)
			(type default)
		)
		(layer "B.Cu")
	)
	(gr_line
		(start 143.671036 -45.313346)
		(end 143.679672 -45.353986)
		(stroke
			(width 0.06223)
			(type default)
		)
		(layer "B.Cu")
	)
	(gr_line
		(start 143.67256 -79.02067)
		(end 143.707358 -79.043276)
		(stroke
			(width 0.06223)
			(type default)
		)
		(layer "B.Cu")
	)
	(gr_line
		(start 143.707358 -79.043276)
		(end 143.729964 -79.078074)
		(stroke
			(width 0.06223)
			(type default)
		)
		(layer "B.Cu")
	)
	(gr_line
		(start 143.71066 -88.379554)
		(end 143.719296 -88.338914)
		(stroke
			(width 0.06223)
			(type default)
		)
		(layer "B.Cu")
	)
	(gr_line
		(start 143.71066 -88.298782)
		(end 143.719296 -88.338914)
		(stroke
			(width 0.06223)
			(type default)
		)
		(layer "B.Cu")
	)
	(gr_line
		(start 143.81734 -65.025778)
		(end 143.834358 -64.999616)
		(stroke
			(width 0.06223)
			(type default)
		)
		(layer "B.Cu")
	)
	(gr_line
		(start 143.834358 -64.999616)
		(end 143.840962 -64.968882)
		(stroke
			(width 0.06223)
			(type default)
		)
		(layer "B.Cu")
	)
	(gr_line
		(start 143.894302 -82.052922)
		(end 143.91132 -82.079338)
		(stroke
			(width 0.06223)
			(type default)
		)
		(layer "B.Cu")
	)
	(gr_line
		(start 143.900398 -85.279992)
		(end 143.977868 -85.645244)
		(stroke
			(width 0.06223)
			(type default)
		)
		(layer "B.Cu")
	)
	(gr_line
		(start 143.900398 -85.279992)
		(end 144.105884 -84.963508)
		(stroke
			(width 0.06223)
			(type default)
		)
		(layer "B.Cu")
	)
	(gr_line
		(start 143.91132 -82.079338)
		(end 143.917924 -82.110072)
		(stroke
			(width 0.06223)
			(type default)
		)
		(layer "B.Cu")
	)
	(gr_line
		(start 143.977868 -85.645244)
		(end 144.294352 -85.850984)
		(stroke
			(width 0.06223)
			(type default)
		)
		(layer "B.Cu")
	)
	(gr_line
		(start 144.041368 -69.261228)
		(end 144.076166 -69.238622)
		(stroke
			(width 0.06223)
			(type default)
		)
		(layer "B.Cu")
	)
	(gr_line
		(start 144.076166 -69.238622)
		(end 144.098772 -69.203824)
		(stroke
			(width 0.06223)
			(type default)
		)
		(layer "B.Cu")
	)
	(gr_line
		(start 144.182338 -46.985174)
		(end 144.190974 -47.026068)
		(stroke
			(width 0.06223)
			(type default)
		)
		(layer "B.Cu")
	)
	(gr_line
		(start 144.182338 -46.985174)
		(end 144.190974 -46.944534)
		(stroke
			(width 0.06223)
			(type default)
		)
		(layer "B.Cu")
	)
	(gr_line
		(start 144.236694 -77.585062)
		(end 144.271492 -77.607668)
		(stroke
			(width 0.06223)
			(type default)
		)
		(layer "B.Cu")
	)
	(gr_line
		(start 144.270222 -54.615588)
		(end 144.276826 -54.646322)
		(stroke
			(width 0.06223)
			(type default)
		)
		(layer "B.Cu")
	)
	(gr_line
		(start 144.271492 -77.607668)
		(end 144.294098 -77.642466)
		(stroke
			(width 0.06223)
			(type default)
		)
		(layer "B.Cu")
	)
	(gr_line
		(start 144.276826 -54.646322)
		(end 144.293844 -54.672738)
		(stroke
			(width 0.06223)
			(type default)
		)
		(layer "B.Cu")
	)
	(gr_line
		(start 144.371314 -91.610688)
		(end 144.388332 -91.584272)
		(stroke
			(width 0.06223)
			(type default)
		)
		(layer "B.Cu")
	)
	(gr_line
		(start 144.388332 -91.584272)
		(end 144.394936 -91.553538)
		(stroke
			(width 0.06223)
			(type default)
		)
		(layer "B.Cu")
	)
	(gr_line
		(start 144.494758 -61.894466)
		(end 144.503394 -61.854334)
		(stroke
			(width 0.06223)
			(type default)
		)
		(layer "B.Cu")
	)
	(gr_line
		(start 144.494758 -61.813694)
		(end 144.503394 -61.854334)
		(stroke
			(width 0.06223)
			(type default)
		)
		(layer "B.Cu")
	)
	(gr_line
		(start 144.51457 -84.92109)
		(end 144.685258 -85.724238)
		(stroke
			(width 0.06223)
			(type default)
		)
		(layer "B.Cu")
	)
	(gr_line
		(start 144.837404 -57.094628)
		(end 144.854422 -57.121044)
		(stroke
			(width 0.06223)
			(type default)
		)
		(layer "B.Cu")
	)
	(gr_line
		(start 144.854422 -57.121044)
		(end 144.861026 -57.151778)
		(stroke
			(width 0.06223)
			(type default)
		)
		(layer "B.Cu")
	)
	(gr_line
		(start 144.950942 -65.60185)
		(end 144.96796 -65.575688)
		(stroke
			(width 0.06223)
			(type default)
		)
		(layer "B.Cu")
	)
	(gr_line
		(start 144.96796 -65.575688)
		(end 144.974564 -65.544954)
		(stroke
			(width 0.06223)
			(type default)
		)
		(layer "B.Cu")
	)
	(gr_line
		(start 144.973548 -45.217842)
		(end 144.982184 -45.17771)
		(stroke
			(width 0.06223)
			(type default)
		)
		(layer "B.Cu")
	)
	(gr_line
		(start 144.973548 -45.13707)
		(end 144.982184 -45.17771)
		(stroke
			(width 0.06223)
			(type default)
		)
		(layer "B.Cu")
	)
	(gr_line
		(start 144.978628 -82.866992)
		(end 145.056098 -83.232244)
		(stroke
			(width 0.06223)
			(type default)
		)
		(layer "B.Cu")
	)
	(gr_line
		(start 144.978628 -82.866992)
		(end 145.184114 -82.550508)
		(stroke
			(width 0.06223)
			(type default)
		)
		(layer "B.Cu")
	)
	(gr_line
		(start 145.056098 -83.232244)
		(end 145.372582 -83.43773)
		(stroke
			(width 0.06223)
			(type default)
		)
		(layer "B.Cu")
	)
	(gr_line
		(start 145.079466 -70.061074)
		(end 145.114264 -70.038468)
		(stroke
			(width 0.06223)
			(type default)
		)
		(layer "B.Cu")
	)
	(gr_line
		(start 145.114264 -70.038468)
		(end 145.13687 -70.00367)
		(stroke
			(width 0.06223)
			(type default)
		)
		(layer "B.Cu")
	)
	(gr_line
		(start 145.150586 -87.995506)
		(end 145.159222 -87.954866)
		(stroke
			(width 0.06223)
			(type default)
		)
		(layer "B.Cu")
	)
	(gr_line
		(start 145.150586 -87.913972)
		(end 145.159222 -87.954866)
		(stroke
			(width 0.06223)
			(type default)
		)
		(layer "B.Cu")
	)
	(gr_arc
		(start 145.280888 -3.096768)
		(mid 145.326544 -3.087651)
		(end 145.365216 -3.061716)
		(stroke
			(width 0.06223)
			(type default)
		)
		(layer "B.Cu")
	)
	(gr_arc
		(start 145.365216 -3.53822)
		(mid 145.326545 -3.512298)
		(end 145.280888 -3.503168)
		(stroke
			(width 0.06223)
			(type default)
		)
		(layer "B.Cu")
	)
	(gr_arc
		(start 145.365216 -3.061716)
		(mid 145.39099 -3.023143)
		(end 145.400014 -2.977642)
		(stroke
			(width 0.06223)
			(type default)
		)
		(layer "B.Cu")
	)
	(gr_line
		(start 145.398998 -81.6483)
		(end 145.416016 -81.674716)
		(stroke
			(width 0.06223)
			(type default)
		)
		(layer "B.Cu")
	)
	(gr_arc
		(start 145.400014 -3.622294)
		(mid 145.390987 -3.576793)
		(end 145.365216 -3.53822)
		(stroke
			(width 0.06223)
			(type default)
		)
		(layer "B.Cu")
	)
	(gr_line
		(start 145.400014 -3.622294)
		(end 145.400014 -3.999992)
		(stroke
			(width 0.06223)
			(type default)
		)
		(layer "B.Cu")
	)
	(gr_line
		(start 145.400014 -2.600198)
		(end 145.400014 -2.977642)
		(stroke
			(width 0.06223)
			(type default)
		)
		(layer "B.Cu")
	)
	(gr_line
		(start 145.416016 -81.674716)
		(end 145.42262 -81.70545)
		(stroke
			(width 0.06223)
			(type default)
		)
		(layer "B.Cu")
	)
	(gr_line
		(start 145.585434 -46.284896)
		(end 145.594324 -46.243494)
		(stroke
			(width 0.06223)
			(type default)
		)
		(layer "B.Cu")
	)
	(gr_line
		(start 145.585434 -46.284896)
		(end 145.594578 -46.327822)
		(stroke
			(width 0.06223)
			(type default)
		)
		(layer "B.Cu")
	)
	(gr_line
		(start 145.5928 -82.506058)
		(end 145.76425 -83.312508)
		(stroke
			(width 0.06223)
			(type default)
		)
		(layer "B.Cu")
	)
	(gr_line
		(start 145.800572 -61.65469)
		(end 145.809208 -61.613796)
		(stroke
			(width 0.06223)
			(type default)
		)
		(layer "B.Cu")
	)
	(gr_line
		(start 145.800572 -61.573156)
		(end 145.809208 -61.613796)
		(stroke
			(width 0.06223)
			(type default)
		)
		(layer "B.Cu")
	)
	(gr_line
		(start 145.810732 -54.65572)
		(end 145.817336 -54.686454)
		(stroke
			(width 0.06223)
			(type default)
		)
		(layer "B.Cu")
	)
	(gr_line
		(start 145.817336 -54.6862)
		(end 145.817336 -54.686454)
		(stroke
			(width 0.06223)
			(type default)
		)
		(layer "B.Cu")
	)
	(gr_line
		(start 145.817336 -54.6862)
		(end 145.833846 -54.7116)
		(stroke
			(width 0.06223)
			(type default)
		)
		(layer "B.Cu")
	)
	(gr_line
		(start 145.926556 -91.521788)
		(end 145.943574 -91.495372)
		(stroke
			(width 0.06223)
			(type default)
		)
		(layer "B.Cu")
	)
	(gr_line
		(start 145.943574 -91.495372)
		(end 145.950178 -91.464638)
		(stroke
			(width 0.06223)
			(type default)
		)
		(layer "B.Cu")
	)
	(gr_line
		(start 146.03222 -70.916038)
		(end 146.068034 -70.892924)
		(stroke
			(width 0.06223)
			(type default)
		)
		(layer "B.Cu")
	)
	(gr_line
		(start 146.068034 -70.892924)
		(end 146.091656 -70.856348)
		(stroke
			(width 0.06223)
			(type default)
		)
		(layer "B.Cu")
	)
	(gr_line
		(start 146.072352 -56.664352)
		(end 146.08937 -56.690768)
		(stroke
			(width 0.06223)
			(type default)
		)
		(layer "B.Cu")
	)
	(gr_line
		(start 146.08937 -56.690768)
		(end 146.095974 -56.721502)
		(stroke
			(width 0.06223)
			(type default)
		)
		(layer "B.Cu")
	)
	(gr_line
		(start 146.150838 -66.043048)
		(end 146.167856 -66.016632)
		(stroke
			(width 0.06223)
			(type default)
		)
		(layer "B.Cu")
	)
	(gr_line
		(start 146.167856 -66.016632)
		(end 146.17446 -65.985898)
		(stroke
			(width 0.06223)
			(type default)
		)
		(layer "B.Cu")
	)
	(gr_line
		(start 146.316954 -44.800012)
		(end 146.32559 -44.75988)
		(stroke
			(width 0.06223)
			(type default)
		)
		(layer "B.Cu")
	)
	(gr_line
		(start 146.316954 -44.71924)
		(end 146.32559 -44.75988)
		(stroke
			(width 0.06223)
			(type default)
		)
		(layer "B.Cu")
	)
	(gr_line
		(start 146.65579 -16.100044)
		(end 146.662394 -16.06931)
		(stroke
			(width 0.06223)
			(type default)
		)
		(layer "B.Cu")
	)
	(gr_line
		(start 146.662394 -16.06931)
		(end 146.679412 -16.042894)
		(stroke
			(width 0.06223)
			(type default)
		)
		(layer "B.Cu")
	)
	(gr_line
		(start 146.714718 -87.866474)
		(end 146.723354 -87.825834)
		(stroke
			(width 0.06223)
			(type default)
		)
		(layer "B.Cu")
	)
	(gr_line
		(start 146.714718 -87.78494)
		(end 146.723354 -87.825834)
		(stroke
			(width 0.06223)
			(type default)
		)
		(layer "B.Cu")
	)
	(gr_line
		(start 146.971258 -84.735924)
		(end 147.048982 -85.101176)
		(stroke
			(width 0.06223)
			(type default)
		)
		(layer "B.Cu")
	)
	(gr_line
		(start 146.971258 -84.735924)
		(end 147.176998 -84.41944)
		(stroke
			(width 0.06223)
			(type default)
		)
		(layer "B.Cu")
	)
	(gr_line
		(start 147.042886 -81.87436)
		(end 147.059904 -81.900776)
		(stroke
			(width 0.06223)
			(type default)
		)
		(layer "B.Cu")
	)
	(gr_line
		(start 147.048982 -85.101176)
		(end 147.365466 -85.306662)
		(stroke
			(width 0.06223)
			(type default)
		)
		(layer "B.Cu")
	)
	(gr_line
		(start 147.059904 -81.900776)
		(end 147.066508 -81.93151)
		(stroke
			(width 0.06223)
			(type default)
		)
		(layer "B.Cu")
	)
	(gr_arc
		(start 147.080986 -4.296918)
		(mid 147.126642 -4.287801)
		(end 147.165314 -4.261866)
		(stroke
			(width 0.06223)
			(type default)
		)
		(layer "B.Cu")
	)
	(gr_line
		(start 147.089876 -91.997022)
		(end 147.106894 -91.970606)
		(stroke
			(width 0.06223)
			(type default)
		)
		(layer "B.Cu")
	)
	(gr_line
		(start 147.106894 -91.970606)
		(end 147.113498 -91.939872)
		(stroke
			(width 0.06223)
			(type default)
		)
		(layer "B.Cu")
	)
	(gr_line
		(start 147.110704 -61.57849)
		(end 147.11934 -61.537596)
		(stroke
			(width 0.06223)
			(type default)
		)
		(layer "B.Cu")
	)
	(gr_line
		(start 147.110704 -61.496956)
		(end 147.11934 -61.537596)
		(stroke
			(width 0.06223)
			(type default)
		)
		(layer "B.Cu")
	)
	(gr_arc
		(start 147.165314 -4.73837)
		(mid 147.12664 -4.71246)
		(end 147.080986 -4.703318)
		(stroke
			(width 0.06223)
			(type default)
		)
		(layer "B.Cu")
	)
	(gr_arc
		(start 147.165314 -4.261866)
		(mid 147.191088 -4.223293)
		(end 147.200112 -4.177792)
		(stroke
			(width 0.06223)
			(type default)
		)
		(layer "B.Cu")
	)
	(gr_arc
		(start 147.200112 -4.822444)
		(mid 147.191101 -4.776932)
		(end 147.165314 -4.73837)
		(stroke
			(width 0.06223)
			(type default)
		)
		(layer "B.Cu")
	)
	(gr_line
		(start 147.200112 -4.822444)
		(end 147.200112 -5.200142)
		(stroke
			(width 0.06223)
			(type default)
		)
		(layer "B.Cu")
	)
	(gr_line
		(start 147.200112 -3.800094)
		(end 147.200112 -4.177792)
		(stroke
			(width 0.06223)
			(type default)
		)
		(layer "B.Cu")
	)
	(gr_line
		(start 147.328382 -56.266588)
		(end 147.3454 -56.293004)
		(stroke
			(width 0.06223)
			(type default)
		)
		(layer "B.Cu")
	)
	(gr_line
		(start 147.330414 -66.626486)
		(end 147.347432 -66.60007)
		(stroke
			(width 0.06223)
			(type default)
		)
		(layer "B.Cu")
	)
	(gr_line
		(start 147.3454 -56.293004)
		(end 147.352004 -56.323738)
		(stroke
			(width 0.06223)
			(type default)
		)
		(layer "B.Cu")
	)
	(gr_line
		(start 147.347432 -66.60007)
		(end 147.354036 -66.569336)
		(stroke
			(width 0.06223)
			(type default)
		)
		(layer "B.Cu")
	)
	(gr_line
		(start 147.395692 -54.76367)
		(end 147.40255 -54.79542)
		(stroke
			(width 0.06223)
			(type default)
		)
		(layer "B.Cu")
	)
	(gr_line
		(start 147.40255 -54.79542)
		(end 147.419822 -54.821836)
		(stroke
			(width 0.06223)
			(type default)
		)
		(layer "B.Cu")
	)
	(gr_line
		(start 147.585684 -84.375244)
		(end 147.756626 -85.18017)
		(stroke
			(width 0.06223)
			(type default)
		)
		(layer "B.Cu")
	)
	(gr_line
		(start 148.107146 -14.591284)
		(end 148.124164 -14.564868)
		(stroke
			(width 0.06223)
			(type default)
		)
		(layer "B.Cu")
	)
	(gr_line
		(start 148.124164 -14.564868)
		(end 148.130768 -14.534134)
		(stroke
			(width 0.06223)
			(type default)
		)
		(layer "B.Cu")
	)
	(gr_line
		(start 148.14423 -87.086186)
		(end 148.152866 -87.045546)
		(stroke
			(width 0.06223)
			(type default)
		)
		(layer "B.Cu")
	)
	(gr_line
		(start 148.14423 -87.004652)
		(end 148.152866 -87.045546)
		(stroke
			(width 0.06223)
			(type default)
		)
		(layer "B.Cu")
	)
	(gr_line
		(start 148.433282 -61.492892)
		(end 148.441918 -61.45276)
		(stroke
			(width 0.06223)
			(type default)
		)
		(layer "B.Cu")
	)
	(gr_line
		(start 148.433282 -61.41212)
		(end 148.441918 -61.45276)
		(stroke
			(width 0.06223)
			(type default)
		)
		(layer "B.Cu")
	)
	(gr_line
		(start 148.548598 -55.813452)
		(end 148.565616 -55.839868)
		(stroke
			(width 0.06223)
			(type default)
		)
		(layer "B.Cu")
	)
	(gr_line
		(start 148.565616 -55.839868)
		(end 148.57222 -55.870602)
		(stroke
			(width 0.06223)
			(type default)
		)
		(layer "B.Cu")
	)
	(gr_line
		(start 148.583904 -67.017646)
		(end 148.60143 -66.990468)
		(stroke
			(width 0.06223)
			(type default)
		)
		(layer "B.Cu")
	)
	(gr_line
		(start 148.60143 -66.990468)
		(end 148.60778 -66.958718)
		(stroke
			(width 0.06223)
			(type default)
		)
		(layer "B.Cu")
	)
	(gr_arc
		(start 148.88083 -3.096768)
		(mid 148.926486 -3.087651)
		(end 148.965158 -3.061716)
		(stroke
			(width 0.06223)
			(type default)
		)
		(layer "B.Cu")
	)
	(gr_arc
		(start 148.965158 -3.53822)
		(mid 148.926489 -3.512285)
		(end 148.88083 -3.503168)
		(stroke
			(width 0.06223)
			(type default)
		)
		(layer "B.Cu")
	)
	(gr_arc
		(start 148.965158 -3.061716)
		(mid 148.990932 -3.023143)
		(end 148.999956 -2.977642)
		(stroke
			(width 0.06223)
			(type default)
		)
		(layer "B.Cu")
	)
	(gr_arc
		(start 148.999956 -3.622294)
		(mid 148.990931 -3.57679)
		(end 148.965158 -3.53822)
		(stroke
			(width 0.06223)
			(type default)
		)
		(layer "B.Cu")
	)
	(gr_line
		(start 148.999956 -3.622294)
		(end 148.999956 -3.999992)
		(stroke
			(width 0.06223)
			(type default)
		)
		(layer "B.Cu")
	)
	(gr_line
		(start 148.999956 -2.600198)
		(end 148.999956 -2.977642)
		(stroke
			(width 0.06223)
			(type default)
		)
		(layer "B.Cu")
	)
	(gr_line
		(start 149.724618 -61.292994)
		(end 149.732746 -61.331348)
		(stroke
			(width 0.06223)
			(type default)
		)
		(layer "B.Cu")
	)
	(gr_line
		(start 149.725126 -61.369702)
		(end 149.725126 -61.37021)
		(stroke
			(width 0.06223)
			(type default)
		)
		(layer "B.Cu")
	)
	(gr_line
		(start 149.725126 -61.369702)
		(end 149.732746 -61.331348)
		(stroke
			(width 0.06223)
			(type default)
		)
		(layer "B.Cu")
	)
	(gr_line
		(start 164.916358 -25.716484)
		(end 165.066218 -25.866344)
		(stroke
			(width 0.072898)
			(type default)
		)
		(layer "B.Cu")
	)
	(gr_line
		(start 164.916358 -25.278334)
		(end 164.916358 -25.716484)
		(stroke
			(width 0.072898)
			(type default)
		)
		(layer "B.Cu")
	)
	(gr_line
		(start 164.916358 -25.278334)
		(end 165.066218 -25.128474)
		(stroke
			(width 0.072898)
			(type default)
		)
		(layer "B.Cu")
	)
	(gr_line
		(start 164.916358 -24.535384)
		(end 165.066218 -24.685244)
		(stroke
			(width 0.072898)
			(type default)
		)
		(layer "B.Cu")
	)
	(gr_line
		(start 164.916358 -24.097234)
		(end 164.916358 -24.535384)
		(stroke
			(width 0.072898)
			(type default)
		)
		(layer "B.Cu")
	)
	(gr_line
		(start 164.916358 -24.097234)
		(end 165.066218 -23.947374)
		(stroke
			(width 0.072898)
			(type default)
		)
		(layer "B.Cu")
	)
	(gr_line
		(start 164.916358 -22.173184)
		(end 165.066218 -22.323044)
		(stroke
			(width 0.072898)
			(type default)
		)
		(layer "B.Cu")
	)
	(gr_line
		(start 164.916358 -21.735034)
		(end 164.916358 -22.173184)
		(stroke
			(width 0.072898)
			(type default)
		)
		(layer "B.Cu")
	)
	(gr_line
		(start 164.916358 -21.735034)
		(end 165.066218 -21.585174)
		(stroke
			(width 0.072898)
			(type default)
		)
		(layer "B.Cu")
	)
	(gr_line
		(start 164.922962 -23.360888)
		(end 165.066218 -23.504144)
		(stroke
			(width 0.072898)
			(type default)
		)
		(layer "B.Cu")
	)
	(gr_line
		(start 164.922962 -22.90953)
		(end 164.922962 -23.360888)
		(stroke
			(width 0.072898)
			(type default)
		)
		(layer "B.Cu")
	)
	(gr_line
		(start 164.922962 -22.90953)
		(end 165.066218 -22.766274)
		(stroke
			(width 0.072898)
			(type default)
		)
		(layer "B.Cu")
	)
	(gr_line
		(start 164.923978 -21.018246)
		(end 165.029642 -21.12391)
		(stroke
			(width 0.072898)
			(type default)
		)
		(layer "B.Cu")
	)
	(gr_line
		(start 164.923978 -20.862544)
		(end 164.923978 -21.018246)
		(stroke
			(width 0.072898)
			(type default)
		)
		(layer "B.Cu")
	)
	(gr_line
		(start 164.923978 -20.170902)
		(end 164.923978 -20.303744)
		(stroke
			(width 0.072898)
			(type default)
		)
		(layer "B.Cu")
	)
	(gr_line
		(start 164.923978 -20.170902)
		(end 165.017196 -20.077684)
		(stroke
			(width 0.072898)
			(type default)
		)
		(layer "B.Cu")
	)
	(gr_line
		(start 165.122606 -19.431)
		(end 165.126162 -19.413474)
		(stroke
			(width 0.072898)
			(type default)
		)
		(layer "B.Cu")
	)
	(gr_line
		(start 165.126162 -19.413474)
		(end 165.136322 -19.397726)
		(stroke
			(width 0.072898)
			(type default)
		)
		(layer "B.Cu")
	)
	(gr_line
		(start 165.379908 -25.439624)
		(end 165.379908 -25.555194)
		(stroke
			(width 0.072898)
			(type default)
		)
		(layer "B.Cu")
	)
	(gr_line
		(start 165.379908 -24.258524)
		(end 165.379908 -24.374094)
		(stroke
			(width 0.072898)
			(type default)
		)
		(layer "B.Cu")
	)
	(gr_line
		(start 165.379908 -23.077424)
		(end 165.379908 -23.192994)
		(stroke
			(width 0.072898)
			(type default)
		)
		(layer "B.Cu")
	)
	(gr_line
		(start 165.379908 -21.896324)
		(end 165.379908 -22.011894)
		(stroke
			(width 0.072898)
			(type default)
		)
		(layer "B.Cu")
	)
	(gr_line
		(start 165.460934 -20.077684)
		(end 165.558978 -20.175728)
		(stroke
			(width 0.072898)
			(type default)
		)
		(layer "B.Cu")
	)
	(gr_line
		(start 165.473126 -21.12391)
		(end 165.558978 -21.038058)
		(stroke
			(width 0.072898)
			(type default)
		)
		(layer "B.Cu")
	)
	(gr_line
		(start 165.558978 -20.862544)
		(end 165.558978 -21.038058)
		(stroke
			(width 0.072898)
			(type default)
		)
		(layer "B.Cu")
	)
	(gr_line
		(start 165.558978 -20.175728)
		(end 165.558978 -20.303744)
		(stroke
			(width 0.072898)
			(type default)
		)
		(layer "B.Cu")
	)
	(gr_line
		(start 165.893496 -27.172666)
		(end 166.203376 -27.482546)
		(stroke
			(width 0.072898)
			(type default)
		)
		(layer "B.Cu")
	)
	(gr_line
		(start 165.893496 -26.96083)
		(end 165.893496 -27.172666)
		(stroke
			(width 0.072898)
			(type default)
		)
		(layer "B.Cu")
	)
	(gr_line
		(start 165.966394 -18.119598)
		(end 165.979348 -18.099786)
		(stroke
			(width 0.072898)
			(type default)
		)
		(layer "B.Cu")
	)
	(gr_line
		(start 165.979348 -18.099786)
		(end 165.98011 -18.09877)
		(stroke
			(width 0.072898)
			(type default)
		)
		(layer "B.Cu")
	)
	(gr_line
		(start 165.98011 -18.09877)
		(end 166.001446 -18.084292)
		(stroke
			(width 0.072898)
			(type default)
		)
		(layer "B.Cu")
	)
	(gr_line
		(start 166.203376 -27.482546)
		(end 166.415212 -27.482546)
		(stroke
			(width 0.072898)
			(type default)
		)
		(layer "B.Cu")
	)
	(gr_line
		(start 166.335456 -26.959052)
		(end 166.41699 -27.040586)
		(stroke
			(width 0.072898)
			(type default)
		)
		(layer "B.Cu")
	)
	(gr_line
		(start 166.64432 -21.10232)
		(end 166.732458 -21.190458)
		(stroke
			(width 0.072898)
			(type default)
		)
		(layer "B.Cu")
	)
	(gr_line
		(start 166.64432 -20.852384)
		(end 166.64432 -21.10232)
		(stroke
			(width 0.072898)
			(type default)
		)
		(layer "B.Cu")
	)
	(gr_line
		(start 166.64432 -20.293584)
		(end 166.740078 -20.197826)
		(stroke
			(width 0.072898)
			(type default)
		)
		(layer "B.Cu")
	)
	(gr_line
		(start 166.728648 -28.007818)
		(end 167.038528 -28.317698)
		(stroke
			(width 0.072898)
			(type default)
		)
		(layer "B.Cu")
	)
	(gr_line
		(start 166.728648 -27.795982)
		(end 166.728648 -28.007818)
		(stroke
			(width 0.072898)
			(type default)
		)
		(layer "B.Cu")
	)
	(gr_line
		(start 166.844218 -19.51863)
		(end 166.84879 -19.495262)
		(stroke
			(width 0.072898)
			(type default)
		)
		(layer "B.Cu")
	)
	(gr_line
		(start 166.84879 -19.495262)
		(end 166.862252 -19.475196)
		(stroke
			(width 0.072898)
			(type default)
		)
		(layer "B.Cu")
	)
	(gr_line
		(start 166.90848 -26.361898)
		(end 167.05834 -26.511758)
		(stroke
			(width 0.072898)
			(type default)
		)
		(layer "B.Cu")
	)
	(gr_line
		(start 166.90848 -25.923748)
		(end 166.90848 -26.361898)
		(stroke
			(width 0.072898)
			(type default)
		)
		(layer "B.Cu")
	)
	(gr_line
		(start 166.90848 -25.923748)
		(end 167.05834 -25.773888)
		(stroke
			(width 0.072898)
			(type default)
		)
		(layer "B.Cu")
	)
	(gr_line
		(start 166.90848 -25.180798)
		(end 167.05834 -25.330658)
		(stroke
			(width 0.072898)
			(type default)
		)
		(layer "B.Cu")
	)
	(gr_line
		(start 166.90848 -24.742648)
		(end 166.90848 -25.180798)
		(stroke
			(width 0.072898)
			(type default)
		)
		(layer "B.Cu")
	)
	(gr_line
		(start 166.90848 -24.742648)
		(end 167.05834 -24.592788)
		(stroke
			(width 0.072898)
			(type default)
		)
		(layer "B.Cu")
	)
	(gr_line
		(start 166.90848 -23.999698)
		(end 167.05834 -24.149558)
		(stroke
			(width 0.072898)
			(type default)
		)
		(layer "B.Cu")
	)
	(gr_line
		(start 166.90848 -23.561548)
		(end 166.90848 -23.999698)
		(stroke
			(width 0.072898)
			(type default)
		)
		(layer "B.Cu")
	)
	(gr_line
		(start 166.90848 -23.561548)
		(end 167.05834 -23.411688)
		(stroke
			(width 0.072898)
			(type default)
		)
		(layer "B.Cu")
	)
	(gr_line
		(start 166.90848 -22.818598)
		(end 167.05834 -22.968458)
		(stroke
			(width 0.072898)
			(type default)
		)
		(layer "B.Cu")
	)
	(gr_line
		(start 166.90848 -22.380448)
		(end 166.90848 -22.818598)
		(stroke
			(width 0.072898)
			(type default)
		)
		(layer "B.Cu")
	)
	(gr_line
		(start 166.90848 -22.380448)
		(end 167.05834 -22.230588)
		(stroke
			(width 0.072898)
			(type default)
		)
		(layer "B.Cu")
	)
	(gr_line
		(start 166.966392 -17.43329)
		(end 167.52062 -17.059402)
		(stroke
			(width 0.072898)
			(type default)
		)
		(layer "B.Cu")
	)
	(gr_line
		(start 167.038528 -28.317698)
		(end 167.250364 -28.317698)
		(stroke
			(width 0.072898)
			(type default)
		)
		(layer "B.Cu")
	)
	(gr_line
		(start 167.11295 -17.712944)
		(end 167.32123 -17.75333)
		(stroke
			(width 0.072898)
			(type default)
		)
		(layer "B.Cu")
	)
	(gr_line
		(start 167.170608 -27.794204)
		(end 167.252142 -27.875738)
		(stroke
			(width 0.072898)
			(type default)
		)
		(layer "B.Cu")
	)
	(gr_line
		(start 167.175942 -21.190458)
		(end 167.27932 -21.08708)
		(stroke
			(width 0.072898)
			(type default)
		)
		(layer "B.Cu")
	)
	(gr_line
		(start 167.183562 -20.197826)
		(end 167.27932 -20.293584)
		(stroke
			(width 0.072898)
			(type default)
		)
		(layer "B.Cu")
	)
	(gr_line
		(start 167.27932 -20.852384)
		(end 167.27932 -21.08708)
		(stroke
			(width 0.072898)
			(type default)
		)
		(layer "B.Cu")
	)
	(gr_line
		(start 167.293798 -27.351482)
		(end 167.603678 -27.661362)
		(stroke
			(width 0.072898)
			(type default)
		)
		(layer "B.Cu")
	)
	(gr_line
		(start 167.293798 -27.139646)
		(end 167.293798 -27.351482)
		(stroke
			(width 0.072898)
			(type default)
		)
		(layer "B.Cu")
	)
	(gr_line
		(start 167.313102 -18.807684)
		(end 167.325294 -18.78965)
		(stroke
			(width 0.072898)
			(type default)
		)
		(layer "B.Cu")
	)
	(gr_line
		(start 167.32123 -17.75333)
		(end 167.68445 -17.508474)
		(stroke
			(width 0.072898)
			(type default)
		)
		(layer "B.Cu")
	)
	(gr_line
		(start 167.325294 -18.78965)
		(end 167.343582 -18.777458)
		(stroke
			(width 0.072898)
			(type default)
		)
		(layer "B.Cu")
	)
	(gr_line
		(start 167.37203 -26.085038)
		(end 167.37203 -26.200608)
		(stroke
			(width 0.072898)
			(type default)
		)
		(layer "B.Cu")
	)
	(gr_line
		(start 167.37203 -24.903938)
		(end 167.37203 -25.019508)
		(stroke
			(width 0.072898)
			(type default)
		)
		(layer "B.Cu")
	)
	(gr_line
		(start 167.37203 -23.722838)
		(end 167.37203 -23.838408)
		(stroke
			(width 0.072898)
			(type default)
		)
		(layer "B.Cu")
	)
	(gr_line
		(start 167.37203 -22.541738)
		(end 167.37203 -22.657308)
		(stroke
			(width 0.072898)
			(type default)
		)
		(layer "B.Cu")
	)
	(gr_line
		(start 167.590978 -28.654502)
		(end 167.667432 -28.730956)
		(stroke
			(width 0.072898)
			(type default)
		)
		(layer "B.Cu")
	)
	(gr_line
		(start 167.590978 -28.214574)
		(end 167.88765 -28.511246)
		(stroke
			(width 0.072898)
			(type default)
		)
		(layer "B.Cu")
	)
	(gr_line
		(start 167.603678 -27.661362)
		(end 167.815514 -27.661362)
		(stroke
			(width 0.072898)
			(type default)
		)
		(layer "B.Cu")
	)
	(gr_line
		(start 167.667432 -28.730956)
		(end 167.684196 -28.74772)
		(stroke
			(width 0.047498)
			(type default)
		)
		(layer "B.Cu")
	)
	(gr_line
		(start 167.684196 -28.74772)
		(end 167.71112 -28.74772)
		(stroke
			(width 0.047498)
			(type default)
		)
		(layer "B.Cu")
	)
	(gr_line
		(start 167.68445 -17.508474)
		(end 167.72509 -17.300194)
		(stroke
			(width 0.072898)
			(type default)
		)
		(layer "B.Cu")
	)
	(gr_line
		(start 167.71366 -28.74772)
		(end 167.73017 -28.74772)
		(stroke
			(width 0.047498)
			(type default)
		)
		(layer "B.Cu")
	)
	(gr_line
		(start 167.73017 -28.74772)
		(end 167.774112 -28.74772)
		(stroke
			(width 0.047498)
			(type default)
		)
		(layer "B.Cu")
	)
	(gr_line
		(start 167.735758 -27.137868)
		(end 167.817292 -27.219402)
		(stroke
			(width 0.072898)
			(type default)
		)
		(layer "B.Cu")
	)
	(gr_line
		(start 167.799766 -30.39999)
		(end 167.924734 -30.27426)
		(stroke
			(width 0.047498)
			(type default)
		)
		(layer "B.Cu")
	)
	(gr_line
		(start 167.80002 -31.199836)
		(end 168.20007 -30.54858)
		(stroke
			(width 0.047498)
			(type default)
		)
		(layer "B.Cu")
	)
	(gr_line
		(start 167.870886 -18.421604)
		(end 168.425368 -18.047716)
		(stroke
			(width 0.072898)
			(type default)
		)
		(layer "B.Cu")
	)
	(gr_line
		(start 167.88765 -28.511246)
		(end 167.904414 -28.52801)
		(stroke
			(width 0.047498)
			(type default)
		)
		(layer "B.Cu")
	)
	(gr_line
		(start 167.90416 -28.57373)
		(end 167.90416 -28.61691)
		(stroke
			(width 0.047498)
			(type default)
		)
		(layer "B.Cu")
	)
	(gr_line
		(start 167.90416 -28.57373)
		(end 167.904414 -28.52801)
		(stroke
			(width 0.047498)
			(type default)
		)
		(layer "B.Cu")
	)
	(gr_line
		(start 167.924734 -30.27426)
		(end 167.952166 -30.247082)
		(stroke
			(width 0.047498)
			(type default)
		)
		(layer "B.Cu")
	)
	(gr_line
		(start 167.946578 -16.772128)
		(end 168.499028 -16.39951)
		(stroke
			(width 0.072898)
			(type default)
		)
		(layer "B.Cu")
	)
	(gr_line
		(start 167.952166 -30.247082)
		(end 167.957246 -30.242256)
		(stroke
			(width 0.047498)
			(type default)
		)
		(layer "B.Cu")
	)
	(gr_line
		(start 168.016428 -18.70202)
		(end 168.224708 -18.742406)
		(stroke
			(width 0.072898)
			(type default)
		)
		(layer "B.Cu")
	)
	(gr_line
		(start 168.09212 -17.052544)
		(end 168.3004 -17.09293)
		(stroke
			(width 0.072898)
			(type default)
		)
		(layer "B.Cu")
	)
	(gr_line
		(start 168.1734 -28.015692)
		(end 168.186862 -28.029154)
		(stroke
			(width 0.047498)
			(type default)
		)
		(layer "B.Cu")
	)
	(gr_line
		(start 168.186862 -28.029154)
		(end 168.190164 -28.032456)
		(stroke
			(width 0.047498)
			(type default)
		)
		(layer "B.Cu")
	)
	(gr_line
		(start 168.190164 -28.032456)
		(end 168.210992 -28.032456)
		(stroke
			(width 0.047498)
			(type default)
		)
		(layer "B.Cu")
	)
	(gr_line
		(start 168.199816 -30.418278)
		(end 168.20007 -30.54858)
		(stroke
			(width 0.047498)
			(type default)
		)
		(layer "B.Cu")
	)
	(gr_line
		(start 168.199816 -30.371542)
		(end 168.199816 -30.418278)
		(stroke
			(width 0.047498)
			(type default)
		)
		(layer "B.Cu")
	)
	(gr_line
		(start 168.213532 -28.032456)
		(end 168.302432 -28.032456)
		(stroke
			(width 0.047498)
			(type default)
		)
		(layer "B.Cu")
	)
	(gr_line
		(start 168.224708 -18.742406)
		(end 168.588182 -18.49755)
		(stroke
			(width 0.072898)
			(type default)
		)
		(layer "B.Cu")
	)
	(gr_line
		(start 168.3004 -17.09293)
		(end 168.66362 -16.84782)
		(stroke
			(width 0.072898)
			(type default)
		)
		(layer "B.Cu")
	)
	(gr_line
		(start 168.302432 -28.032456)
		(end 168.331388 -28.061412)
		(stroke
			(width 0.047498)
			(type default)
		)
		(layer "B.Cu")
	)
	(gr_line
		(start 168.380918 -27.783028)
		(end 168.397682 -27.799792)
		(stroke
			(width 0.047498)
			(type default)
		)
		(layer "B.Cu")
	)
	(gr_line
		(start 168.397682 -27.848306)
		(end 168.397682 -27.867102)
		(stroke
			(width 0.047498)
			(type default)
		)
		(layer "B.Cu")
	)
	(gr_line
		(start 168.397682 -27.81808)
		(end 168.397682 -27.845766)
		(stroke
			(width 0.047498)
			(type default)
		)
		(layer "B.Cu")
	)
	(gr_line
		(start 168.397682 -27.799792)
		(end 168.397682 -27.81808)
		(stroke
			(width 0.047498)
			(type default)
		)
		(layer "B.Cu")
	)
	(gr_line
		(start 168.588182 -18.49755)
		(end 168.628822 -18.289016)
		(stroke
			(width 0.072898)
			(type default)
		)
		(layer "B.Cu")
	)
	(gr_line
		(start 168.599866 -31.199836)
		(end 168.9862 -30.570932)
		(stroke
			(width 0.047498)
			(type default)
		)
		(layer "B.Cu")
	)
	(gr_line
		(start 168.599866 -30.39999)
		(end 168.79951 -30.200346)
		(stroke
			(width 0.047498)
			(type default)
		)
		(layer "B.Cu")
	)
	(gr_line
		(start 168.66362 -16.84782)
		(end 168.70426 -16.63954)
		(stroke
			(width 0.072898)
			(type default)
		)
		(layer "B.Cu")
	)
	(gr_line
		(start 168.849802 -17.761458)
		(end 169.40276 -17.388586)
		(stroke
			(width 0.072898)
			(type default)
		)
		(layer "B.Cu")
	)
	(gr_line
		(start 168.924732 -16.112236)
		(end 169.477944 -15.73911)
		(stroke
			(width 0.072898)
			(type default)
		)
		(layer "B.Cu")
	)
	(gr_line
		(start 168.94302 -27.221688)
		(end 169.09288 -27.371548)
		(stroke
			(width 0.072898)
			(type default)
		)
		(layer "B.Cu")
	)
	(gr_line
		(start 168.94302 -26.783538)
		(end 168.94302 -27.221688)
		(stroke
			(width 0.072898)
			(type default)
		)
		(layer "B.Cu")
	)
	(gr_line
		(start 168.94302 -26.783538)
		(end 169.09288 -26.633678)
		(stroke
			(width 0.072898)
			(type default)
		)
		(layer "B.Cu")
	)
	(gr_line
		(start 168.94302 -26.040588)
		(end 169.09288 -26.190448)
		(stroke
			(width 0.072898)
			(type default)
		)
		(layer "B.Cu")
	)
	(gr_line
		(start 168.94302 -25.602438)
		(end 168.94302 -26.040588)
		(stroke
			(width 0.072898)
			(type default)
		)
		(layer "B.Cu")
	)
	(gr_line
		(start 168.94302 -25.602438)
		(end 169.09288 -25.452578)
		(stroke
			(width 0.072898)
			(type default)
		)
		(layer "B.Cu")
	)
	(gr_line
		(start 168.94302 -24.859488)
		(end 169.09288 -25.009348)
		(stroke
			(width 0.072898)
			(type default)
		)
		(layer "B.Cu")
	)
	(gr_line
		(start 168.94302 -24.421338)
		(end 168.94302 -24.859488)
		(stroke
			(width 0.072898)
			(type default)
		)
		(layer "B.Cu")
	)
	(gr_line
		(start 168.94302 -24.421338)
		(end 169.09288 -24.271478)
		(stroke
			(width 0.072898)
			(type default)
		)
		(layer "B.Cu")
	)
	(gr_line
		(start 168.94302 -23.678388)
		(end 169.09288 -23.828248)
		(stroke
			(width 0.072898)
			(type default)
		)
		(layer "B.Cu")
	)
	(gr_line
		(start 168.94302 -23.240238)
		(end 168.94302 -23.678388)
		(stroke
			(width 0.072898)
			(type default)
		)
		(layer "B.Cu")
	)
	(gr_line
		(start 168.94302 -23.240238)
		(end 169.09288 -23.090378)
		(stroke
			(width 0.072898)
			(type default)
		)
		(layer "B.Cu")
	)
	(gr_line
		(start 168.94302 -22.497288)
		(end 169.09288 -22.647148)
		(stroke
			(width 0.072898)
			(type default)
		)
		(layer "B.Cu")
	)
	(gr_line
		(start 168.94302 -22.059138)
		(end 168.94302 -22.497288)
		(stroke
			(width 0.072898)
			(type default)
		)
		(layer "B.Cu")
	)
	(gr_line
		(start 168.94302 -22.059138)
		(end 169.09288 -21.909278)
		(stroke
			(width 0.072898)
			(type default)
		)
		(layer "B.Cu")
	)
	(gr_line
		(start 168.953434 -28.422854)
		(end 168.9862 -28.45562)
		(stroke
			(width 0.047498)
			(type default)
		)
		(layer "B.Cu")
	)
	(gr_line
		(start 168.98239 -21.286216)
		(end 169.046906 -21.350732)
		(stroke
			(width 0.072898)
			(type default)
		)
		(layer "B.Cu")
	)
	(gr_line
		(start 168.98239 -20.727416)
		(end 169.049446 -20.66036)
		(stroke
			(width 0.072898)
			(type default)
		)
		(layer "B.Cu")
	)
	(gr_line
		(start 168.9862 -30.384496)
		(end 168.9862 -30.570932)
		(stroke
			(width 0.047498)
			(type default)
		)
		(layer "B.Cu")
	)
	(gr_line
		(start 168.995852 -18.04162)
		(end 169.204132 -18.08226)
		(stroke
			(width 0.072898)
			(type default)
		)
		(layer "B.Cu")
	)
	(gr_line
		(start 169.07129 -16.39189)
		(end 169.27957 -16.43253)
		(stroke
			(width 0.072898)
			(type default)
		)
		(layer "B.Cu")
	)
	(gr_line
		(start 169.122852 -20.140168)
		(end 169.126154 -20.130008)
		(stroke
			(width 0.072898)
			(type default)
		)
		(layer "B.Cu")
	)
	(gr_line
		(start 169.204132 -18.08226)
		(end 169.567352 -17.83715)
		(stroke
			(width 0.072898)
			(type default)
		)
		(layer "B.Cu")
	)
	(gr_line
		(start 169.246804 -28.2829)
		(end 169.556684 -28.59278)
		(stroke
			(width 0.072898)
			(type default)
		)
		(layer "B.Cu")
	)
	(gr_line
		(start 169.246804 -27.996896)
		(end 169.246804 -28.2829)
		(stroke
			(width 0.072898)
			(type default)
		)
		(layer "B.Cu")
	)
	(gr_line
		(start 169.246804 -27.963622)
		(end 169.246804 -27.994356)
		(stroke
			(width 0.072898)
			(type default)
		)
		(layer "B.Cu")
	)
	(gr_line
		(start 169.27957 -16.43253)
		(end 169.64279 -16.18742)
		(stroke
			(width 0.072898)
			(type default)
		)
		(layer "B.Cu")
	)
	(gr_line
		(start 169.40657 -27.652472)
		(end 169.40657 -27.683206)
		(stroke
			(width 0.072898)
			(type default)
		)
		(layer "B.Cu")
	)
	(gr_line
		(start 169.40657 -26.944828)
		(end 169.40657 -27.060398)
		(stroke
			(width 0.072898)
			(type default)
		)
		(layer "B.Cu")
	)
	(gr_line
		(start 169.40657 -25.763728)
		(end 169.40657 -25.879298)
		(stroke
			(width 0.072898)
			(type default)
		)
		(layer "B.Cu")
	)
	(gr_line
		(start 169.40657 -24.582628)
		(end 169.40657 -24.698198)
		(stroke
			(width 0.072898)
			(type default)
		)
		(layer "B.Cu")
	)
	(gr_line
		(start 169.40657 -23.401528)
		(end 169.40657 -23.517098)
		(stroke
			(width 0.072898)
			(type default)
		)
		(layer "B.Cu")
	)
	(gr_line
		(start 169.40657 -22.220428)
		(end 169.40657 -22.335998)
		(stroke
			(width 0.072898)
			(type default)
		)
		(layer "B.Cu")
	)
	(gr_line
		(start 169.483278 -19.057366)
		(end 169.502582 -18.9992)
		(stroke
			(width 0.072898)
			(type default)
		)
		(layer "B.Cu")
	)
	(gr_line
		(start 169.490644 -21.350732)
		(end 169.5577 -21.283676)
		(stroke
			(width 0.072898)
			(type default)
		)
		(layer "B.Cu")
	)
	(gr_line
		(start 169.493184 -20.66036)
		(end 169.5577 -20.724876)
		(stroke
			(width 0.072898)
			(type default)
		)
		(layer "B.Cu")
	)
	(gr_line
		(start 169.502582 -18.9992)
		(end 169.553636 -18.962878)
		(stroke
			(width 0.072898)
			(type default)
		)
		(layer "B.Cu")
	)
	(gr_line
		(start 169.556684 -28.59278)
		(end 169.872406 -28.59278)
		(stroke
			(width 0.072898)
			(type default)
		)
		(layer "B.Cu")
	)
	(gr_line
		(start 169.567352 -17.83715)
		(end 169.607738 -17.62887)
		(stroke
			(width 0.072898)
			(type default)
		)
		(layer "B.Cu")
	)
	(gr_line
		(start 169.64279 -16.18742)
		(end 169.68343 -15.97914)
		(stroke
			(width 0.072898)
			(type default)
		)
		(layer "B.Cu")
	)
	(gr_line
		(start 169.688764 -27.9654)
		(end 169.929048 -28.205684)
		(stroke
			(width 0.072898)
			(type default)
		)
		(layer "B.Cu")
	)
	(gr_line
		(start 169.82821 -17.10182)
		(end 170.3832 -16.727678)
		(stroke
			(width 0.072898)
			(type default)
		)
		(layer "B.Cu")
	)
	(gr_line
		(start 169.903394 -15.45209)
		(end 170.457876 -15.078202)
		(stroke
			(width 0.072898)
			(type default)
		)
		(layer "B.Cu")
	)
	(gr_line
		(start 169.915078 -28.63215)
		(end 169.930572 -28.647644)
		(stroke
			(width 0.04445)
			(type default)
		)
		(layer "B.Cu")
	)
	(gr_line
		(start 169.975022 -17.38122)
		(end 170.183556 -17.42186)
		(stroke
			(width 0.072898)
			(type default)
		)
		(layer "B.Cu")
	)
	(gr_line
		(start 170.034458 -28.979622)
		(end 170.05808 -29.003244)
		(stroke
			(width 0.047498)
			(type default)
		)
		(layer "B.Cu")
	)
	(gr_line
		(start 170.034458 -28.956)
		(end 170.034458 -28.979622)
		(stroke
			(width 0.047498)
			(type default)
		)
		(layer "B.Cu")
	)
	(gr_line
		(start 170.049952 -15.73149)
		(end 170.25874 -15.771876)
		(stroke
			(width 0.072898)
			(type default)
		)
		(layer "B.Cu")
	)
	(gr_line
		(start 170.120564 -29.065728)
		(end 170.120564 -29.20365)
		(stroke
			(width 0.047498)
			(type default)
		)
		(layer "B.Cu")
	)
	(gr_line
		(start 170.183556 -17.42186)
		(end 170.546776 -17.177004)
		(stroke
			(width 0.072898)
			(type default)
		)
		(layer "B.Cu")
	)
	(gr_line
		(start 170.199812 -30.39999)
		(end 170.413172 -30.18663)
		(stroke
			(width 0.047498)
			(type default)
		)
		(layer "B.Cu")
	)
	(gr_line
		(start 170.200066 -31.20009)
		(end 170.599862 -30.541722)
		(stroke
			(width 0.047498)
			(type default)
		)
		(layer "B.Cu")
	)
	(gr_line
		(start 170.25874 -15.771876)
		(end 170.62196 -15.52702)
		(stroke
			(width 0.072898)
			(type default)
		)
		(layer "B.Cu")
	)
	(gr_line
		(start 170.321986 -29.003244)
		(end 170.345608 -28.979622)
		(stroke
			(width 0.047498)
			(type default)
		)
		(layer "B.Cu")
	)
	(gr_line
		(start 170.345608 -28.956)
		(end 170.345608 -28.979622)
		(stroke
			(width 0.047498)
			(type default)
		)
		(layer "B.Cu")
	)
	(gr_line
		(start 170.546776 -17.177004)
		(end 170.587416 -16.96847)
		(stroke
			(width 0.072898)
			(type default)
		)
		(layer "B.Cu")
	)
	(gr_line
		(start 170.599862 -30.37078)
		(end 170.599862 -30.541722)
		(stroke
			(width 0.047498)
			(type default)
		)
		(layer "B.Cu")
	)
	(gr_line
		(start 170.62196 -15.52702)
		(end 170.6626 -15.318486)
		(stroke
			(width 0.072898)
			(type default)
		)
		(layer "B.Cu")
	)
	(gr_line
		(start 170.923204 -21.308314)
		(end 171.031408 -21.416518)
		(stroke
			(width 0.072898)
			(type default)
		)
		(layer "B.Cu")
	)
	(gr_line
		(start 170.923204 -21.16582)
		(end 170.923204 -21.308314)
		(stroke
			(width 0.072898)
			(type default)
		)
		(layer "B.Cu")
	)
	(gr_line
		(start 170.923204 -20.60702)
		(end 171.006262 -20.523962)
		(stroke
			(width 0.072898)
			(type default)
		)
		(layer "B.Cu")
	)
	(gr_line
		(start 170.937936 -17.978882)
		(end 171.47794 -17.595088)
		(stroke
			(width 0.072898)
			(type default)
		)
		(layer "B.Cu")
	)
	(gr_line
		(start 170.941492 -28.453842)
		(end 171.124118 -28.636468)
		(stroke
			(width 0.072898)
			(type default)
		)
		(layer "B.Cu")
	)
	(gr_line
		(start 170.941492 -28.015692)
		(end 170.941492 -28.453842)
		(stroke
			(width 0.072898)
			(type default)
		)
		(layer "B.Cu")
	)
	(gr_line
		(start 170.941492 -28.015692)
		(end 171.124118 -27.833066)
		(stroke
			(width 0.072898)
			(type default)
		)
		(layer "B.Cu")
	)
	(gr_line
		(start 170.974258 -27.239976)
		(end 171.124118 -27.389836)
		(stroke
			(width 0.072898)
			(type default)
		)
		(layer "B.Cu")
	)
	(gr_line
		(start 170.974258 -26.801826)
		(end 170.974258 -27.239976)
		(stroke
			(width 0.072898)
			(type default)
		)
		(layer "B.Cu")
	)
	(gr_line
		(start 170.974258 -26.801826)
		(end 171.124118 -26.651966)
		(stroke
			(width 0.072898)
			(type default)
		)
		(layer "B.Cu")
	)
	(gr_line
		(start 170.974258 -26.058876)
		(end 171.124118 -26.208736)
		(stroke
			(width 0.072898)
			(type default)
		)
		(layer "B.Cu")
	)
	(gr_line
		(start 170.974258 -25.620726)
		(end 170.974258 -26.058876)
		(stroke
			(width 0.072898)
			(type default)
		)
		(layer "B.Cu")
	)
	(gr_line
		(start 170.974258 -25.620726)
		(end 171.124118 -25.470866)
		(stroke
			(width 0.072898)
			(type default)
		)
		(layer "B.Cu")
	)
	(gr_line
		(start 170.974258 -24.877776)
		(end 171.124118 -25.027636)
		(stroke
			(width 0.072898)
			(type default)
		)
		(layer "B.Cu")
	)
	(gr_line
		(start 170.974258 -24.439626)
		(end 170.974258 -24.877776)
		(stroke
			(width 0.072898)
			(type default)
		)
		(layer "B.Cu")
	)
	(gr_line
		(start 170.974258 -24.439626)
		(end 171.124118 -24.289766)
		(stroke
			(width 0.072898)
			(type default)
		)
		(layer "B.Cu")
	)
	(gr_line
		(start 170.974258 -23.696676)
		(end 171.124118 -23.846536)
		(stroke
			(width 0.072898)
			(type default)
		)
		(layer "B.Cu")
	)
	(gr_line
		(start 170.974258 -23.258526)
		(end 170.974258 -23.696676)
		(stroke
			(width 0.072898)
			(type default)
		)
		(layer "B.Cu")
	)
	(gr_line
		(start 170.974258 -23.258526)
		(end 171.124118 -23.108666)
		(stroke
			(width 0.072898)
			(type default)
		)
		(layer "B.Cu")
	)
	(gr_line
		(start 170.974258 -22.515576)
		(end 171.124118 -22.665436)
		(stroke
			(width 0.072898)
			(type default)
		)
		(layer "B.Cu")
	)
	(gr_line
		(start 170.974258 -22.077426)
		(end 170.974258 -22.515576)
		(stroke
			(width 0.072898)
			(type default)
		)
		(layer "B.Cu")
	)
	(gr_line
		(start 170.974258 -22.077426)
		(end 171.124118 -21.927566)
		(stroke
			(width 0.072898)
			(type default)
		)
		(layer "B.Cu")
	)
	(gr_line
		(start 170.999912 -30.39999)
		(end 171.173394 -30.226508)
		(stroke
			(width 0.047498)
			(type default)
		)
		(layer "B.Cu")
	)
	(gr_line
		(start 171.000166 -31.20009)
		(end 171.390564 -30.567884)
		(stroke
			(width 0.047498)
			(type default)
		)
		(layer "B.Cu")
	)
	(gr_line
		(start 171.080938 -20.182078)
		(end 171.093384 -20.155408)
		(stroke
			(width 0.072898)
			(type default)
		)
		(layer "B.Cu")
	)
	(gr_line
		(start 171.088812 -18.25625)
		(end 171.297854 -18.291556)
		(stroke
			(width 0.072898)
			(type default)
		)
		(layer "B.Cu")
	)
	(gr_line
		(start 171.126658 -29.035248)
		(end 171.141136 -29.049726)
		(stroke
			(width 0.047498)
			(type default)
		)
		(layer "B.Cu")
	)
	(gr_line
		(start 171.126658 -29.011626)
		(end 171.126658 -29.035248)
		(stroke
			(width 0.047498)
			(type default)
		)
		(layer "B.Cu")
	)
	(gr_line
		(start 171.142914 -29.051504)
		(end 171.168822 -29.077412)
		(stroke
			(width 0.047498)
			(type default)
		)
		(layer "B.Cu")
	)
	(gr_line
		(start 171.168822 -29.077412)
		(end 171.190158 -29.098748)
		(stroke
			(width 0.047498)
			(type default)
		)
		(layer "B.Cu")
	)
	(gr_line
		(start 171.297854 -18.291556)
		(end 171.654978 -18.03781)
		(stroke
			(width 0.072898)
			(type default)
		)
		(layer "B.Cu")
	)
	(gr_line
		(start 171.374308 -29.098748)
		(end 171.395644 -29.077412)
		(stroke
			(width 0.047498)
			(type default)
		)
		(layer "B.Cu")
	)
	(gr_line
		(start 171.390564 -30.179518)
		(end 171.390564 -30.567884)
		(stroke
			(width 0.047498)
			(type default)
		)
		(layer "B.Cu")
	)
	(gr_line
		(start 171.395644 -29.077412)
		(end 171.421552 -29.051504)
		(stroke
			(width 0.047498)
			(type default)
		)
		(layer "B.Cu")
	)
	(gr_line
		(start 171.42333 -29.049726)
		(end 171.437808 -29.035248)
		(stroke
			(width 0.047498)
			(type default)
		)
		(layer "B.Cu")
	)
	(gr_line
		(start 171.437808 -29.011626)
		(end 171.437808 -29.035248)
		(stroke
			(width 0.047498)
			(type default)
		)
		(layer "B.Cu")
	)
	(gr_line
		(start 171.437808 -28.144216)
		(end 171.437808 -28.325318)
		(stroke
			(width 0.072898)
			(type default)
		)
		(layer "B.Cu")
	)
	(gr_line
		(start 171.437808 -26.963116)
		(end 171.437808 -27.078686)
		(stroke
			(width 0.072898)
			(type default)
		)
		(layer "B.Cu")
	)
	(gr_line
		(start 171.437808 -25.782016)
		(end 171.437808 -25.897586)
		(stroke
			(width 0.072898)
			(type default)
		)
		(layer "B.Cu")
	)
	(gr_line
		(start 171.437808 -24.600916)
		(end 171.437808 -24.716486)
		(stroke
			(width 0.072898)
			(type default)
		)
		(layer "B.Cu")
	)
	(gr_line
		(start 171.437808 -23.419816)
		(end 171.437808 -23.535386)
		(stroke
			(width 0.072898)
			(type default)
		)
		(layer "B.Cu")
	)
	(gr_line
		(start 171.437808 -22.238716)
		(end 171.437808 -22.354286)
		(stroke
			(width 0.072898)
			(type default)
		)
		(layer "B.Cu")
	)
	(gr_line
		(start 171.449746 -20.523962)
		(end 171.532804 -20.60702)
		(stroke
			(width 0.072898)
			(type default)
		)
		(layer "B.Cu")
	)
	(gr_line
		(start 171.474892 -21.416518)
		(end 171.532804 -21.358606)
		(stroke
			(width 0.072898)
			(type default)
		)
		(layer "B.Cu")
	)
	(gr_line
		(start 171.515024 -19.256248)
		(end 171.534582 -19.214084)
		(stroke
			(width 0.072898)
			(type default)
		)
		(layer "B.Cu")
	)
	(gr_line
		(start 171.532804 -21.16582)
		(end 171.532804 -21.358606)
		(stroke
			(width 0.072898)
			(type default)
		)
		(layer "B.Cu")
	)
	(gr_line
		(start 171.534582 -19.214084)
		(end 171.573952 -19.187668)
		(stroke
			(width 0.072898)
			(type default)
		)
		(layer "B.Cu")
	)
	(gr_line
		(start 171.654978 -18.03781)
		(end 171.690538 -17.828768)
		(stroke
			(width 0.072898)
			(type default)
		)
		(layer "B.Cu")
	)
	(gr_line
		(start 171.900088 -17.29486)
		(end 172.440346 -16.910812)
		(stroke
			(width 0.072898)
			(type default)
		)
		(layer "B.Cu")
	)
	(gr_line
		(start 172.051472 -17.571974)
		(end 172.260514 -17.60728)
		(stroke
			(width 0.072898)
			(type default)
		)
		(layer "B.Cu")
	)
	(gr_line
		(start 172.260514 -17.60728)
		(end 172.617638 -17.353534)
		(stroke
			(width 0.072898)
			(type default)
		)
		(layer "B.Cu")
	)
	(gr_line
		(start 172.469556 -16.889984)
		(end 172.475906 -16.885412)
		(stroke
			(width 0.072898)
			(type default)
		)
		(layer "B.Cu")
	)
	(gr_line
		(start 172.599858 -30.39999)
		(end 172.751496 -30.248352)
		(stroke
			(width 0.047498)
			(type default)
		)
		(layer "B.Cu")
	)
	(gr_line
		(start 172.600112 -31.20009)
		(end 172.999908 -30.52191)
		(stroke
			(width 0.047498)
			(type default)
		)
		(layer "B.Cu")
	)
	(gr_line
		(start 172.617638 -17.353534)
		(end 172.652944 -17.144492)
		(stroke
			(width 0.072898)
			(type default)
		)
		(layer "B.Cu")
	)
	(gr_line
		(start 172.655484 -15.19555)
		(end 172.677074 -15.181072)
		(stroke
			(width 0.072898)
			(type default)
		)
		(layer "B.Cu")
	)
	(gr_line
		(start 172.677074 -15.181072)
		(end 172.701712 -15.1765)
		(stroke
			(width 0.072898)
			(type default)
		)
		(layer "B.Cu")
	)
	(gr_line
		(start 172.74413 -29.741622)
		(end 172.767752 -29.765244)
		(stroke
			(width 0.047498)
			(type default)
		)
		(layer "B.Cu")
	)
	(gr_line
		(start 172.74413 -29.718)
		(end 172.74413 -29.741622)
		(stroke
			(width 0.047498)
			(type default)
		)
		(layer "B.Cu")
	)
	(gr_line
		(start 172.999908 -30.234382)
		(end 172.999908 -30.52191)
		(stroke
			(width 0.047498)
			(type default)
		)
		(layer "B.Cu")
	)
	(gr_line
		(start 172.999908 -30.234382)
		(end 173.00067 -30.23362)
		(stroke
			(width 0.047498)
			(type default)
		)
		(layer "B.Cu")
	)
	(gr_line
		(start 173.031658 -29.765244)
		(end 173.05528 -29.741622)
		(stroke
			(width 0.047498)
			(type default)
		)
		(layer "B.Cu")
	)
	(gr_line
		(start 173.039532 -27.419554)
		(end 173.202092 -27.582114)
		(stroke
			(width 0.072898)
			(type default)
		)
		(layer "B.Cu")
	)
	(gr_line
		(start 173.039532 -26.981404)
		(end 173.039532 -27.419554)
		(stroke
			(width 0.072898)
			(type default)
		)
		(layer "B.Cu")
	)
	(gr_line
		(start 173.039532 -26.981404)
		(end 173.202092 -26.818844)
		(stroke
			(width 0.072898)
			(type default)
		)
		(layer "B.Cu")
	)
	(gr_line
		(start 173.039532 -26.213054)
		(end 173.202092 -26.375614)
		(stroke
			(width 0.072898)
			(type default)
		)
		(layer "B.Cu")
	)
	(gr_line
		(start 173.039532 -25.774904)
		(end 173.039532 -26.213054)
		(stroke
			(width 0.072898)
			(type default)
		)
		(layer "B.Cu")
	)
	(gr_line
		(start 173.039532 -25.774904)
		(end 173.202092 -25.612344)
		(stroke
			(width 0.072898)
			(type default)
		)
		(layer "B.Cu")
	)
	(gr_line
		(start 173.039532 -25.006554)
		(end 173.202092 -25.169114)
		(stroke
			(width 0.072898)
			(type default)
		)
		(layer "B.Cu")
	)
	(gr_line
		(start 173.039532 -24.568404)
		(end 173.039532 -25.006554)
		(stroke
			(width 0.072898)
			(type default)
		)
		(layer "B.Cu")
	)
	(gr_line
		(start 173.039532 -24.568404)
		(end 173.202092 -24.405844)
		(stroke
			(width 0.072898)
			(type default)
		)
		(layer "B.Cu")
	)
	(gr_line
		(start 173.039532 -23.800054)
		(end 173.202092 -23.962614)
		(stroke
			(width 0.072898)
			(type default)
		)
		(layer "B.Cu")
	)
	(gr_line
		(start 173.039532 -23.361904)
		(end 173.039532 -23.800054)
		(stroke
			(width 0.072898)
			(type default)
		)
		(layer "B.Cu")
	)
	(gr_line
		(start 173.039532 -23.361904)
		(end 173.202092 -23.199344)
		(stroke
			(width 0.072898)
			(type default)
		)
		(layer "B.Cu")
	)
	(gr_line
		(start 173.039532 -22.593554)
		(end 173.202092 -22.756114)
		(stroke
			(width 0.072898)
			(type default)
		)
		(layer "B.Cu")
	)
	(gr_line
		(start 173.039532 -22.155404)
		(end 173.039532 -22.593554)
		(stroke
			(width 0.072898)
			(type default)
		)
		(layer "B.Cu")
	)
	(gr_line
		(start 173.039532 -22.155404)
		(end 173.202092 -21.992844)
		(stroke
			(width 0.072898)
			(type default)
		)
		(layer "B.Cu")
	)
	(gr_line
		(start 173.045882 -21.298154)
		(end 173.132242 -21.384514)
		(stroke
			(width 0.072898)
			(type default)
		)
		(layer "B.Cu")
	)
	(gr_line
		(start 173.045882 -21.165566)
		(end 173.045882 -21.298154)
		(stroke
			(width 0.072898)
			(type default)
		)
		(layer "B.Cu")
	)
	(gr_line
		(start 173.045882 -20.606766)
		(end 173.113446 -20.539202)
		(stroke
			(width 0.072898)
			(type default)
		)
		(layer "B.Cu")
	)
	(gr_line
		(start 173.05528 -29.718)
		(end 173.05528 -29.741622)
		(stroke
			(width 0.047498)
			(type default)
		)
		(layer "B.Cu")
	)
	(gr_line
		(start 173.17085 -19.871182)
		(end 173.20514 -19.822922)
		(stroke
			(width 0.072898)
			(type default)
		)
		(layer "B.Cu")
	)
	(gr_line
		(start 173.32579 -16.281146)
		(end 173.348396 -16.265144)
		(stroke
			(width 0.072898)
			(type default)
		)
		(layer "B.Cu")
	)
	(gr_line
		(start 173.348396 -16.265144)
		(end 173.375574 -16.25981)
		(stroke
			(width 0.072898)
			(type default)
		)
		(layer "B.Cu")
	)
	(gr_line
		(start 173.399958 -30.39999)
		(end 173.513242 -30.286706)
		(stroke
			(width 0.047498)
			(type default)
		)
		(layer "B.Cu")
	)
	(gr_line
		(start 173.400212 -31.20009)
		(end 173.809914 -30.505146)
		(stroke
			(width 0.047498)
			(type default)
		)
		(layer "B.Cu")
	)
	(gr_line
		(start 173.449742 -29.487622)
		(end 173.473364 -29.511244)
		(stroke
			(width 0.047498)
			(type default)
		)
		(layer "B.Cu")
	)
	(gr_line
		(start 173.449742 -29.464)
		(end 173.449742 -29.487622)
		(stroke
			(width 0.047498)
			(type default)
		)
		(layer "B.Cu")
	)
	(gr_line
		(start 173.50994 -28.887674)
		(end 173.50994 -29.009594)
		(stroke
			(width 0.072898)
			(type default)
		)
		(layer "B.Cu")
	)
	(gr_line
		(start 173.50994 -28.793948)
		(end 173.50994 -28.885134)
		(stroke
			(width 0.072898)
			(type default)
		)
		(layer "B.Cu")
	)
	(gr_line
		(start 173.50994 -28.793948)
		(end 173.81982 -28.484068)
		(stroke
			(width 0.072898)
			(type default)
		)
		(layer "B.Cu")
	)
	(gr_line
		(start 173.513242 -30.270704)
		(end 173.513242 -30.286706)
		(stroke
			(width 0.047498)
			(type default)
		)
		(layer "B.Cu")
	)
	(gr_line
		(start 173.515782 -27.129994)
		(end 173.515782 -27.270964)
		(stroke
			(width 0.072898)
			(type default)
		)
		(layer "B.Cu")
	)
	(gr_line
		(start 173.515782 -25.923494)
		(end 173.515782 -26.064464)
		(stroke
			(width 0.072898)
			(type default)
		)
		(layer "B.Cu")
	)
	(gr_line
		(start 173.515782 -24.716994)
		(end 173.515782 -24.857964)
		(stroke
			(width 0.072898)
			(type default)
		)
		(layer "B.Cu")
	)
	(gr_line
		(start 173.515782 -23.510494)
		(end 173.515782 -23.651464)
		(stroke
			(width 0.072898)
			(type default)
		)
		(layer "B.Cu")
	)
	(gr_line
		(start 173.515782 -22.303994)
		(end 173.515782 -22.444964)
		(stroke
			(width 0.072898)
			(type default)
		)
		(layer "B.Cu")
	)
	(gr_line
		(start 173.557184 -20.539202)
		(end 173.625002 -20.60702)
		(stroke
			(width 0.072898)
			(type default)
		)
		(layer "B.Cu")
	)
	(gr_line
		(start 173.575726 -21.384514)
		(end 173.625002 -21.335238)
		(stroke
			(width 0.072898)
			(type default)
		)
		(layer "B.Cu")
	)
	(gr_line
		(start 173.611286 -19.247866)
		(end 173.659292 -19.180048)
		(stroke
			(width 0.072898)
			(type default)
		)
		(layer "B.Cu")
	)
	(gr_line
		(start 173.625002 -21.16582)
		(end 173.625002 -21.335238)
		(stroke
			(width 0.072898)
			(type default)
		)
		(layer "B.Cu")
	)
	(gr_line
		(start 173.659292 -19.180048)
		(end 173.740572 -19.162776)
		(stroke
			(width 0.072898)
			(type default)
		)
		(layer "B.Cu")
	)
	(gr_line
		(start 173.699932 -30.086554)
		(end 173.809914 -30.196536)
		(stroke
			(width 0.047498)
			(type default)
		)
		(layer "B.Cu")
	)
	(gr_line
		(start 173.73727 -29.511244)
		(end 173.760892 -29.487622)
		(stroke
			(width 0.047498)
			(type default)
		)
		(layer "B.Cu")
	)
	(gr_line
		(start 173.760892 -29.464)
		(end 173.760892 -29.487622)
		(stroke
			(width 0.047498)
			(type default)
		)
		(layer "B.Cu")
	)
	(gr_line
		(start 173.760892 -29.198824)
		(end 173.760892 -29.320744)
		(stroke
			(width 0.072898)
			(type default)
		)
		(layer "B.Cu")
	)
	(gr_line
		(start 173.809914 -30.196536)
		(end 173.809914 -30.505146)
		(stroke
			(width 0.047498)
			(type default)
		)
		(layer "B.Cu")
	)
	(gr_line
		(start 173.816264 -17.675606)
		(end 173.83633 -17.662144)
		(stroke
			(width 0.072898)
			(type default)
		)
		(layer "B.Cu")
	)
	(gr_line
		(start 173.81982 -28.484068)
		(end 174.03191 -28.484068)
		(stroke
			(width 0.072898)
			(type default)
		)
		(layer "B.Cu")
	)
	(gr_line
		(start 173.83633 -17.662144)
		(end 173.859698 -17.657572)
		(stroke
			(width 0.072898)
			(type default)
		)
		(layer "B.Cu")
	)
	(gr_line
		(start 173.9519 -29.007816)
		(end 174.033688 -28.926028)
		(stroke
			(width 0.072898)
			(type default)
		)
		(layer "B.Cu")
	)
	(gr_line
		(start 174.12081 -27.662632)
		(end 174.27067 -27.812492)
		(stroke
			(width 0.072898)
			(type default)
		)
		(layer "B.Cu")
	)
	(gr_line
		(start 174.12081 -27.224482)
		(end 174.12081 -27.662632)
		(stroke
			(width 0.072898)
			(type default)
		)
		(layer "B.Cu")
	)
	(gr_line
		(start 174.12081 -27.224482)
		(end 174.27067 -27.074622)
		(stroke
			(width 0.072898)
			(type default)
		)
		(layer "B.Cu")
	)
	(gr_line
		(start 174.364904 -17.559274)
		(end 175.02251 -17.431512)
		(stroke
			(width 0.072898)
			(type default)
		)
		(layer "B.Cu")
	)
	(gr_line
		(start 174.390558 -17.87398)
		(end 174.566834 -17.992598)
		(stroke
			(width 0.072898)
			(type default)
		)
		(layer "B.Cu")
	)
	(gr_line
		(start 174.390558 -12.425172)
		(end 174.412148 -12.410694)
		(stroke
			(width 0.072898)
			(type default)
		)
		(layer "B.Cu")
	)
	(gr_line
		(start 174.412148 -12.410694)
		(end 174.436786 -12.406122)
		(stroke
			(width 0.072898)
			(type default)
		)
		(layer "B.Cu")
	)
	(gr_line
		(start 174.412656 -26.36393)
		(end 174.412656 -26.406602)
		(stroke
			(width 0.072898)
			(type default)
		)
		(layer "B.Cu")
	)
	(gr_line
		(start 174.412656 -26.190956)
		(end 174.412656 -26.36139)
		(stroke
			(width 0.072898)
			(type default)
		)
		(layer "B.Cu")
	)
	(gr_line
		(start 174.412656 -26.190956)
		(end 174.722536 -25.88133)
		(stroke
			(width 0.072898)
			(type default)
		)
		(layer "B.Cu")
	)
	(gr_line
		(start 174.566834 -17.992598)
		(end 174.996856 -17.909032)
		(stroke
			(width 0.072898)
			(type default)
		)
		(layer "B.Cu")
	)
	(gr_line
		(start 174.58436 -27.385772)
		(end 174.58436 -27.501342)
		(stroke
			(width 0.072898)
			(type default)
		)
		(layer "B.Cu")
	)
	(gr_line
		(start 174.58436 -26.67508)
		(end 174.58436 -26.717752)
		(stroke
			(width 0.072898)
			(type default)
		)
		(layer "B.Cu")
	)
	(gr_line
		(start 174.722536 -25.88133)
		(end 174.934372 -25.88133)
		(stroke
			(width 0.072898)
			(type default)
		)
		(layer "B.Cu")
	)
	(gr_line
		(start 174.854616 -26.404824)
		(end 174.93615 -26.32329)
		(stroke
			(width 0.072898)
			(type default)
		)
		(layer "B.Cu")
	)
	(gr_line
		(start 174.996856 -17.909032)
		(end 175.115728 -17.73301)
		(stroke
			(width 0.072898)
			(type default)
		)
		(layer "B.Cu")
	)
	(gr_line
		(start 174.999904 -30.39999)
		(end 175.151796 -30.248098)
		(stroke
			(width 0.047498)
			(type default)
		)
		(layer "B.Cu")
	)
	(gr_line
		(start 175.000158 -31.20009)
		(end 175.399954 -30.52191)
		(stroke
			(width 0.047498)
			(type default)
		)
		(layer "B.Cu")
	)
	(gr_line
		(start 175.04283 -15.93596)
		(end 175.692816 -15.809468)
		(stroke
			(width 0.072898)
			(type default)
		)
		(layer "B.Cu")
	)
	(gr_line
		(start 175.043846 -21.382482)
		(end 175.170592 -21.509228)
		(stroke
			(width 0.072898)
			(type default)
		)
		(layer "B.Cu")
	)
	(gr_line
		(start 175.043846 -21.233892)
		(end 175.043846 -21.382482)
		(stroke
			(width 0.072898)
			(type default)
		)
		(layer "B.Cu")
	)
	(gr_line
		(start 175.043846 -20.675092)
		(end 175.105568 -20.61337)
		(stroke
			(width 0.072898)
			(type default)
		)
		(layer "B.Cu")
	)
	(gr_line
		(start 175.066198 -16.250666)
		(end 175.241966 -16.369284)
		(stroke
			(width 0.072898)
			(type default)
		)
		(layer "B.Cu")
	)
	(gr_line
		(start 175.079406 -25.119076)
		(end 175.229266 -25.268936)
		(stroke
			(width 0.072898)
			(type default)
		)
		(layer "B.Cu")
	)
	(gr_line
		(start 175.079406 -24.680926)
		(end 175.079406 -25.119076)
		(stroke
			(width 0.072898)
			(type default)
		)
		(layer "B.Cu")
	)
	(gr_line
		(start 175.079406 -24.680926)
		(end 175.229266 -24.531066)
		(stroke
			(width 0.072898)
			(type default)
		)
		(layer "B.Cu")
	)
	(gr_line
		(start 175.079406 -23.937976)
		(end 175.229266 -24.087836)
		(stroke
			(width 0.072898)
			(type default)
		)
		(layer "B.Cu")
	)
	(gr_line
		(start 175.079406 -23.499826)
		(end 175.079406 -23.937976)
		(stroke
			(width 0.072898)
			(type default)
		)
		(layer "B.Cu")
	)
	(gr_line
		(start 175.079406 -23.499826)
		(end 175.229266 -23.349966)
		(stroke
			(width 0.072898)
			(type default)
		)
		(layer "B.Cu")
	)
	(gr_line
		(start 175.079406 -22.756876)
		(end 175.229266 -22.906736)
		(stroke
			(width 0.072898)
			(type default)
		)
		(layer "B.Cu")
	)
	(gr_line
		(start 175.079406 -22.318726)
		(end 175.079406 -22.756876)
		(stroke
			(width 0.072898)
			(type default)
		)
		(layer "B.Cu")
	)
	(gr_line
		(start 175.079406 -22.318726)
		(end 175.229266 -22.168866)
		(stroke
			(width 0.072898)
			(type default)
		)
		(layer "B.Cu")
	)
	(gr_line
		(start 175.107854 -29.90215)
		(end 175.11649 -29.910786)
		(stroke
			(width 0.047498)
			(type default)
		)
		(layer "B.Cu")
	)
	(gr_line
		(start 175.107854 -29.878528)
		(end 175.107854 -29.90215)
		(stroke
			(width 0.047498)
			(type default)
		)
		(layer "B.Cu")
	)
	(gr_line
		(start 175.118268 -29.912564)
		(end 175.151796 -29.946092)
		(stroke
			(width 0.047498)
			(type default)
		)
		(layer "B.Cu")
	)
	(gr_line
		(start 175.151796 -29.946092)
		(end 175.174656 -29.968952)
		(stroke
			(width 0.047498)
			(type default)
		)
		(layer "B.Cu")
	)
	(gr_line
		(start 175.174656 -29.968952)
		(end 175.174656 -30.126178)
		(stroke
			(width 0.047498)
			(type default)
		)
		(layer "B.Cu")
	)
	(gr_line
		(start 175.241966 -16.369284)
		(end 175.672242 -16.285718)
		(stroke
			(width 0.072898)
			(type default)
		)
		(layer "B.Cu")
	)
	(gr_line
		(start 175.358806 -29.950664)
		(end 175.363378 -29.946092)
		(stroke
			(width 0.047498)
			(type default)
		)
		(layer "B.Cu")
	)
	(gr_line
		(start 175.363378 -29.946092)
		(end 175.396906 -29.912564)
		(stroke
			(width 0.047498)
			(type default)
		)
		(layer "B.Cu")
	)
	(gr_line
		(start 175.398684 -29.910786)
		(end 175.419004 -29.890466)
		(stroke
			(width 0.047498)
			(type default)
		)
		(layer "B.Cu")
	)
	(gr_line
		(start 175.399954 -30.234382)
		(end 175.399954 -30.52191)
		(stroke
			(width 0.047498)
			(type default)
		)
		(layer "B.Cu")
	)
	(gr_line
		(start 175.399954 -30.234382)
		(end 175.40097 -30.233366)
		(stroke
			(width 0.047498)
			(type default)
		)
		(layer "B.Cu")
	)
	(gr_line
		(start 175.419004 -29.878528)
		(end 175.419004 -29.890466)
		(stroke
			(width 0.047498)
			(type default)
		)
		(layer "B.Cu")
	)
	(gr_line
		(start 175.436784 -19.982434)
		(end 175.487838 -19.971766)
		(stroke
			(width 0.072898)
			(type default)
		)
		(layer "B.Cu")
	)
	(gr_line
		(start 175.515778 -28.312872)
		(end 175.665638 -28.462732)
		(stroke
			(width 0.072898)
			(type default)
		)
		(layer "B.Cu")
	)
	(gr_line
		(start 175.515778 -27.874722)
		(end 175.515778 -28.312872)
		(stroke
			(width 0.072898)
			(type default)
		)
		(layer "B.Cu")
	)
	(gr_line
		(start 175.515778 -27.874722)
		(end 175.665638 -27.724862)
		(stroke
			(width 0.072898)
			(type default)
		)
		(layer "B.Cu")
	)
	(gr_line
		(start 175.525176 -17.333722)
		(end 176.179734 -17.206468)
		(stroke
			(width 0.072898)
			(type default)
		)
		(layer "B.Cu")
	)
	(gr_line
		(start 175.542956 -24.842216)
		(end 175.542956 -24.957786)
		(stroke
			(width 0.072898)
			(type default)
		)
		(layer "B.Cu")
	)
	(gr_line
		(start 175.542956 -23.661116)
		(end 175.542956 -23.776686)
		(stroke
			(width 0.072898)
			(type default)
		)
		(layer "B.Cu")
	)
	(gr_line
		(start 175.542956 -22.480016)
		(end 175.542956 -22.595586)
		(stroke
			(width 0.072898)
			(type default)
		)
		(layer "B.Cu")
	)
	(gr_line
		(start 175.549052 -20.61337)
		(end 175.611028 -20.675346)
		(stroke
			(width 0.072898)
			(type default)
		)
		(layer "B.Cu")
	)
	(gr_line
		(start 175.550322 -17.648428)
		(end 175.72609 -17.7673)
		(stroke
			(width 0.072898)
			(type default)
		)
		(layer "B.Cu")
	)
	(gr_line
		(start 175.611028 -21.234146)
		(end 175.611028 -21.51253)
		(stroke
			(width 0.072898)
			(type default)
		)
		(layer "B.Cu")
	)
	(gr_line
		(start 175.672242 -16.285718)
		(end 175.790606 -16.10995)
		(stroke
			(width 0.072898)
			(type default)
		)
		(layer "B.Cu")
	)
	(gr_line
		(start 175.72609 -17.7673)
		(end 176.156366 -17.683734)
		(stroke
			(width 0.072898)
			(type default)
		)
		(layer "B.Cu")
	)
	(gr_line
		(start 175.792638 -16.106902)
		(end 176.22266 -16.023336)
		(stroke
			(width 0.072898)
			(type default)
		)
		(layer "B.Cu")
	)
	(gr_line
		(start 175.800004 -31.20009)
		(end 176.213516 -30.498542)
		(stroke
			(width 0.047498)
			(type default)
		)
		(layer "B.Cu")
	)
	(gr_line
		(start 175.800004 -30.400244)
		(end 175.951896 -30.248352)
		(stroke
			(width 0.047498)
			(type default)
		)
		(layer "B.Cu")
	)
	(gr_line
		(start 175.978058 -26.290524)
		(end 175.978058 -26.50236)
		(stroke
			(width 0.072898)
			(type default)
		)
		(layer "B.Cu")
	)
	(gr_line
		(start 175.978058 -26.290524)
		(end 176.287938 -25.980644)
		(stroke
			(width 0.072898)
			(type default)
		)
		(layer "B.Cu")
	)
	(gr_line
		(start 175.979328 -28.036012)
		(end 175.979328 -28.151582)
		(stroke
			(width 0.072898)
			(type default)
		)
		(layer "B.Cu")
	)
	(gr_line
		(start 176.156366 -17.683734)
		(end 176.274984 -17.507458)
		(stroke
			(width 0.072898)
			(type default)
		)
		(layer "B.Cu")
	)
	(gr_line
		(start 176.159414 -15.718536)
		(end 176.17059 -15.716504)
		(stroke
			(width 0.072898)
			(type default)
		)
		(layer "B.Cu")
	)
	(gr_line
		(start 176.203102 -15.710154)
		(end 176.85385 -15.583662)
		(stroke
			(width 0.072898)
			(type default)
		)
		(layer "B.Cu")
	)
	(gr_line
		(start 176.213516 -30.246066)
		(end 176.213516 -30.498542)
		(stroke
			(width 0.047498)
			(type default)
		)
		(layer "B.Cu")
	)
	(gr_line
		(start 176.225708 -16.025368)
		(end 176.401476 -16.143986)
		(stroke
			(width 0.072898)
			(type default)
		)
		(layer "B.Cu")
	)
	(gr_line
		(start 176.287938 -25.980644)
		(end 176.499774 -25.980644)
		(stroke
			(width 0.072898)
			(type default)
		)
		(layer "B.Cu")
	)
	(gr_line
		(start 176.401476 -16.143986)
		(end 176.831498 -16.06042)
		(stroke
			(width 0.072898)
			(type default)
		)
		(layer "B.Cu")
	)
	(gr_line
		(start 176.420018 -26.504138)
		(end 176.501552 -26.422604)
		(stroke
			(width 0.072898)
			(type default)
		)
		(layer "B.Cu")
	)
	(gr_line
		(start 176.464468 -28.404058)
		(end 176.478946 -28.418536)
		(stroke
			(width 0.047498)
			(type default)
		)
		(layer "B.Cu")
	)
	(gr_line
		(start 176.464468 -28.380436)
		(end 176.464468 -28.404058)
		(stroke
			(width 0.047498)
			(type default)
		)
		(layer "B.Cu")
	)
	(gr_line
		(start 176.480724 -28.420314)
		(end 176.528476 -28.468066)
		(stroke
			(width 0.047498)
			(type default)
		)
		(layer "B.Cu")
	)
	(gr_line
		(start 176.528476 -28.468066)
		(end 176.540668 -28.480258)
		(stroke
			(width 0.047498)
			(type default)
		)
		(layer "B.Cu")
	)
	(gr_line
		(start 176.540668 -28.480258)
		(end 176.540668 -28.658566)
		(stroke
			(width 0.047498)
			(type default)
		)
		(layer "B.Cu")
	)
	(gr_line
		(start 176.684432 -17.108424)
		(end 177.340514 -16.980916)
		(stroke
			(width 0.072898)
			(type default)
		)
		(layer "B.Cu")
	)
	(gr_line
		(start 176.709324 -17.42313)
		(end 176.8856 -17.541748)
		(stroke
			(width 0.072898)
			(type default)
		)
		(layer "B.Cu")
	)
	(gr_line
		(start 176.724818 -28.454858)
		(end 176.724818 -28.468066)
		(stroke
			(width 0.047498)
			(type default)
		)
		(layer "B.Cu")
	)
	(gr_line
		(start 176.724818 -28.454858)
		(end 176.759362 -28.420314)
		(stroke
			(width 0.047498)
			(type default)
		)
		(layer "B.Cu")
	)
	(gr_line
		(start 176.76114 -28.418536)
		(end 176.775618 -28.404058)
		(stroke
			(width 0.047498)
			(type default)
		)
		(layer "B.Cu")
	)
	(gr_line
		(start 176.775618 -28.380436)
		(end 176.775618 -28.404058)
		(stroke
			(width 0.047498)
			(type default)
		)
		(layer "B.Cu")
	)
	(gr_line
		(start 176.807114 -26.91765)
		(end 176.807114 -27.129486)
		(stroke
			(width 0.072898)
			(type default)
		)
		(layer "B.Cu")
	)
	(gr_line
		(start 176.807114 -26.91765)
		(end 177.116994 -26.60777)
		(stroke
			(width 0.072898)
			(type default)
		)
		(layer "B.Cu")
	)
	(gr_line
		(start 176.831498 -16.06042)
		(end 176.950116 -15.884652)
		(stroke
			(width 0.072898)
			(type default)
		)
		(layer "B.Cu")
	)
	(gr_line
		(start 176.8856 -17.541748)
		(end 177.315622 -17.458182)
		(stroke
			(width 0.072898)
			(type default)
		)
		(layer "B.Cu")
	)
	(gr_line
		(start 176.886616 -15.577312)
		(end 176.909984 -15.57274)
		(stroke
			(width 0.072898)
			(type default)
		)
		(layer "B.Cu")
	)
	(gr_line
		(start 176.952148 -15.881604)
		(end 176.969166 -15.878302)
		(stroke
			(width 0.072898)
			(type default)
		)
		(layer "B.Cu")
	)
	(gr_line
		(start 177.116994 -26.60777)
		(end 177.32883 -26.60777)
		(stroke
			(width 0.072898)
			(type default)
		)
		(layer "B.Cu")
	)
	(gr_line
		(start 177.178716 -21.063458)
		(end 177.244756 -20.998942)
		(stroke
			(width 0.072898)
			(type default)
		)
		(layer "B.Cu")
	)
	(gr_line
		(start 177.249074 -27.131264)
		(end 177.330608 -27.04973)
		(stroke
			(width 0.072898)
			(type default)
		)
		(layer "B.Cu")
	)
	(gr_line
		(start 177.315622 -17.458182)
		(end 177.434494 -17.28216)
		(stroke
			(width 0.072898)
			(type default)
		)
		(layer "B.Cu")
	)
	(gr_line
		(start 177.471578 -20.777708)
		(end 177.534062 -20.716748)
		(stroke
			(width 0.072898)
			(type default)
		)
		(layer "B.Cu")
	)
	(gr_line
		(start 177.843434 -16.883126)
		(end 178.4985 -16.755872)
		(stroke
			(width 0.072898)
			(type default)
		)
		(layer "B.Cu")
	)
	(gr_line
		(start 177.868834 -17.197832)
		(end 178.044856 -17.31645)
		(stroke
			(width 0.072898)
			(type default)
		)
		(layer "B.Cu")
	)
	(gr_line
		(start 178.024282 -21.139912)
		(end 178.03495 -21.15058)
		(stroke
			(width 0.072898)
			(type default)
		)
		(layer "B.Cu")
	)
	(gr_line
		(start 178.024282 -20.696174)
		(end 178.140614 -20.579842)
		(stroke
			(width 0.072898)
			(type default)
		)
		(layer "B.Cu")
	)
	(gr_line
		(start 178.03495 -21.15058)
		(end 178.141376 -21.15058)
		(stroke
			(width 0.072898)
			(type default)
		)
		(layer "B.Cu")
	)
	(gr_line
		(start 178.044856 -17.31645)
		(end 178.475132 -17.232884)
		(stroke
			(width 0.072898)
			(type default)
		)
		(layer "B.Cu")
	)
	(gr_line
		(start 178.394868 -15.284196)
		(end 178.414426 -15.280386)
		(stroke
			(width 0.072898)
			(type default)
		)
		(layer "B.Cu")
	)
	(gr_line
		(start 178.414426 -15.280386)
		(end 178.433984 -15.284196)
		(stroke
			(width 0.072898)
			(type default)
		)
		(layer "B.Cu")
	)
	(gr_line
		(start 178.4477 -14.060678)
		(end 178.467258 -14.056868)
		(stroke
			(width 0.072898)
			(type default)
		)
		(layer "B.Cu")
	)
	(gr_line
		(start 178.467258 -14.056868)
		(end 178.48707 -14.060678)
		(stroke
			(width 0.072898)
			(type default)
		)
		(layer "B.Cu")
	)
	(gr_line
		(start 178.475132 -17.232884)
		(end 178.59375 -17.056862)
		(stroke
			(width 0.072898)
			(type default)
		)
		(layer "B.Cu")
	)
	(gr_line
		(start 178.699414 -20.579842)
		(end 178.812698 -20.693126)
		(stroke
			(width 0.072898)
			(type default)
		)
		(layer "B.Cu")
	)
	(gr_line
		(start 178.700176 -21.15058)
		(end 178.84648 -21.15058)
		(stroke
			(width 0.072898)
			(type default)
		)
		(layer "B.Cu")
	)
	(gr_line
		(start 178.812698 -20.693126)
		(end 178.90109 -20.693126)
		(stroke
			(width 0.072898)
			(type default)
		)
		(layer "B.Cu")
	)
	(gr_line
		(start 178.84648 -21.15058)
		(end 179.006246 -20.990814)
		(stroke
			(width 0.072898)
			(type default)
		)
		(layer "B.Cu")
	)
	(gr_line
		(start 179.190396 -24.873458)
		(end 179.340256 -25.023318)
		(stroke
			(width 0.072898)
			(type default)
		)
		(layer "B.Cu")
	)
	(gr_line
		(start 179.190396 -24.435308)
		(end 179.190396 -24.873458)
		(stroke
			(width 0.072898)
			(type default)
		)
		(layer "B.Cu")
	)
	(gr_line
		(start 179.190396 -24.435308)
		(end 179.340256 -24.285448)
		(stroke
			(width 0.072898)
			(type default)
		)
		(layer "B.Cu")
	)
	(gr_line
		(start 179.190396 -23.692358)
		(end 179.340256 -23.842218)
		(stroke
			(width 0.072898)
			(type default)
		)
		(layer "B.Cu")
	)
	(gr_line
		(start 179.190396 -23.254208)
		(end 179.190396 -23.692358)
		(stroke
			(width 0.072898)
			(type default)
		)
		(layer "B.Cu")
	)
	(gr_line
		(start 179.190396 -23.254208)
		(end 179.340256 -23.104348)
		(stroke
			(width 0.072898)
			(type default)
		)
		(layer "B.Cu")
	)
	(gr_line
		(start 179.234846 -15.756636)
		(end 179.254404 -15.760446)
		(stroke
			(width 0.072898)
			(type default)
		)
		(layer "B.Cu")
	)
	(gr_line
		(start 179.254404 -15.760446)
		(end 179.273962 -15.756636)
		(stroke
			(width 0.072898)
			(type default)
		)
		(layer "B.Cu")
	)
	(gr_line
		(start 179.394104 -14.553438)
		(end 179.418996 -14.558264)
		(stroke
			(width 0.072898)
			(type default)
		)
		(layer "B.Cu")
	)
	(gr_line
		(start 179.418996 -14.558264)
		(end 179.444396 -14.552422)
		(stroke
			(width 0.072898)
			(type default)
		)
		(layer "B.Cu")
	)
	(gr_line
		(start 179.640992 -21.75002)
		(end 179.661566 -21.741384)
		(stroke
			(width 0.072898)
			(type default)
		)
		(layer "B.Cu")
	)
	(gr_line
		(start 179.653946 -24.596598)
		(end 179.653946 -24.712168)
		(stroke
			(width 0.072898)
			(type default)
		)
		(layer "B.Cu")
	)
	(gr_line
		(start 179.653946 -23.415498)
		(end 179.653946 -23.531068)
		(stroke
			(width 0.072898)
			(type default)
		)
		(layer "B.Cu")
	)
	(gr_arc
		(start 179.823872 -11.5443)
		(mid 179.948338 -11.492744)
		(end 179.999894 -11.368278)
		(stroke
			(width 0.072898)
			(type default)
		)
		(layer "B.Cu")
	)
	(gr_arc
		(start 179.999894 -12.031726)
		(mid 179.948274 -11.907057)
		(end 179.823618 -11.85545)
		(stroke
			(width 0.072898)
			(type default)
		)
		(layer "B.Cu")
	)
	(gr_line
		(start 179.999894 -12.031726)
		(end 179.999894 -12.400026)
		(stroke
			(width 0.072898)
			(type default)
		)
		(layer "B.Cu")
	)
	(gr_line
		(start 179.999894 -10.999978)
		(end 179.999894 -11.368278)
		(stroke
			(width 0.072898)
			(type default)
		)
		(layer "B.Cu")
	)
	(gr_line
		(start 180.3019 -14.35608)
		(end 180.305964 -14.355064)
		(stroke
			(width 0.072898)
			(type default)
		)
		(layer "B.Cu")
	)
	(gr_line
		(start 180.305964 -14.355064)
		(end 180.309012 -14.353286)
		(stroke
			(width 0.072898)
			(type default)
		)
		(layer "B.Cu")
	)
	(gr_line
		(start 180.499512 -21.387308)
		(end 180.521356 -21.378164)
		(stroke
			(width 0.072898)
			(type default)
		)
		(layer "B.Cu")
	)
	(gr_line
		(start 180.641244 -14.172692)
		(end 180.67655 -14.153388)
		(stroke
			(width 0.072898)
			(type default)
		)
		(layer "B.Cu")
	)
	(gr_line
		(start 180.67655 -14.153388)
		(end 180.698648 -14.119352)
		(stroke
			(width 0.072898)
			(type default)
		)
		(layer "B.Cu")
	)
	(gr_line
		(start 180.761894 -15.467584)
		(end 180.783992 -15.463266)
		(stroke
			(width 0.072898)
			(type default)
		)
		(layer "B.Cu")
	)
	(gr_line
		(start 180.783992 -15.463266)
		(end 180.802788 -15.451074)
		(stroke
			(width 0.072898)
			(type default)
		)
		(layer "B.Cu")
	)
	(gr_line
		(start 180.791866 -21.76907)
		(end 180.864764 -21.841968)
		(stroke
			(width 0.072898)
			(type default)
		)
		(layer "B.Cu")
	)
	(gr_line
		(start 180.791866 -21.325586)
		(end 180.842412 -21.27504)
		(stroke
			(width 0.072898)
			(type default)
		)
		(layer "B.Cu")
	)
	(gr_line
		(start 180.842412 -21.27504)
		(end 180.99024 -21.27504)
		(stroke
			(width 0.072898)
			(type default)
		)
		(layer "B.Cu")
	)
	(gr_line
		(start 180.864764 -21.841968)
		(end 180.989986 -21.841968)
		(stroke
			(width 0.072898)
			(type default)
		)
		(layer "B.Cu")
	)
	(gr_line
		(start 180.96992 -13.701268)
		(end 180.979572 -13.686282)
		(stroke
			(width 0.072898)
			(type default)
		)
		(layer "B.Cu")
	)
	(gr_line
		(start 180.979572 -13.686282)
		(end 180.983382 -13.668756)
		(stroke
			(width 0.072898)
			(type default)
		)
		(layer "B.Cu")
	)
	(gr_line
		(start 181.267608 -16.534384)
		(end 181.292246 -16.529812)
		(stroke
			(width 0.072898)
			(type default)
		)
		(layer "B.Cu")
	)
	(gr_line
		(start 181.292246 -16.529812)
		(end 181.313836 -16.515334)
		(stroke
			(width 0.072898)
			(type default)
		)
		(layer "B.Cu")
	)
	(gr_line
		(start 181.548786 -21.841968)
		(end 181.714648 -21.841968)
		(stroke
			(width 0.072898)
			(type default)
		)
		(layer "B.Cu")
	)
	(gr_line
		(start 181.54904 -21.27504)
		(end 181.669182 -21.27504)
		(stroke
			(width 0.072898)
			(type default)
		)
		(layer "B.Cu")
	)
	(gr_line
		(start 181.590188 -17.812512)
		(end 181.608984 -17.808702)
		(stroke
			(width 0.072898)
			(type default)
		)
		(layer "B.Cu")
	)
	(gr_line
		(start 181.608984 -17.808702)
		(end 181.624478 -17.798542)
		(stroke
			(width 0.072898)
			(type default)
		)
		(layer "B.Cu")
	)
	(gr_arc
		(start 181.62397 -10.344404)
		(mid 181.748449 -10.292858)
		(end 181.799992 -10.168382)
		(stroke
			(width 0.072898)
			(type default)
		)
		(layer "B.Cu")
	)
	(gr_line
		(start 181.669182 -21.27504)
		(end 181.75351 -21.359368)
		(stroke
			(width 0.072898)
			(type default)
		)
		(layer "B.Cu")
	)
	(gr_line
		(start 181.714648 -21.841968)
		(end 181.75351 -21.803106)
		(stroke
			(width 0.072898)
			(type default)
		)
		(layer "B.Cu")
	)
	(gr_arc
		(start 181.799992 -10.83183)
		(mid 181.748374 -10.707159)
		(end 181.623716 -10.655554)
		(stroke
			(width 0.072898)
			(type default)
		)
		(layer "B.Cu")
	)
	(gr_line
		(start 181.799992 -10.83183)
		(end 181.799992 -11.20013)
		(stroke
			(width 0.072898)
			(type default)
		)
		(layer "B.Cu")
	)
	(gr_line
		(start 181.799992 -9.800082)
		(end 181.799992 -10.168382)
		(stroke
			(width 0.072898)
			(type default)
		)
		(layer "B.Cu")
	)
	(gr_line
		(start 181.838346 -17.28851)
		(end 182.398162 -16.925036)
		(stroke
			(width 0.072898)
			(type default)
		)
		(layer "B.Cu")
	)
	(gr_line
		(start 181.868826 -14.75867)
		(end 181.89194 -14.743684)
		(stroke
			(width 0.072898)
			(type default)
		)
		(layer "B.Cu")
	)
	(gr_line
		(start 181.89194 -14.743684)
		(end 181.906926 -14.72057)
		(stroke
			(width 0.072898)
			(type default)
		)
		(layer "B.Cu")
	)
	(gr_line
		(start 181.97957 -17.570958)
		(end 182.187342 -17.6149)
		(stroke
			(width 0.072898)
			(type default)
		)
		(layer "B.Cu")
	)
	(gr_line
		(start 182.187342 -17.6149)
		(end 182.554626 -17.376394)
		(stroke
			(width 0.072898)
			(type default)
		)
		(layer "B.Cu")
	)
	(gr_line
		(start 182.554626 -17.376394)
		(end 182.598822 -17.168622)
		(stroke
			(width 0.072898)
			(type default)
		)
		(layer "B.Cu")
	)
	(gr_line
		(start 182.668926 -13.54709)
		(end 182.679086 -13.531596)
		(stroke
			(width 0.072898)
			(type default)
		)
		(layer "B.Cu")
	)
	(gr_line
		(start 182.678832 -13.531596)
		(end 182.679086 -13.531596)
		(stroke
			(width 0.072898)
			(type default)
		)
		(layer "B.Cu")
	)
	(gr_line
		(start 182.678832 -13.531596)
		(end 182.682642 -13.51407)
		(stroke
			(width 0.072898)
			(type default)
		)
		(layer "B.Cu")
	)
	(gr_line
		(start 182.828692 -16.645636)
		(end 183.388254 -16.282162)
		(stroke
			(width 0.072898)
			(type default)
		)
		(layer "B.Cu")
	)
	(gr_line
		(start 182.97017 -16.927576)
		(end 183.177942 -16.971772)
		(stroke
			(width 0.072898)
			(type default)
		)
		(layer "B.Cu")
	)
	(gr_line
		(start 183.095646 -18.673064)
		(end 183.113172 -18.669254)
		(stroke
			(width 0.072898)
			(type default)
		)
		(layer "B.Cu")
	)
	(gr_line
		(start 183.113172 -18.669254)
		(end 183.127396 -18.659856)
		(stroke
			(width 0.072898)
			(type default)
		)
		(layer "B.Cu")
	)
	(gr_line
		(start 183.177942 -16.971772)
		(end 183.545226 -16.733012)
		(stroke
			(width 0.072898)
			(type default)
		)
		(layer "B.Cu")
	)
	(gr_arc
		(start 183.423814 -11.5443)
		(mid 183.54828 -11.492744)
		(end 183.599836 -11.368278)
		(stroke
			(width 0.072898)
			(type default)
		)
		(layer "B.Cu")
	)
	(gr_line
		(start 183.545226 -16.733012)
		(end 183.589422 -16.525494)
		(stroke
			(width 0.072898)
			(type default)
		)
		(layer "B.Cu")
	)
	(gr_arc
		(start 183.599836 -12.031726)
		(mid 183.548213 -11.907077)
		(end 183.42356 -11.85545)
		(stroke
			(width 0.072898)
			(type default)
		)
		(layer "B.Cu")
	)
	(gr_line
		(start 183.599836 -12.031726)
		(end 183.599836 -12.400026)
		(stroke
			(width 0.072898)
			(type default)
		)
		(layer "B.Cu")
	)
	(gr_line
		(start 183.599836 -10.999978)
		(end 183.599836 -11.368278)
		(stroke
			(width 0.072898)
			(type default)
		)
		(layer "B.Cu")
	)
	(gr_line
		(start 183.819038 -16.002254)
		(end 184.379616 -15.638272)
		(stroke
			(width 0.072898)
			(type default)
		)
		(layer "B.Cu")
	)
	(gr_line
		(start 183.96077 -16.284448)
		(end 184.168542 -16.32839)
		(stroke
			(width 0.072898)
			(type default)
		)
		(layer "B.Cu")
	)
	(gr_line
		(start 184.09412 -14.639544)
		(end 184.111392 -14.62786)
		(stroke
			(width 0.072898)
			(type default)
		)
		(layer "B.Cu")
	)
	(gr_line
		(start 184.111392 -14.62786)
		(end 184.123076 -14.610588)
		(stroke
			(width 0.072898)
			(type default)
		)
		(layer "B.Cu")
	)
	(gr_line
		(start 184.168542 -16.32839)
		(end 184.535826 -16.089884)
		(stroke
			(width 0.072898)
			(type default)
		)
		(layer "B.Cu")
	)
	(gr_line
		(start 184.229756 -21.368512)
		(end 184.253124 -21.36394)
		(stroke
			(width 0.072898)
			(type default)
		)
		(layer "B.Cu")
	)
	(gr_line
		(start 184.253124 -21.36394)
		(end 184.27319 -21.350478)
		(stroke
			(width 0.072898)
			(type default)
		)
		(layer "B.Cu")
	)
	(gr_line
		(start 184.328054 -17.509236)
		(end 184.886346 -17.146778)
		(stroke
			(width 0.072898)
			(type default)
		)
		(layer "B.Cu")
	)
	(gr_line
		(start 184.468008 -17.792446)
		(end 184.675526 -17.836642)
		(stroke
			(width 0.072898)
			(type default)
		)
		(layer "B.Cu")
	)
	(gr_line
		(start 184.509156 -14.037818)
		(end 184.523634 -14.016228)
		(stroke
			(width 0.072898)
			(type default)
		)
		(layer "B.Cu")
	)
	(gr_line
		(start 184.523634 -14.016228)
		(end 184.528714 -13.990574)
		(stroke
			(width 0.072898)
			(type default)
		)
		(layer "B.Cu")
	)
	(gr_line
		(start 184.535826 -16.089884)
		(end 184.580022 -15.882366)
		(stroke
			(width 0.072898)
			(type default)
		)
		(layer "B.Cu")
	)
	(gr_line
		(start 184.59323 -19.496278)
		(end 184.605168 -19.493484)
		(stroke
			(width 0.072898)
			(type default)
		)
		(layer "B.Cu")
	)
	(gr_line
		(start 184.605168 -19.493484)
		(end 184.615836 -19.486626)
		(stroke
			(width 0.072898)
			(type default)
		)
		(layer "B.Cu")
	)
	(gr_line
		(start 184.675526 -17.836642)
		(end 185.04281 -17.597882)
		(stroke
			(width 0.072898)
			(type default)
		)
		(layer "B.Cu")
	)
	(gr_line
		(start 185.04281 -17.597882)
		(end 185.087006 -17.390364)
		(stroke
			(width 0.072898)
			(type default)
		)
		(layer "B.Cu")
	)
	(gr_arc
		(start 185.223912 -10.344404)
		(mid 185.348378 -10.292848)
		(end 185.399934 -10.168382)
		(stroke
			(width 0.072898)
			(type default)
		)
		(layer "B.Cu")
	)
	(gr_line
		(start 185.317638 -16.866362)
		(end 185.876946 -16.503142)
		(stroke
			(width 0.072898)
			(type default)
		)
		(layer "B.Cu")
	)
	(gr_arc
		(start 185.399934 -10.83183)
		(mid 185.348312 -10.70718)
		(end 185.223658 -10.655554)
		(stroke
			(width 0.072898)
			(type default)
		)
		(layer "B.Cu")
	)
	(gr_line
		(start 185.399934 -10.83183)
		(end 185.399934 -11.20013)
		(stroke
			(width 0.072898)
			(type default)
		)
		(layer "B.Cu")
	)
	(gr_line
		(start 185.399934 -9.800082)
		(end 185.399934 -10.168382)
		(stroke
			(width 0.072898)
			(type default)
		)
		(layer "B.Cu")
	)
	(gr_line
		(start 185.458608 -17.149064)
		(end 185.666126 -17.19326)
		(stroke
			(width 0.072898)
			(type default)
		)
		(layer "B.Cu")
	)
	(gr_line
		(start 185.517028 -15.270988)
		(end 185.540142 -15.256002)
		(stroke
			(width 0.072898)
			(type default)
		)
		(layer "B.Cu")
	)
	(gr_line
		(start 185.540142 -15.256002)
		(end 185.555128 -15.232888)
		(stroke
			(width 0.072898)
			(type default)
		)
		(layer "B.Cu")
	)
	(gr_line
		(start 185.666126 -17.19326)
		(end 186.03341 -16.9545)
		(stroke
			(width 0.072898)
			(type default)
		)
		(layer "B.Cu")
	)
	(gr_line
		(start 186.03341 -16.9545)
		(end 186.077606 -16.746982)
		(stroke
			(width 0.072898)
			(type default)
		)
		(layer "B.Cu")
	)
	(gr_line
		(start 186.419998 -16.521684)
		(end 186.443112 -16.506698)
		(stroke
			(width 0.072898)
			(type default)
		)
		(layer "B.Cu")
	)
	(gr_line
		(start 186.426348 -13.892276)
		(end 186.455304 -13.847572)
		(stroke
			(width 0.072898)
			(type default)
		)
		(layer "B.Cu")
	)
	(gr_line
		(start 186.44235 -15.936214)
		(end 186.804808 -15.377922)
		(stroke
			(width 0.072898)
			(type default)
		)
		(layer "B.Cu")
	)
	(gr_line
		(start 186.443112 -16.506698)
		(end 186.458098 -16.483584)
		(stroke
			(width 0.072898)
			(type default)
		)
		(layer "B.Cu")
	)
	(gr_line
		(start 186.601608 -17.82318)
		(end 186.645804 -17.615662)
		(stroke
			(width 0.072898)
			(type default)
		)
		(layer "B.Cu")
	)
	(gr_line
		(start 186.645804 -17.615662)
		(end 187.013088 -17.377156)
		(stroke
			(width 0.072898)
			(type default)
		)
		(layer "B.Cu")
	)
	(gr_line
		(start 186.685174 -16.138398)
		(end 186.892438 -16.094456)
		(stroke
			(width 0.072898)
			(type default)
		)
		(layer "B.Cu")
	)
	(gr_line
		(start 186.802776 -18.066512)
		(end 187.36183 -17.703546)
		(stroke
			(width 0.072898)
			(type default)
		)
		(layer "B.Cu")
	)
	(gr_line
		(start 186.892438 -16.094456)
		(end 187.131198 -15.726918)
		(stroke
			(width 0.072898)
			(type default)
		)
		(layer "B.Cu")
	)
	(gr_line
		(start 187.013088 -17.377156)
		(end 187.22086 -17.421098)
		(stroke
			(width 0.072898)
			(type default)
		)
		(layer "B.Cu")
	)
	(gr_arc
		(start 187.023756 -11.5443)
		(mid 187.148222 -11.492744)
		(end 187.199778 -11.368278)
		(stroke
			(width 0.072898)
			(type default)
		)
		(layer "B.Cu")
	)
	(gr_line
		(start 187.087256 -15.519146)
		(end 187.131198 -15.726918)
		(stroke
			(width 0.072898)
			(type default)
		)
		(layer "B.Cu")
	)
	(gr_arc
		(start 187.199778 -12.031726)
		(mid 187.148157 -11.907063)
		(end 187.023502 -11.85545)
		(stroke
			(width 0.072898)
			(type default)
		)
		(layer "B.Cu")
	)
	(gr_line
		(start 187.199778 -12.031726)
		(end 187.199778 -12.400026)
		(stroke
			(width 0.072898)
			(type default)
		)
		(layer "B.Cu")
	)
	(gr_line
		(start 187.199778 -10.999978)
		(end 187.199778 -11.368278)
		(stroke
			(width 0.072898)
			(type default)
		)
		(layer "B.Cu")
	)
	(gr_line
		(start 187.793376 -17.423384)
		(end 187.81649 -17.408398)
		(stroke
			(width 0.072898)
			(type default)
		)
		(layer "B.Cu")
	)
	(gr_line
		(start 187.81649 -17.408398)
		(end 187.831476 -17.385284)
		(stroke
			(width 0.072898)
			(type default)
		)
		(layer "B.Cu")
	)
	(gr_line
		(start 188.08319 -13.981176)
		(end 188.093858 -13.964666)
		(stroke
			(width 0.072898)
			(type default)
		)
		(layer "B.Cu")
	)
	(gr_line
		(start 188.093858 -13.964666)
		(end 188.097922 -13.945616)
		(stroke
			(width 0.072898)
			(type default)
		)
		(layer "B.Cu")
	)
	(gr_arc
		(start 188.823854 -10.344404)
		(mid 188.94832 -10.292848)
		(end 188.999876 -10.168382)
		(stroke
			(width 0.072898)
			(type default)
		)
		(layer "B.Cu")
	)
	(gr_arc
		(start 188.999876 -10.83183)
		(mid 188.948257 -10.707165)
		(end 188.8236 -10.655554)
		(stroke
			(width 0.072898)
			(type default)
		)
		(layer "B.Cu")
	)
	(gr_line
		(start 188.999876 -10.83183)
		(end 188.999876 -11.20013)
		(stroke
			(width 0.072898)
			(type default)
		)
		(layer "B.Cu")
	)
	(gr_line
		(start 188.999876 -9.800082)
		(end 188.999876 -10.168382)
		(stroke
			(width 0.072898)
			(type default)
		)
		(layer "B.Cu")
	)
	(gr_line
		(start 189.77483 -17.639538)
		(end 189.795404 -17.625822)
		(stroke
			(width 0.072898)
			(type default)
		)
		(layer "B.Cu")
	)
	(gr_line
		(start 189.795404 -17.625822)
		(end 189.80912 -17.60474)
		(stroke
			(width 0.072898)
			(type default)
		)
		(layer "B.Cu")
	)
	(gr_line
		(start 189.995048 -14.052296)
		(end 190.004446 -14.038072)
		(stroke
			(width 0.072898)
			(type default)
		)
		(layer "B.Cu")
	)
	(gr_line
		(start 190.004446 -14.038072)
		(end 190.008256 -14.020546)
		(stroke
			(width 0.072898)
			(type default)
		)
		(layer "B.Cu")
	)
	(gr_arc
		(start 190.623952 -11.5443)
		(mid 190.748418 -11.492744)
		(end 190.799974 -11.368278)
		(stroke
			(width 0.072898)
			(type default)
		)
		(layer "B.Cu")
	)
	(gr_arc
		(start 190.799974 -12.031726)
		(mid 190.748353 -11.907064)
		(end 190.623698 -11.85545)
		(stroke
			(width 0.072898)
			(type default)
		)
		(layer "B.Cu")
	)
	(gr_line
		(start 190.799974 -12.031726)
		(end 190.799974 -12.400026)
		(stroke
			(width 0.072898)
			(type default)
		)
		(layer "B.Cu")
	)
	(gr_line
		(start 190.799974 -10.999978)
		(end 190.799974 -11.368278)
		(stroke
			(width 0.072898)
			(type default)
		)
		(layer "B.Cu")
	)
	(gr_line
		(start 191.656462 -14.760702)
		(end 191.66586 -14.746478)
		(stroke
			(width 0.072898)
			(type default)
		)
		(layer "B.Cu")
	)
	(gr_line
		(start 191.66586 -14.746478)
		(end 191.66967 -14.728952)
		(stroke
			(width 0.072898)
			(type default)
		)
		(layer "B.Cu")
	)
	(gr_arc
		(start 192.423796 -10.344404)
		(mid 192.548262 -10.292848)
		(end 192.599818 -10.168382)
		(stroke
			(width 0.072898)
			(type default)
		)
		(layer "B.Cu")
	)
	(gr_arc
		(start 192.599818 -10.83183)
		(mid 192.548201 -10.70715)
		(end 192.423542 -10.655554)
		(stroke
			(width 0.072898)
			(type default)
		)
		(layer "B.Cu")
	)
	(gr_line
		(start 192.599818 -10.83183)
		(end 192.599818 -11.20013)
		(stroke
			(width 0.072898)
			(type default)
		)
		(layer "B.Cu")
	)
	(gr_line
		(start 192.599818 -9.800082)
		(end 192.599818 -10.168382)
		(stroke
			(width 0.072898)
			(type default)
		)
		(layer "B.Cu")
	)
	(gr_line
		(start 0 -142.999968)
		(end 0 -1.999996)
		(stroke
			(width 1.524)
			(type default)
		)
		(layer "In1.Cu")
	)
	(gr_arc
		(start 0 -142.999968)
		(mid 0.585785 -144.414179)
		(end 1.999996 -144.999964)
		(stroke
			(width 1.524)
			(type default)
		)
		(layer "In1.Cu")
	)
	(gr_arc
		(start 1.999996 0)
		(mid 0.585785 -0.585785)
		(end 0 -1.999996)
		(stroke
			(width 1.524)
			(type default)
		)
		(layer "In1.Cu")
	)
	(gr_line
		(start 1.999996 0)
		(end 208.000092 0)
		(stroke
			(width 1.524)
			(type default)
		)
		(layer "In1.Cu")
	)
	(gr_line
		(start 4.74218 -63.79464)
		(end 5.27812 -64.33058)
		(stroke
			(width 0.381)
			(type default)
		)
		(layer "In1.Cu")
	)
	(gr_line
		(start 4.74218 -35.76828)
		(end 4.74218 -63.79464)
		(stroke
			(width 0.381)
			(type default)
		)
		(layer "In1.Cu")
	)
	(gr_line
		(start 5.27812 -64.33058)
		(end 5.68706 -64.33058)
		(stroke
			(width 0.381)
			(type default)
		)
		(layer "In1.Cu")
	)
	(gr_line
		(start 5.33146 -35.179)
		(end 4.74218 -35.76828)
		(stroke
			(width 0.381)
			(type default)
		)
		(layer "In1.Cu")
	)
	(gr_line
		(start 5.68706 -64.33058)
		(end 23.84298 -64.33058)
		(stroke
			(width 0.381)
			(type default)
		)
		(layer "In1.Cu")
	)
	(gr_line
		(start 18.19148 -35.179)
		(end 5.33146 -35.179)
		(stroke
			(width 0.381)
			(type default)
		)
		(layer "In1.Cu")
	)
	(gr_line
		(start 21.00834 -37.99586)
		(end 18.19148 -35.179)
		(stroke
			(width 0.381)
			(type default)
		)
		(layer "In1.Cu")
	)
	(gr_line
		(start 23.80742 -37.99586)
		(end 21.00834 -37.99586)
		(stroke
			(width 0.381)
			(type default)
		)
		(layer "In1.Cu")
	)
	(gr_line
		(start 23.84298 -64.33058)
		(end 24.83612 -63.33744)
		(stroke
			(width 0.381)
			(type default)
		)
		(layer "In1.Cu")
	)
	(gr_line
		(start 24.83612 -63.33744)
		(end 24.83612 -39.02456)
		(stroke
			(width 0.381)
			(type default)
		)
		(layer "In1.Cu")
	)
	(gr_line
		(start 24.83612 -39.02456)
		(end 23.80742 -37.99586)
		(stroke
			(width 0.381)
			(type default)
		)
		(layer "In1.Cu")
	)
	(gr_line
		(start 83.002374 -144.999964)
		(end 1.999996 -144.999964)
		(stroke
			(width 1.524)
			(type default)
		)
		(layer "In1.Cu")
	)
	(gr_arc
		(start 83.002374 -144.999964)
		(mid 84.41672 -144.414257)
		(end 85.002624 -142.999968)
		(stroke
			(width 1.524)
			(type default)
		)
		(layer "In1.Cu")
	)
	(gr_line
		(start 85.002624 -132.26288)
		(end 85.002624 -142.999968)
		(stroke
			(width 1.524)
			(type default)
		)
		(layer "In1.Cu")
	)
	(gr_arc
		(start 85.438742 -12.399772)
		(mid 85.999955 -12.961366)
		(end 86.561422 -12.400026)
		(stroke
			(width 0.2)
			(type default)
		)
		(layer "In1.Cu")
	)
	(gr_line
		(start 85.438742 -10.999978)
		(end 85.438742 -12.399772)
		(stroke
			(width 0.2)
			(type default)
		)
		(layer "In1.Cu")
	)
	(gr_arc
		(start 85.438742 -5.199888)
		(mid 85.999955 -5.761482)
		(end 86.561422 -5.200142)
		(stroke
			(width 0.2)
			(type default)
		)
		(layer "In1.Cu")
	)
	(gr_line
		(start 85.438742 -3.800094)
		(end 85.438742 -5.199888)
		(stroke
			(width 0.2)
			(type default)
		)
		(layer "In1.Cu")
	)
	(gr_line
		(start 86.561422 -12.400026)
		(end 86.561422 -10.999978)
		(stroke
			(width 0.2)
			(type default)
		)
		(layer "In1.Cu")
	)
	(gr_arc
		(start 86.561422 -10.999978)
		(mid 86.000082 -10.438638)
		(end 85.438742 -10.999978)
		(stroke
			(width 0.2)
			(type default)
		)
		(layer "In1.Cu")
	)
	(gr_line
		(start 86.561422 -5.200142)
		(end 86.561422 -3.800094)
		(stroke
			(width 0.2)
			(type default)
		)
		(layer "In1.Cu")
	)
	(gr_arc
		(start 86.561422 -3.800094)
		(mid 86.000082 -3.238754)
		(end 85.438742 -3.800094)
		(stroke
			(width 0.2)
			(type default)
		)
		(layer "In1.Cu")
	)
	(gr_arc
		(start 87.23884 -11.199876)
		(mid 87.800053 -11.76147)
		(end 88.36152 -11.20013)
		(stroke
			(width 0.2)
			(type default)
		)
		(layer "In1.Cu")
	)
	(gr_line
		(start 87.23884 -9.800082)
		(end 87.23884 -11.199876)
		(stroke
			(width 0.2)
			(type default)
		)
		(layer "In1.Cu")
	)
	(gr_arc
		(start 87.23884 -3.999738)
		(mid 87.800053 -4.561332)
		(end 88.36152 -3.999992)
		(stroke
			(width 0.2)
			(type default)
		)
		(layer "In1.Cu")
	)
	(gr_line
		(start 87.23884 -2.600198)
		(end 87.23884 -3.999738)
		(stroke
			(width 0.2)
			(type default)
		)
		(layer "In1.Cu")
	)
	(gr_line
		(start 88.36152 -11.20013)
		(end 88.36152 -9.800082)
		(stroke
			(width 0.2)
			(type default)
		)
		(layer "In1.Cu")
	)
	(gr_arc
		(start 88.36152 -9.800082)
		(mid 87.80018 -9.238742)
		(end 87.23884 -9.800082)
		(stroke
			(width 0.2)
			(type default)
		)
		(layer "In1.Cu")
	)
	(gr_line
		(start 88.36152 -3.999992)
		(end 88.36152 -2.600198)
		(stroke
			(width 0.2)
			(type default)
		)
		(layer "In1.Cu")
	)
	(gr_arc
		(start 88.36152 -2.600198)
		(mid 87.80018 -2.038858)
		(end 87.23884 -2.600198)
		(stroke
			(width 0.2)
			(type default)
		)
		(layer "In1.Cu")
	)
	(gr_arc
		(start 89.038684 -12.399772)
		(mid 89.599897 -12.961366)
		(end 90.161364 -12.400026)
		(stroke
			(width 0.2)
			(type default)
		)
		(layer "In1.Cu")
	)
	(gr_line
		(start 89.038684 -10.999978)
		(end 89.038684 -12.399772)
		(stroke
			(width 0.2)
			(type default)
		)
		(layer "In1.Cu")
	)
	(gr_arc
		(start 89.038684 -5.199888)
		(mid 89.599897 -5.761482)
		(end 90.161364 -5.200142)
		(stroke
			(width 0.2)
			(type default)
		)
		(layer "In1.Cu")
	)
	(gr_line
		(start 89.038684 -3.800094)
		(end 89.038684 -5.199888)
		(stroke
			(width 0.2)
			(type default)
		)
		(layer "In1.Cu")
	)
	(gr_arc
		(start 89.212674 -127.325628)
		(mid 86.197998 -129.018598)
		(end 85.002624 -132.26288)
		(stroke
			(width 1.524)
			(type default)
		)
		(layer "In1.Cu")
	)
	(gr_line
		(start 90.161364 -12.400026)
		(end 90.161364 -10.999978)
		(stroke
			(width 0.2)
			(type default)
		)
		(layer "In1.Cu")
	)
	(gr_arc
		(start 90.161364 -10.999978)
		(mid 89.600024 -10.438638)
		(end 89.038684 -10.999978)
		(stroke
			(width 0.2)
			(type default)
		)
		(layer "In1.Cu")
	)
	(gr_line
		(start 90.161364 -5.200142)
		(end 90.161364 -3.800094)
		(stroke
			(width 0.2)
			(type default)
		)
		(layer "In1.Cu")
	)
	(gr_arc
		(start 90.161364 -3.800094)
		(mid 89.600024 -3.238754)
		(end 89.038684 -3.800094)
		(stroke
			(width 0.2)
			(type default)
		)
		(layer "In1.Cu")
	)
	(gr_arc
		(start 90.838782 -11.199876)
		(mid 91.399995 -11.76147)
		(end 91.961462 -11.20013)
		(stroke
			(width 0.2)
			(type default)
		)
		(layer "In1.Cu")
	)
	(gr_line
		(start 90.838782 -9.800082)
		(end 90.838782 -11.199876)
		(stroke
			(width 0.2)
			(type default)
		)
		(layer "In1.Cu")
	)
	(gr_arc
		(start 90.838782 -3.999738)
		(mid 91.399995 -4.561332)
		(end 91.961462 -3.999992)
		(stroke
			(width 0.2)
			(type default)
		)
		(layer "In1.Cu")
	)
	(gr_line
		(start 90.838782 -2.600198)
		(end 90.838782 -3.999738)
		(stroke
			(width 0.2)
			(type default)
		)
		(layer "In1.Cu")
	)
	(gr_line
		(start 91.961462 -11.20013)
		(end 91.961462 -9.800082)
		(stroke
			(width 0.2)
			(type default)
		)
		(layer "In1.Cu")
	)
	(gr_arc
		(start 91.961462 -9.800082)
		(mid 91.400122 -9.238742)
		(end 90.838782 -9.800082)
		(stroke
			(width 0.2)
			(type default)
		)
		(layer "In1.Cu")
	)
	(gr_line
		(start 91.961462 -3.999992)
		(end 91.961462 -2.600198)
		(stroke
			(width 0.2)
			(type default)
		)
		(layer "In1.Cu")
	)
	(gr_arc
		(start 91.961462 -2.600198)
		(mid 91.400122 -2.038858)
		(end 90.838782 -2.600198)
		(stroke
			(width 0.2)
			(type default)
		)
		(layer "In1.Cu")
	)
	(gr_arc
		(start 92.638626 -12.399772)
		(mid 93.199839 -12.961366)
		(end 93.761306 -12.400026)
		(stroke
			(width 0.2)
			(type default)
		)
		(layer "In1.Cu")
	)
	(gr_line
		(start 92.638626 -10.999978)
		(end 92.638626 -12.399772)
		(stroke
			(width 0.2)
			(type default)
		)
		(layer "In1.Cu")
	)
	(gr_arc
		(start 92.638626 -5.199888)
		(mid 93.199839 -5.761482)
		(end 93.761306 -5.200142)
		(stroke
			(width 0.2)
			(type default)
		)
		(layer "In1.Cu")
	)
	(gr_line
		(start 92.638626 -3.800094)
		(end 92.638626 -5.199888)
		(stroke
			(width 0.2)
			(type default)
		)
		(layer "In1.Cu")
	)
	(gr_line
		(start 93.761306 -12.400026)
		(end 93.761306 -10.999978)
		(stroke
			(width 0.2)
			(type default)
		)
		(layer "In1.Cu")
	)
	(gr_arc
		(start 93.761306 -10.999978)
		(mid 93.199966 -10.438638)
		(end 92.638626 -10.999978)
		(stroke
			(width 0.2)
			(type default)
		)
		(layer "In1.Cu")
	)
	(gr_line
		(start 93.761306 -5.200142)
		(end 93.761306 -3.800094)
		(stroke
			(width 0.2)
			(type default)
		)
		(layer "In1.Cu")
	)
	(gr_arc
		(start 93.761306 -3.800094)
		(mid 93.199966 -3.238754)
		(end 92.638626 -3.800094)
		(stroke
			(width 0.2)
			(type default)
		)
		(layer "In1.Cu")
	)
	(gr_arc
		(start 94.438724 -11.199876)
		(mid 94.999937 -11.76147)
		(end 95.561404 -11.20013)
		(stroke
			(width 0.2)
			(type default)
		)
		(layer "In1.Cu")
	)
	(gr_line
		(start 94.438724 -9.800082)
		(end 94.438724 -11.199876)
		(stroke
			(width 0.2)
			(type default)
		)
		(layer "In1.Cu")
	)
	(gr_arc
		(start 94.438724 -3.999738)
		(mid 94.999937 -4.561332)
		(end 95.561404 -3.999992)
		(stroke
			(width 0.2)
			(type default)
		)
		(layer "In1.Cu")
	)
	(gr_line
		(start 94.438724 -2.600198)
		(end 94.438724 -3.999738)
		(stroke
			(width 0.2)
			(type default)
		)
		(layer "In1.Cu")
	)
	(gr_line
		(start 95.561404 -11.20013)
		(end 95.561404 -9.800082)
		(stroke
			(width 0.2)
			(type default)
		)
		(layer "In1.Cu")
	)
	(gr_arc
		(start 95.561404 -9.800082)
		(mid 95.000064 -9.238742)
		(end 94.438724 -9.800082)
		(stroke
			(width 0.2)
			(type default)
		)
		(layer "In1.Cu")
	)
	(gr_line
		(start 95.561404 -3.999992)
		(end 95.561404 -2.600198)
		(stroke
			(width 0.2)
			(type default)
		)
		(layer "In1.Cu")
	)
	(gr_arc
		(start 95.561404 -2.600198)
		(mid 95.000064 -2.038858)
		(end 94.438724 -2.600198)
		(stroke
			(width 0.2)
			(type default)
		)
		(layer "In1.Cu")
	)
	(gr_arc
		(start 96.238822 -12.399772)
		(mid 96.800035 -12.961366)
		(end 97.361502 -12.400026)
		(stroke
			(width 0.2)
			(type default)
		)
		(layer "In1.Cu")
	)
	(gr_line
		(start 96.238822 -10.999978)
		(end 96.238822 -12.399772)
		(stroke
			(width 0.2)
			(type default)
		)
		(layer "In1.Cu")
	)
	(gr_arc
		(start 96.238822 -5.199888)
		(mid 96.800035 -5.761482)
		(end 97.361502 -5.200142)
		(stroke
			(width 0.2)
			(type default)
		)
		(layer "In1.Cu")
	)
	(gr_line
		(start 96.238822 -3.800094)
		(end 96.238822 -5.199888)
		(stroke
			(width 0.2)
			(type default)
		)
		(layer "In1.Cu")
	)
	(gr_line
		(start 97.361502 -12.400026)
		(end 97.361502 -10.999978)
		(stroke
			(width 0.2)
			(type default)
		)
		(layer "In1.Cu")
	)
	(gr_arc
		(start 97.361502 -10.999978)
		(mid 96.800162 -10.438638)
		(end 96.238822 -10.999978)
		(stroke
			(width 0.2)
			(type default)
		)
		(layer "In1.Cu")
	)
	(gr_line
		(start 97.361502 -5.200142)
		(end 97.361502 -3.800094)
		(stroke
			(width 0.2)
			(type default)
		)
		(layer "In1.Cu")
	)
	(gr_arc
		(start 97.361502 -3.800094)
		(mid 96.800162 -3.238754)
		(end 96.238822 -3.800094)
		(stroke
			(width 0.2)
			(type default)
		)
		(layer "In1.Cu")
	)
	(gr_line
		(start 97.499932 -126.000002)
		(end 89.212674 -127.325628)
		(stroke
			(width 1.524)
			(type default)
		)
		(layer "In1.Cu")
	)
	(gr_arc
		(start 98.038666 -11.199876)
		(mid 98.599879 -11.76147)
		(end 99.161346 -11.20013)
		(stroke
			(width 0.2)
			(type default)
		)
		(layer "In1.Cu")
	)
	(gr_line
		(start 98.038666 -9.800082)
		(end 98.038666 -11.199876)
		(stroke
			(width 0.2)
			(type default)
		)
		(layer "In1.Cu")
	)
	(gr_arc
		(start 98.038666 -3.999738)
		(mid 98.599879 -4.561332)
		(end 99.161346 -3.999992)
		(stroke
			(width 0.2)
			(type default)
		)
		(layer "In1.Cu")
	)
	(gr_line
		(start 98.038666 -2.600198)
		(end 98.038666 -3.999738)
		(stroke
			(width 0.2)
			(type default)
		)
		(layer "In1.Cu")
	)
	(gr_arc
		(start 98.641916 -54.99989)
		(mid 98.999929 -55.358284)
		(end 99.358196 -55.000144)
		(stroke
			(width 0.2)
			(type default)
		)
		(layer "In1.Cu")
	)
	(gr_line
		(start 98.641916 -54.000146)
		(end 98.641916 -54.99989)
		(stroke
			(width 0.2)
			(type default)
		)
		(layer "In1.Cu")
	)
	(gr_line
		(start 99.161346 -11.20013)
		(end 99.161346 -9.800082)
		(stroke
			(width 0.2)
			(type default)
		)
		(layer "In1.Cu")
	)
	(gr_arc
		(start 99.161346 -9.800082)
		(mid 98.600006 -9.238742)
		(end 98.038666 -9.800082)
		(stroke
			(width 0.2)
			(type default)
		)
		(layer "In1.Cu")
	)
	(gr_line
		(start 99.161346 -3.999992)
		(end 99.161346 -2.600198)
		(stroke
			(width 0.2)
			(type default)
		)
		(layer "In1.Cu")
	)
	(gr_arc
		(start 99.161346 -2.600198)
		(mid 98.600006 -2.038858)
		(end 98.038666 -2.600198)
		(stroke
			(width 0.2)
			(type default)
		)
		(layer "In1.Cu")
	)
	(gr_line
		(start 99.358196 -55.000144)
		(end 99.358196 -54.000146)
		(stroke
			(width 0.2)
			(type default)
		)
		(layer "In1.Cu")
	)
	(gr_arc
		(start 99.358196 -54.000146)
		(mid 99.000056 -53.642006)
		(end 98.641916 -54.000146)
		(stroke
			(width 0.2)
			(type default)
		)
		(layer "In1.Cu")
	)
	(gr_arc
		(start 99.641914 -51.999896)
		(mid 99.999927 -52.35829)
		(end 100.358194 -52.00015)
		(stroke
			(width 0.2)
			(type default)
		)
		(layer "In1.Cu")
	)
	(gr_line
		(start 99.641914 -51.000152)
		(end 99.641914 -51.999896)
		(stroke
			(width 0.2)
			(type default)
		)
		(layer "In1.Cu")
	)
	(gr_arc
		(start 99.838764 -12.399772)
		(mid 100.399977 -12.961366)
		(end 100.961444 -12.400026)
		(stroke
			(width 0.2)
			(type default)
		)
		(layer "In1.Cu")
	)
	(gr_line
		(start 99.838764 -10.999978)
		(end 99.838764 -12.399772)
		(stroke
			(width 0.2)
			(type default)
		)
		(layer "In1.Cu")
	)
	(gr_arc
		(start 99.838764 -5.199888)
		(mid 100.399977 -5.761482)
		(end 100.961444 -5.200142)
		(stroke
			(width 0.2)
			(type default)
		)
		(layer "In1.Cu")
	)
	(gr_line
		(start 99.838764 -3.800094)
		(end 99.838764 -5.199888)
		(stroke
			(width 0.2)
			(type default)
		)
		(layer "In1.Cu")
	)
	(gr_line
		(start 100.358194 -52.00015)
		(end 100.358194 -51.000152)
		(stroke
			(width 0.2)
			(type default)
		)
		(layer "In1.Cu")
	)
	(gr_arc
		(start 100.358194 -51.000152)
		(mid 100.000054 -50.642012)
		(end 99.641914 -51.000152)
		(stroke
			(width 0.2)
			(type default)
		)
		(layer "In1.Cu")
	)
	(gr_arc
		(start 100.641912 -55.999888)
		(mid 100.999925 -56.358282)
		(end 101.358192 -56.000142)
		(stroke
			(width 0.2)
			(type default)
		)
		(layer "In1.Cu")
	)
	(gr_line
		(start 100.641912 -55.000144)
		(end 100.641912 -55.999888)
		(stroke
			(width 0.2)
			(type default)
		)
		(layer "In1.Cu")
	)
	(gr_arc
		(start 100.641912 -52.999894)
		(mid 100.999925 -53.358288)
		(end 101.358192 -53.000148)
		(stroke
			(width 0.2)
			(type default)
		)
		(layer "In1.Cu")
	)
	(gr_line
		(start 100.641912 -52.00015)
		(end 100.641912 -52.999894)
		(stroke
			(width 0.2)
			(type default)
		)
		(layer "In1.Cu")
	)
	(gr_line
		(start 100.961444 -12.400026)
		(end 100.961444 -10.999978)
		(stroke
			(width 0.2)
			(type default)
		)
		(layer "In1.Cu")
	)
	(gr_arc
		(start 100.961444 -10.999978)
		(mid 100.400104 -10.438638)
		(end 99.838764 -10.999978)
		(stroke
			(width 0.2)
			(type default)
		)
		(layer "In1.Cu")
	)
	(gr_line
		(start 100.961444 -5.200142)
		(end 100.961444 -3.800094)
		(stroke
			(width 0.2)
			(type default)
		)
		(layer "In1.Cu")
	)
	(gr_arc
		(start 100.961444 -3.800094)
		(mid 100.400104 -3.238754)
		(end 99.838764 -3.800094)
		(stroke
			(width 0.2)
			(type default)
		)
		(layer "In1.Cu")
	)
	(gr_line
		(start 101.358192 -56.000142)
		(end 101.358192 -55.000144)
		(stroke
			(width 0.2)
			(type default)
		)
		(layer "In1.Cu")
	)
	(gr_arc
		(start 101.358192 -55.000144)
		(mid 101.000052 -54.642004)
		(end 100.641912 -55.000144)
		(stroke
			(width 0.2)
			(type default)
		)
		(layer "In1.Cu")
	)
	(gr_line
		(start 101.358192 -53.000148)
		(end 101.358192 -52.00015)
		(stroke
			(width 0.2)
			(type default)
		)
		(layer "In1.Cu")
	)
	(gr_arc
		(start 101.358192 -52.00015)
		(mid 101.000052 -51.64201)
		(end 100.641912 -52.00015)
		(stroke
			(width 0.2)
			(type default)
		)
		(layer "In1.Cu")
	)
	(gr_arc
		(start 101.638862 -11.199876)
		(mid 102.200075 -11.76147)
		(end 102.761542 -11.20013)
		(stroke
			(width 0.2)
			(type default)
		)
		(layer "In1.Cu")
	)
	(gr_line
		(start 101.638862 -9.800082)
		(end 101.638862 -11.199876)
		(stroke
			(width 0.2)
			(type default)
		)
		(layer "In1.Cu")
	)
	(gr_arc
		(start 101.638862 -3.999738)
		(mid 102.200075 -4.561332)
		(end 102.761542 -3.999992)
		(stroke
			(width 0.2)
			(type default)
		)
		(layer "In1.Cu")
	)
	(gr_line
		(start 101.638862 -2.600198)
		(end 101.638862 -3.999738)
		(stroke
			(width 0.2)
			(type default)
		)
		(layer "In1.Cu")
	)
	(gr_arc
		(start 101.64191 -55.999888)
		(mid 101.999923 -56.358282)
		(end 102.35819 -56.000142)
		(stroke
			(width 0.2)
			(type default)
		)
		(layer "In1.Cu")
	)
	(gr_line
		(start 101.64191 -55.000144)
		(end 101.64191 -55.999888)
		(stroke
			(width 0.2)
			(type default)
		)
		(layer "In1.Cu")
	)
	(gr_arc
		(start 101.64191 -51.999896)
		(mid 101.999923 -52.35829)
		(end 102.35819 -52.00015)
		(stroke
			(width 0.2)
			(type default)
		)
		(layer "In1.Cu")
	)
	(gr_line
		(start 101.64191 -51.000152)
		(end 101.64191 -51.999896)
		(stroke
			(width 0.2)
			(type default)
		)
		(layer "In1.Cu")
	)
	(gr_arc
		(start 102.266496 -115.990878)
		(mid 102.491032 -116.733574)
		(end 103.233728 -116.509038)
		(stroke
			(width 0.2)
			(type default)
		)
		(layer "In1.Cu")
	)
	(gr_line
		(start 102.266496 -115.990624)
		(end 102.266496 -115.990878)
		(stroke
			(width 0.2)
			(type default)
		)
		(layer "In1.Cu")
	)
	(gr_arc
		(start 102.266496 -112.191038)
		(mid 102.491032 -112.933734)
		(end 103.233728 -112.709198)
		(stroke
			(width 0.2)
			(type default)
		)
		(layer "In1.Cu")
	)
	(gr_line
		(start 102.266496 -112.190784)
		(end 102.266496 -112.191038)
		(stroke
			(width 0.2)
			(type default)
		)
		(layer "In1.Cu")
	)
	(gr_line
		(start 102.311454 -108.415074)
		(end 102.311962 -108.415328)
		(stroke
			(width 0.2)
			(type default)
		)
		(layer "In1.Cu")
	)
	(gr_line
		(start 102.311454 -108.41482)
		(end 102.311454 -108.415074)
		(stroke
			(width 0.2)
			(type default)
		)
		(layer "In1.Cu")
	)
	(gr_line
		(start 102.311454 -104.61498)
		(end 102.311962 -104.615234)
		(stroke
			(width 0.2)
			(type default)
		)
		(layer "In1.Cu")
	)
	(gr_line
		(start 102.311454 -104.614726)
		(end 102.311454 -104.61498)
		(stroke
			(width 0.2)
			(type default)
		)
		(layer "In1.Cu")
	)
	(gr_arc
		(start 102.311962 -108.415328)
		(mid 102.515416 -109.088174)
		(end 103.188262 -108.88472)
		(stroke
			(width 0.2)
			(type default)
		)
		(layer "In1.Cu")
	)
	(gr_arc
		(start 102.311962 -104.615234)
		(mid 102.515416 -105.28808)
		(end 103.188262 -105.084626)
		(stroke
			(width 0.2)
			(type default)
		)
		(layer "In1.Cu")
	)
	(gr_line
		(start 102.35819 -56.000142)
		(end 102.35819 -55.000144)
		(stroke
			(width 0.2)
			(type default)
		)
		(layer "In1.Cu")
	)
	(gr_arc
		(start 102.35819 -55.000144)
		(mid 102.00005 -54.642004)
		(end 101.64191 -55.000144)
		(stroke
			(width 0.2)
			(type default)
		)
		(layer "In1.Cu")
	)
	(gr_line
		(start 102.35819 -52.00015)
		(end 102.35819 -51.000152)
		(stroke
			(width 0.2)
			(type default)
		)
		(layer "In1.Cu")
	)
	(gr_arc
		(start 102.35819 -51.000152)
		(mid 102.00005 -50.642012)
		(end 101.64191 -51.000152)
		(stroke
			(width 0.2)
			(type default)
		)
		(layer "In1.Cu")
	)
	(gr_arc
		(start 102.641908 -55.999888)
		(mid 102.999921 -56.358282)
		(end 103.358188 -56.000142)
		(stroke
			(width 0.2)
			(type default)
		)
		(layer "In1.Cu")
	)
	(gr_line
		(start 102.641908 -55.000144)
		(end 102.641908 -55.999888)
		(stroke
			(width 0.2)
			(type default)
		)
		(layer "In1.Cu")
	)
	(gr_arc
		(start 102.641908 -52.999894)
		(mid 102.999921 -53.358288)
		(end 103.358188 -53.000148)
		(stroke
			(width 0.2)
			(type default)
		)
		(layer "In1.Cu")
	)
	(gr_line
		(start 102.641908 -52.00015)
		(end 102.641908 -52.999894)
		(stroke
			(width 0.2)
			(type default)
		)
		(layer "In1.Cu")
	)
	(gr_line
		(start 102.761542 -11.20013)
		(end 102.761542 -9.800082)
		(stroke
			(width 0.2)
			(type default)
		)
		(layer "In1.Cu")
	)
	(gr_arc
		(start 102.761542 -9.800082)
		(mid 102.200202 -9.238742)
		(end 101.638862 -9.800082)
		(stroke
			(width 0.2)
			(type default)
		)
		(layer "In1.Cu")
	)
	(gr_line
		(start 102.761542 -3.999992)
		(end 102.761542 -2.600198)
		(stroke
			(width 0.2)
			(type default)
		)
		(layer "In1.Cu")
	)
	(gr_arc
		(start 102.761542 -2.600198)
		(mid 102.200202 -2.038858)
		(end 101.638862 -2.600198)
		(stroke
			(width 0.2)
			(type default)
		)
		(layer "In1.Cu")
	)
	(gr_line
		(start 103.016304 -114.59083)
		(end 102.266496 -115.990624)
		(stroke
			(width 0.2)
			(type default)
		)
		(layer "In1.Cu")
	)
	(gr_line
		(start 103.016304 -110.79099)
		(end 102.266496 -112.190784)
		(stroke
			(width 0.2)
			(type default)
		)
		(layer "In1.Cu")
	)
	(gr_line
		(start 103.061008 -107.015026)
		(end 102.311454 -108.41482)
		(stroke
			(width 0.2)
			(type default)
		)
		(layer "In1.Cu")
	)
	(gr_line
		(start 103.061008 -103.215186)
		(end 102.311454 -104.614726)
		(stroke
			(width 0.2)
			(type default)
		)
		(layer "In1.Cu")
	)
	(gr_line
		(start 103.06177 -107.01528)
		(end 103.061008 -107.015026)
		(stroke
			(width 0.2)
			(type default)
		)
		(layer "In1.Cu")
	)
	(gr_line
		(start 103.06177 -103.21544)
		(end 103.061008 -103.215186)
		(stroke
			(width 0.2)
			(type default)
		)
		(layer "In1.Cu")
	)
	(gr_line
		(start 103.188262 -108.88472)
		(end 103.189024 -108.884974)
		(stroke
			(width 0.2)
			(type default)
		)
		(layer "In1.Cu")
	)
	(gr_line
		(start 103.188262 -105.084626)
		(end 103.189024 -105.08488)
		(stroke
			(width 0.2)
			(type default)
		)
		(layer "In1.Cu")
	)
	(gr_line
		(start 103.189024 -108.884974)
		(end 103.938832 -107.484926)
		(stroke
			(width 0.2)
			(type default)
		)
		(layer "In1.Cu")
	)
	(gr_line
		(start 103.189024 -105.08488)
		(end 103.938832 -103.685086)
		(stroke
			(width 0.2)
			(type default)
		)
		(layer "In1.Cu")
	)
	(gr_line
		(start 103.233728 -116.509038)
		(end 103.983536 -115.10899)
		(stroke
			(width 0.2)
			(type default)
		)
		(layer "In1.Cu")
	)
	(gr_line
		(start 103.233728 -112.709198)
		(end 103.983536 -111.30915)
		(stroke
			(width 0.2)
			(type default)
		)
		(layer "In1.Cu")
	)
	(gr_line
		(start 103.358188 -56.000142)
		(end 103.358188 -55.000144)
		(stroke
			(width 0.2)
			(type default)
		)
		(layer "In1.Cu")
	)
	(gr_arc
		(start 103.358188 -55.000144)
		(mid 103.000048 -54.642004)
		(end 102.641908 -55.000144)
		(stroke
			(width 0.2)
			(type default)
		)
		(layer "In1.Cu")
	)
	(gr_line
		(start 103.358188 -53.000148)
		(end 103.358188 -52.00015)
		(stroke
			(width 0.2)
			(type default)
		)
		(layer "In1.Cu")
	)
	(gr_arc
		(start 103.358188 -52.00015)
		(mid 103.000048 -51.64201)
		(end 102.641908 -52.00015)
		(stroke
			(width 0.2)
			(type default)
		)
		(layer "In1.Cu")
	)
	(gr_arc
		(start 103.438706 -12.399772)
		(mid 103.999919 -12.961366)
		(end 104.561386 -12.400026)
		(stroke
			(width 0.2)
			(type default)
		)
		(layer "In1.Cu")
	)
	(gr_line
		(start 103.438706 -10.999978)
		(end 103.438706 -12.399772)
		(stroke
			(width 0.2)
			(type default)
		)
		(layer "In1.Cu")
	)
	(gr_arc
		(start 103.438706 -5.199888)
		(mid 103.999919 -5.761482)
		(end 104.561386 -5.200142)
		(stroke
			(width 0.2)
			(type default)
		)
		(layer "In1.Cu")
	)
	(gr_line
		(start 103.438706 -3.800094)
		(end 103.438706 -5.199888)
		(stroke
			(width 0.2)
			(type default)
		)
		(layer "In1.Cu")
	)
	(gr_arc
		(start 103.641906 -55.999888)
		(mid 103.999919 -56.358282)
		(end 104.358186 -56.000142)
		(stroke
			(width 0.2)
			(type default)
		)
		(layer "In1.Cu")
	)
	(gr_line
		(start 103.641906 -55.000144)
		(end 103.641906 -55.999888)
		(stroke
			(width 0.2)
			(type default)
		)
		(layer "In1.Cu")
	)
	(gr_arc
		(start 103.641906 -51.999896)
		(mid 103.999919 -52.35829)
		(end 104.358186 -52.00015)
		(stroke
			(width 0.2)
			(type default)
		)
		(layer "In1.Cu")
	)
	(gr_line
		(start 103.641906 -51.000152)
		(end 103.641906 -51.999896)
		(stroke
			(width 0.2)
			(type default)
		)
		(layer "In1.Cu")
	)
	(gr_arc
		(start 103.93807 -107.484672)
		(mid 103.734616 -106.811826)
		(end 103.06177 -107.01528)
		(stroke
			(width 0.2)
			(type default)
		)
		(layer "In1.Cu")
	)
	(gr_arc
		(start 103.93807 -103.684832)
		(mid 103.734616 -103.011986)
		(end 103.06177 -103.21544)
		(stroke
			(width 0.2)
			(type default)
		)
		(layer "In1.Cu")
	)
	(gr_line
		(start 103.938832 -107.484926)
		(end 103.93807 -107.484672)
		(stroke
			(width 0.2)
			(type default)
		)
		(layer "In1.Cu")
	)
	(gr_line
		(start 103.938832 -103.685086)
		(end 103.93807 -103.684832)
		(stroke
			(width 0.2)
			(type default)
		)
		(layer "In1.Cu")
	)
	(gr_arc
		(start 103.983536 -115.10899)
		(mid 103.759 -114.366294)
		(end 103.016304 -114.59083)
		(stroke
			(width 0.2)
			(type default)
		)
		(layer "In1.Cu")
	)
	(gr_arc
		(start 103.983536 -111.30915)
		(mid 103.759 -110.566454)
		(end 103.016304 -110.79099)
		(stroke
			(width 0.2)
			(type default)
		)
		(layer "In1.Cu")
	)
	(gr_line
		(start 104.358186 -56.000142)
		(end 104.358186 -55.000144)
		(stroke
			(width 0.2)
			(type default)
		)
		(layer "In1.Cu")
	)
	(gr_arc
		(start 104.358186 -55.000144)
		(mid 104.000046 -54.642004)
		(end 103.641906 -55.000144)
		(stroke
			(width 0.2)
			(type default)
		)
		(layer "In1.Cu")
	)
	(gr_line
		(start 104.358186 -52.00015)
		(end 104.358186 -51.000152)
		(stroke
			(width 0.2)
			(type default)
		)
		(layer "In1.Cu")
	)
	(gr_arc
		(start 104.358186 -51.000152)
		(mid 104.000046 -50.642012)
		(end 103.641906 -51.000152)
		(stroke
			(width 0.2)
			(type default)
		)
		(layer "In1.Cu")
	)
	(gr_arc
		(start 104.516428 -115.990624)
		(mid 104.740809 -116.733627)
		(end 105.48366 -116.509038)
		(stroke
			(width 0.2)
			(type default)
		)
		(layer "In1.Cu")
	)
	(gr_arc
		(start 104.516428 -112.190784)
		(mid 104.740809 -112.933787)
		(end 105.48366 -112.709198)
		(stroke
			(width 0.2)
			(type default)
		)
		(layer "In1.Cu")
	)
	(gr_line
		(start 104.561386 -108.415074)
		(end 104.561894 -108.415328)
		(stroke
			(width 0.2)
			(type default)
		)
		(layer "In1.Cu")
	)
	(gr_line
		(start 104.561386 -108.41482)
		(end 104.561386 -108.415074)
		(stroke
			(width 0.2)
			(type default)
		)
		(layer "In1.Cu")
	)
	(gr_line
		(start 104.561386 -104.61498)
		(end 104.561894 -104.615234)
		(stroke
			(width 0.2)
			(type default)
		)
		(layer "In1.Cu")
	)
	(gr_line
		(start 104.561386 -104.614472)
		(end 104.561386 -104.61498)
		(stroke
			(width 0.2)
			(type default)
		)
		(layer "In1.Cu")
	)
	(gr_line
		(start 104.561386 -12.400026)
		(end 104.561386 -10.999978)
		(stroke
			(width 0.2)
			(type default)
		)
		(layer "In1.Cu")
	)
	(gr_arc
		(start 104.561386 -10.999978)
		(mid 104.000046 -10.438638)
		(end 103.438706 -10.999978)
		(stroke
			(width 0.2)
			(type default)
		)
		(layer "In1.Cu")
	)
	(gr_line
		(start 104.561386 -5.200142)
		(end 104.561386 -3.800094)
		(stroke
			(width 0.2)
			(type default)
		)
		(layer "In1.Cu")
	)
	(gr_arc
		(start 104.561386 -3.800094)
		(mid 104.000046 -3.238754)
		(end 103.438706 -3.800094)
		(stroke
			(width 0.2)
			(type default)
		)
		(layer "In1.Cu")
	)
	(gr_arc
		(start 104.561894 -108.415328)
		(mid 104.765348 -109.088174)
		(end 105.438194 -108.88472)
		(stroke
			(width 0.2)
			(type default)
		)
		(layer "In1.Cu")
	)
	(gr_arc
		(start 104.561894 -104.615234)
		(mid 104.765348 -105.28808)
		(end 105.438194 -105.084626)
		(stroke
			(width 0.2)
			(type default)
		)
		(layer "In1.Cu")
	)
	(gr_arc
		(start 104.641904 -55.999888)
		(mid 104.999917 -56.358282)
		(end 105.358184 -56.000142)
		(stroke
			(width 0.2)
			(type default)
		)
		(layer "In1.Cu")
	)
	(gr_line
		(start 104.641904 -55.000144)
		(end 104.641904 -55.999888)
		(stroke
			(width 0.2)
			(type default)
		)
		(layer "In1.Cu")
	)
	(gr_arc
		(start 104.641904 -52.999894)
		(mid 104.999917 -53.358288)
		(end 105.358184 -53.000148)
		(stroke
			(width 0.2)
			(type default)
		)
		(layer "In1.Cu")
	)
	(gr_line
		(start 104.641904 -52.00015)
		(end 104.641904 -52.999894)
		(stroke
			(width 0.2)
			(type default)
		)
		(layer "In1.Cu")
	)
	(gr_arc
		(start 105.238804 -11.199876)
		(mid 105.800017 -11.76147)
		(end 106.361484 -11.20013)
		(stroke
			(width 0.2)
			(type default)
		)
		(layer "In1.Cu")
	)
	(gr_line
		(start 105.238804 -9.800082)
		(end 105.238804 -11.199876)
		(stroke
			(width 0.2)
			(type default)
		)
		(layer "In1.Cu")
	)
	(gr_arc
		(start 105.238804 -3.999738)
		(mid 105.800017 -4.561332)
		(end 106.361484 -3.999992)
		(stroke
			(width 0.2)
			(type default)
		)
		(layer "In1.Cu")
	)
	(gr_line
		(start 105.238804 -2.600198)
		(end 105.238804 -3.999738)
		(stroke
			(width 0.2)
			(type default)
		)
		(layer "In1.Cu")
	)
	(gr_line
		(start 105.26649 -114.59083)
		(end 104.516428 -115.990624)
		(stroke
			(width 0.2)
			(type default)
		)
		(layer "In1.Cu")
	)
	(gr_line
		(start 105.26649 -110.79099)
		(end 104.516428 -112.190784)
		(stroke
			(width 0.2)
			(type default)
		)
		(layer "In1.Cu")
	)
	(gr_line
		(start 105.311194 -107.014772)
		(end 104.561386 -108.41482)
		(stroke
			(width 0.2)
			(type default)
		)
		(layer "In1.Cu")
	)
	(gr_line
		(start 105.311194 -103.214932)
		(end 104.561386 -104.614472)
		(stroke
			(width 0.2)
			(type default)
		)
		(layer "In1.Cu")
	)
	(gr_line
		(start 105.311956 -107.01528)
		(end 105.311194 -107.014772)
		(stroke
			(width 0.2)
			(type default)
		)
		(layer "In1.Cu")
	)
	(gr_line
		(start 105.311956 -103.21544)
		(end 105.311194 -103.214932)
		(stroke
			(width 0.2)
			(type default)
		)
		(layer "In1.Cu")
	)
	(gr_line
		(start 105.358184 -56.000142)
		(end 105.358184 -55.000144)
		(stroke
			(width 0.2)
			(type default)
		)
		(layer "In1.Cu")
	)
	(gr_arc
		(start 105.358184 -55.000144)
		(mid 105.000044 -54.642004)
		(end 104.641904 -55.000144)
		(stroke
			(width 0.2)
			(type default)
		)
		(layer "In1.Cu")
	)
	(gr_line
		(start 105.358184 -53.000148)
		(end 105.358184 -52.00015)
		(stroke
			(width 0.2)
			(type default)
		)
		(layer "In1.Cu")
	)
	(gr_arc
		(start 105.358184 -52.00015)
		(mid 105.000044 -51.64201)
		(end 104.641904 -52.00015)
		(stroke
			(width 0.2)
			(type default)
		)
		(layer "In1.Cu")
	)
	(gr_line
		(start 105.438194 -108.88472)
		(end 105.438956 -108.885228)
		(stroke
			(width 0.2)
			(type default)
		)
		(layer "In1.Cu")
	)
	(gr_line
		(start 105.438194 -105.084626)
		(end 105.438956 -105.085134)
		(stroke
			(width 0.2)
			(type default)
		)
		(layer "In1.Cu")
	)
	(gr_line
		(start 105.438956 -108.885228)
		(end 106.189018 -107.48518)
		(stroke
			(width 0.2)
			(type default)
		)
		(layer "In1.Cu")
	)
	(gr_line
		(start 105.438956 -105.085134)
		(end 106.189018 -103.68534)
		(stroke
			(width 0.2)
			(type default)
		)
		(layer "In1.Cu")
	)
	(gr_line
		(start 105.48366 -116.509038)
		(end 106.233722 -115.10899)
		(stroke
			(width 0.2)
			(type default)
		)
		(layer "In1.Cu")
	)
	(gr_line
		(start 105.48366 -112.709198)
		(end 106.233722 -111.30915)
		(stroke
			(width 0.2)
			(type default)
		)
		(layer "In1.Cu")
	)
	(gr_arc
		(start 105.641902 -55.999888)
		(mid 105.999915 -56.358282)
		(end 106.358182 -56.000142)
		(stroke
			(width 0.2)
			(type default)
		)
		(layer "In1.Cu")
	)
	(gr_line
		(start 105.641902 -55.000144)
		(end 105.641902 -55.999888)
		(stroke
			(width 0.2)
			(type default)
		)
		(layer "In1.Cu")
	)
	(gr_arc
		(start 105.641902 -51.999896)
		(mid 105.999915 -52.35829)
		(end 106.358182 -52.00015)
		(stroke
			(width 0.2)
			(type default)
		)
		(layer "In1.Cu")
	)
	(gr_line
		(start 105.641902 -51.000152)
		(end 105.641902 -51.999896)
		(stroke
			(width 0.2)
			(type default)
		)
		(layer "In1.Cu")
	)
	(gr_arc
		(start 106.188256 -107.484672)
		(mid 105.984802 -106.811826)
		(end 105.311956 -107.01528)
		(stroke
			(width 0.2)
			(type default)
		)
		(layer "In1.Cu")
	)
	(gr_arc
		(start 106.188256 -103.684832)
		(mid 105.984802 -103.011986)
		(end 105.311956 -103.21544)
		(stroke
			(width 0.2)
			(type default)
		)
		(layer "In1.Cu")
	)
	(gr_line
		(start 106.189018 -107.48518)
		(end 106.188256 -107.484672)
		(stroke
			(width 0.2)
			(type default)
		)
		(layer "In1.Cu")
	)
	(gr_line
		(start 106.189018 -103.68534)
		(end 106.188256 -103.684832)
		(stroke
			(width 0.2)
			(type default)
		)
		(layer "In1.Cu")
	)
	(gr_arc
		(start 106.233722 -115.10899)
		(mid 106.009186 -114.366294)
		(end 105.26649 -114.59083)
		(stroke
			(width 0.2)
			(type default)
		)
		(layer "In1.Cu")
	)
	(gr_arc
		(start 106.233722 -111.30915)
		(mid 106.009186 -110.566454)
		(end 105.26649 -110.79099)
		(stroke
			(width 0.2)
			(type default)
		)
		(layer "In1.Cu")
	)
	(gr_line
		(start 106.358182 -56.000142)
		(end 106.358182 -55.000144)
		(stroke
			(width 0.2)
			(type default)
		)
		(layer "In1.Cu")
	)
	(gr_arc
		(start 106.358182 -55.000144)
		(mid 106.000042 -54.642004)
		(end 105.641902 -55.000144)
		(stroke
			(width 0.2)
			(type default)
		)
		(layer "In1.Cu")
	)
	(gr_line
		(start 106.358182 -52.00015)
		(end 106.358182 -51.000152)
		(stroke
			(width 0.2)
			(type default)
		)
		(layer "In1.Cu")
	)
	(gr_arc
		(start 106.358182 -51.000152)
		(mid 106.000042 -50.642012)
		(end 105.641902 -51.000152)
		(stroke
			(width 0.2)
			(type default)
		)
		(layer "In1.Cu")
	)
	(gr_line
		(start 106.361484 -11.20013)
		(end 106.361484 -9.800082)
		(stroke
			(width 0.2)
			(type default)
		)
		(layer "In1.Cu")
	)
	(gr_arc
		(start 106.361484 -9.800082)
		(mid 105.800144 -9.238742)
		(end 105.238804 -9.800082)
		(stroke
			(width 0.2)
			(type default)
		)
		(layer "In1.Cu")
	)
	(gr_line
		(start 106.361484 -3.999992)
		(end 106.361484 -2.600198)
		(stroke
			(width 0.2)
			(type default)
		)
		(layer "In1.Cu")
	)
	(gr_arc
		(start 106.361484 -2.600198)
		(mid 105.800144 -2.038858)
		(end 105.238804 -2.600198)
		(stroke
			(width 0.2)
			(type default)
		)
		(layer "In1.Cu")
	)
	(gr_arc
		(start 106.6419 -55.999888)
		(mid 106.999913 -56.358282)
		(end 107.35818 -56.000142)
		(stroke
			(width 0.2)
			(type default)
		)
		(layer "In1.Cu")
	)
	(gr_line
		(start 106.6419 -55.000144)
		(end 106.6419 -55.999888)
		(stroke
			(width 0.2)
			(type default)
		)
		(layer "In1.Cu")
	)
	(gr_arc
		(start 106.6419 -52.999894)
		(mid 106.999913 -53.358288)
		(end 107.35818 -53.000148)
		(stroke
			(width 0.2)
			(type default)
		)
		(layer "In1.Cu")
	)
	(gr_line
		(start 106.6419 -52.00015)
		(end 106.6419 -52.999894)
		(stroke
			(width 0.2)
			(type default)
		)
		(layer "In1.Cu")
	)
	(gr_arc
		(start 107.038648 -12.399772)
		(mid 107.599861 -12.961366)
		(end 108.161328 -12.400026)
		(stroke
			(width 0.2)
			(type default)
		)
		(layer "In1.Cu")
	)
	(gr_line
		(start 107.038648 -10.999978)
		(end 107.038648 -12.399772)
		(stroke
			(width 0.2)
			(type default)
		)
		(layer "In1.Cu")
	)
	(gr_arc
		(start 107.038648 -5.199888)
		(mid 107.599861 -5.761482)
		(end 108.161328 -5.200142)
		(stroke
			(width 0.2)
			(type default)
		)
		(layer "In1.Cu")
	)
	(gr_line
		(start 107.038648 -3.800094)
		(end 107.038648 -5.199888)
		(stroke
			(width 0.2)
			(type default)
		)
		(layer "In1.Cu")
	)
	(gr_line
		(start 107.35818 -56.000142)
		(end 107.35818 -55.000144)
		(stroke
			(width 0.2)
			(type default)
		)
		(layer "In1.Cu")
	)
	(gr_arc
		(start 107.35818 -55.000144)
		(mid 107.00004 -54.642004)
		(end 106.6419 -55.000144)
		(stroke
			(width 0.2)
			(type default)
		)
		(layer "In1.Cu")
	)
	(gr_line
		(start 107.35818 -53.000148)
		(end 107.35818 -52.00015)
		(stroke
			(width 0.2)
			(type default)
		)
		(layer "In1.Cu")
	)
	(gr_arc
		(start 107.35818 -52.00015)
		(mid 107.00004 -51.64201)
		(end 106.6419 -52.00015)
		(stroke
			(width 0.2)
			(type default)
		)
		(layer "In1.Cu")
	)
	(gr_arc
		(start 107.641898 -55.999888)
		(mid 107.999911 -56.358282)
		(end 108.358178 -56.000142)
		(stroke
			(width 0.2)
			(type default)
		)
		(layer "In1.Cu")
	)
	(gr_line
		(start 107.641898 -55.000144)
		(end 107.641898 -55.999888)
		(stroke
			(width 0.2)
			(type default)
		)
		(layer "In1.Cu")
	)
	(gr_arc
		(start 107.641898 -51.999896)
		(mid 107.999911 -52.35829)
		(end 108.358178 -52.00015)
		(stroke
			(width 0.2)
			(type default)
		)
		(layer "In1.Cu")
	)
	(gr_line
		(start 107.641898 -51.000152)
		(end 107.641898 -51.999896)
		(stroke
			(width 0.2)
			(type default)
		)
		(layer "In1.Cu")
	)
	(gr_line
		(start 108.161328 -12.400026)
		(end 108.161328 -10.999978)
		(stroke
			(width 0.2)
			(type default)
		)
		(layer "In1.Cu")
	)
	(gr_arc
		(start 108.161328 -10.999978)
		(mid 107.599988 -10.438638)
		(end 107.038648 -10.999978)
		(stroke
			(width 0.2)
			(type default)
		)
		(layer "In1.Cu")
	)
	(gr_line
		(start 108.161328 -5.200142)
		(end 108.161328 -3.800094)
		(stroke
			(width 0.2)
			(type default)
		)
		(layer "In1.Cu")
	)
	(gr_arc
		(start 108.161328 -3.800094)
		(mid 107.599988 -3.238754)
		(end 107.038648 -3.800094)
		(stroke
			(width 0.2)
			(type default)
		)
		(layer "In1.Cu")
	)
	(gr_line
		(start 108.358178 -56.000142)
		(end 108.358178 -55.000144)
		(stroke
			(width 0.2)
			(type default)
		)
		(layer "In1.Cu")
	)
	(gr_arc
		(start 108.358178 -55.000144)
		(mid 108.000038 -54.642004)
		(end 107.641898 -55.000144)
		(stroke
			(width 0.2)
			(type default)
		)
		(layer "In1.Cu")
	)
	(gr_line
		(start 108.358178 -52.00015)
		(end 108.358178 -51.000152)
		(stroke
			(width 0.2)
			(type default)
		)
		(layer "In1.Cu")
	)
	(gr_arc
		(start 108.358178 -51.000152)
		(mid 108.000038 -50.642012)
		(end 107.641898 -51.000152)
		(stroke
			(width 0.2)
			(type default)
		)
		(layer "In1.Cu")
	)
	(gr_arc
		(start 108.641896 -55.999888)
		(mid 108.999909 -56.358282)
		(end 109.358176 -56.000142)
		(stroke
			(width 0.2)
			(type default)
		)
		(layer "In1.Cu")
	)
	(gr_line
		(start 108.641896 -55.000144)
		(end 108.641896 -55.999888)
		(stroke
			(width 0.2)
			(type default)
		)
		(layer "In1.Cu")
	)
	(gr_arc
		(start 108.641896 -52.999894)
		(mid 108.999909 -53.358288)
		(end 109.358176 -53.000148)
		(stroke
			(width 0.2)
			(type default)
		)
		(layer "In1.Cu")
	)
	(gr_line
		(start 108.641896 -52.00015)
		(end 108.641896 -52.999894)
		(stroke
			(width 0.2)
			(type default)
		)
		(layer "In1.Cu")
	)
	(gr_arc
		(start 108.838746 -11.199876)
		(mid 109.399959 -11.76147)
		(end 109.961426 -11.20013)
		(stroke
			(width 0.2)
			(type default)
		)
		(layer "In1.Cu")
	)
	(gr_line
		(start 108.838746 -9.800082)
		(end 108.838746 -11.199876)
		(stroke
			(width 0.2)
			(type default)
		)
		(layer "In1.Cu")
	)
	(gr_arc
		(start 108.838746 -3.999738)
		(mid 109.399959 -4.561332)
		(end 109.961426 -3.999992)
		(stroke
			(width 0.2)
			(type default)
		)
		(layer "In1.Cu")
	)
	(gr_line
		(start 108.838746 -2.600198)
		(end 108.838746 -3.999738)
		(stroke
			(width 0.2)
			(type default)
		)
		(layer "In1.Cu")
	)
	(gr_line
		(start 109.358176 -56.000142)
		(end 109.358176 -55.000144)
		(stroke
			(width 0.2)
			(type default)
		)
		(layer "In1.Cu")
	)
	(gr_arc
		(start 109.358176 -55.000144)
		(mid 109.000036 -54.642004)
		(end 108.641896 -55.000144)
		(stroke
			(width 0.2)
			(type default)
		)
		(layer "In1.Cu")
	)
	(gr_line
		(start 109.358176 -53.000148)
		(end 109.358176 -52.00015)
		(stroke
			(width 0.2)
			(type default)
		)
		(layer "In1.Cu")
	)
	(gr_arc
		(start 109.358176 -52.00015)
		(mid 109.000036 -51.64201)
		(end 108.641896 -52.00015)
		(stroke
			(width 0.2)
			(type default)
		)
		(layer "In1.Cu")
	)
	(gr_arc
		(start 109.641894 -55.999888)
		(mid 109.999907 -56.358282)
		(end 110.358174 -56.000142)
		(stroke
			(width 0.2)
			(type default)
		)
		(layer "In1.Cu")
	)
	(gr_line
		(start 109.641894 -55.000144)
		(end 109.641894 -55.999888)
		(stroke
			(width 0.2)
			(type default)
		)
		(layer "In1.Cu")
	)
	(gr_arc
		(start 109.641894 -51.999896)
		(mid 109.999907 -52.35829)
		(end 110.358174 -52.00015)
		(stroke
			(width 0.2)
			(type default)
		)
		(layer "In1.Cu")
	)
	(gr_line
		(start 109.641894 -51.000152)
		(end 109.641894 -51.999896)
		(stroke
			(width 0.2)
			(type default)
		)
		(layer "In1.Cu")
	)
	(gr_line
		(start 109.961426 -11.20013)
		(end 109.961426 -9.800082)
		(stroke
			(width 0.2)
			(type default)
		)
		(layer "In1.Cu")
	)
	(gr_arc
		(start 109.961426 -9.800082)
		(mid 109.400086 -9.238742)
		(end 108.838746 -9.800082)
		(stroke
			(width 0.2)
			(type default)
		)
		(layer "In1.Cu")
	)
	(gr_line
		(start 109.961426 -3.999992)
		(end 109.961426 -2.600198)
		(stroke
			(width 0.2)
			(type default)
		)
		(layer "In1.Cu")
	)
	(gr_arc
		(start 109.961426 -2.600198)
		(mid 109.400086 -2.038858)
		(end 108.838746 -2.600198)
		(stroke
			(width 0.2)
			(type default)
		)
		(layer "In1.Cu")
	)
	(gr_line
		(start 110.358174 -56.000142)
		(end 110.358174 -55.000144)
		(stroke
			(width 0.2)
			(type default)
		)
		(layer "In1.Cu")
	)
	(gr_arc
		(start 110.358174 -55.000144)
		(mid 110.000034 -54.642004)
		(end 109.641894 -55.000144)
		(stroke
			(width 0.2)
			(type default)
		)
		(layer "In1.Cu")
	)
	(gr_line
		(start 110.358174 -52.00015)
		(end 110.358174 -51.000152)
		(stroke
			(width 0.2)
			(type default)
		)
		(layer "In1.Cu")
	)
	(gr_arc
		(start 110.358174 -51.000152)
		(mid 110.000034 -50.642012)
		(end 109.641894 -51.000152)
		(stroke
			(width 0.2)
			(type default)
		)
		(layer "In1.Cu")
	)
	(gr_arc
		(start 110.638844 -12.399772)
		(mid 111.200057 -12.961366)
		(end 111.761524 -12.400026)
		(stroke
			(width 0.2)
			(type default)
		)
		(layer "In1.Cu")
	)
	(gr_line
		(start 110.638844 -10.999978)
		(end 110.638844 -12.399772)
		(stroke
			(width 0.2)
			(type default)
		)
		(layer "In1.Cu")
	)
	(gr_arc
		(start 110.638844 -5.199888)
		(mid 111.200057 -5.761482)
		(end 111.761524 -5.200142)
		(stroke
			(width 0.2)
			(type default)
		)
		(layer "In1.Cu")
	)
	(gr_line
		(start 110.638844 -3.800094)
		(end 110.638844 -5.199888)
		(stroke
			(width 0.2)
			(type default)
		)
		(layer "In1.Cu")
	)
	(gr_arc
		(start 110.641892 -55.999888)
		(mid 110.999905 -56.358282)
		(end 111.358172 -56.000142)
		(stroke
			(width 0.2)
			(type default)
		)
		(layer "In1.Cu")
	)
	(gr_line
		(start 110.641892 -55.000144)
		(end 110.641892 -55.999888)
		(stroke
			(width 0.2)
			(type default)
		)
		(layer "In1.Cu")
	)
	(gr_arc
		(start 110.641892 -52.999894)
		(mid 110.999905 -53.358288)
		(end 111.358172 -53.000148)
		(stroke
			(width 0.2)
			(type default)
		)
		(layer "In1.Cu")
	)
	(gr_line
		(start 110.641892 -52.00015)
		(end 110.641892 -52.999894)
		(stroke
			(width 0.2)
			(type default)
		)
		(layer "In1.Cu")
	)
	(gr_line
		(start 111.358172 -56.000142)
		(end 111.358172 -55.000144)
		(stroke
			(width 0.2)
			(type default)
		)
		(layer "In1.Cu")
	)
	(gr_arc
		(start 111.358172 -55.000144)
		(mid 111.000032 -54.642004)
		(end 110.641892 -55.000144)
		(stroke
			(width 0.2)
			(type default)
		)
		(layer "In1.Cu")
	)
	(gr_line
		(start 111.358172 -53.000148)
		(end 111.358172 -52.00015)
		(stroke
			(width 0.2)
			(type default)
		)
		(layer "In1.Cu")
	)
	(gr_arc
		(start 111.358172 -52.00015)
		(mid 111.000032 -51.64201)
		(end 110.641892 -52.00015)
		(stroke
			(width 0.2)
			(type default)
		)
		(layer "In1.Cu")
	)
	(gr_arc
		(start 111.64189 -55.999888)
		(mid 111.999903 -56.358282)
		(end 112.35817 -56.000142)
		(stroke
			(width 0.2)
			(type default)
		)
		(layer "In1.Cu")
	)
	(gr_line
		(start 111.64189 -55.000144)
		(end 111.64189 -55.999888)
		(stroke
			(width 0.2)
			(type default)
		)
		(layer "In1.Cu")
	)
	(gr_arc
		(start 111.64189 -51.999896)
		(mid 111.999903 -52.35829)
		(end 112.35817 -52.00015)
		(stroke
			(width 0.2)
			(type default)
		)
		(layer "In1.Cu")
	)
	(gr_line
		(start 111.64189 -51.000152)
		(end 111.64189 -51.999896)
		(stroke
			(width 0.2)
			(type default)
		)
		(layer "In1.Cu")
	)
	(gr_line
		(start 111.761524 -12.400026)
		(end 111.761524 -10.999978)
		(stroke
			(width 0.2)
			(type default)
		)
		(layer "In1.Cu")
	)
	(gr_arc
		(start 111.761524 -10.999978)
		(mid 111.200184 -10.438638)
		(end 110.638844 -10.999978)
		(stroke
			(width 0.2)
			(type default)
		)
		(layer "In1.Cu")
	)
	(gr_line
		(start 111.761524 -5.200142)
		(end 111.761524 -3.800094)
		(stroke
			(width 0.2)
			(type default)
		)
		(layer "In1.Cu")
	)
	(gr_arc
		(start 111.761524 -3.800094)
		(mid 111.200184 -3.238754)
		(end 110.638844 -3.800094)
		(stroke
			(width 0.2)
			(type default)
		)
		(layer "In1.Cu")
	)
	(gr_line
		(start 112.35817 -56.000142)
		(end 112.35817 -55.000144)
		(stroke
			(width 0.2)
			(type default)
		)
		(layer "In1.Cu")
	)
	(gr_arc
		(start 112.35817 -55.000144)
		(mid 112.00003 -54.642004)
		(end 111.64189 -55.000144)
		(stroke
			(width 0.2)
			(type default)
		)
		(layer "In1.Cu")
	)
	(gr_line
		(start 112.35817 -52.00015)
		(end 112.35817 -51.000152)
		(stroke
			(width 0.2)
			(type default)
		)
		(layer "In1.Cu")
	)
	(gr_arc
		(start 112.35817 -51.000152)
		(mid 112.00003 -50.642012)
		(end 111.64189 -51.000152)
		(stroke
			(width 0.2)
			(type default)
		)
		(layer "In1.Cu")
	)
	(gr_arc
		(start 112.438688 -11.199876)
		(mid 112.999901 -11.76147)
		(end 113.561368 -11.20013)
		(stroke
			(width 0.2)
			(type default)
		)
		(layer "In1.Cu")
	)
	(gr_line
		(start 112.438688 -9.800082)
		(end 112.438688 -11.199876)
		(stroke
			(width 0.2)
			(type default)
		)
		(layer "In1.Cu")
	)
	(gr_arc
		(start 112.438688 -3.999738)
		(mid 112.999901 -4.561332)
		(end 113.561368 -3.999992)
		(stroke
			(width 0.2)
			(type default)
		)
		(layer "In1.Cu")
	)
	(gr_line
		(start 112.438688 -2.600198)
		(end 112.438688 -3.999738)
		(stroke
			(width 0.2)
			(type default)
		)
		(layer "In1.Cu")
	)
	(gr_line
		(start 112.499902 -126.000002)
		(end 97.499932 -126.000002)
		(stroke
			(width 1.524)
			(type default)
		)
		(layer "In1.Cu")
	)
	(gr_arc
		(start 112.641888 -55.999888)
		(mid 112.999901 -56.358282)
		(end 113.358168 -56.000142)
		(stroke
			(width 0.2)
			(type default)
		)
		(layer "In1.Cu")
	)
	(gr_line
		(start 112.641888 -55.000144)
		(end 112.641888 -55.999888)
		(stroke
			(width 0.2)
			(type default)
		)
		(layer "In1.Cu")
	)
	(gr_arc
		(start 112.641888 -52.999894)
		(mid 112.999901 -53.358288)
		(end 113.358168 -53.000148)
		(stroke
			(width 0.2)
			(type default)
		)
		(layer "In1.Cu")
	)
	(gr_line
		(start 112.641888 -52.00015)
		(end 112.641888 -52.999894)
		(stroke
			(width 0.2)
			(type default)
		)
		(layer "In1.Cu")
	)
	(gr_line
		(start 113.358168 -56.000142)
		(end 113.358168 -55.000144)
		(stroke
			(width 0.2)
			(type default)
		)
		(layer "In1.Cu")
	)
	(gr_arc
		(start 113.358168 -55.000144)
		(mid 113.000028 -54.642004)
		(end 112.641888 -55.000144)
		(stroke
			(width 0.2)
			(type default)
		)
		(layer "In1.Cu")
	)
	(gr_line
		(start 113.358168 -53.000148)
		(end 113.358168 -52.00015)
		(stroke
			(width 0.2)
			(type default)
		)
		(layer "In1.Cu")
	)
	(gr_arc
		(start 113.358168 -52.00015)
		(mid 113.000028 -51.64201)
		(end 112.641888 -52.00015)
		(stroke
			(width 0.2)
			(type default)
		)
		(layer "In1.Cu")
	)
	(gr_line
		(start 113.561368 -11.20013)
		(end 113.561368 -9.800082)
		(stroke
			(width 0.2)
			(type default)
		)
		(layer "In1.Cu")
	)
	(gr_arc
		(start 113.561368 -9.800082)
		(mid 113.000028 -9.238742)
		(end 112.438688 -9.800082)
		(stroke
			(width 0.2)
			(type default)
		)
		(layer "In1.Cu")
	)
	(gr_line
		(start 113.561368 -3.999992)
		(end 113.561368 -2.600198)
		(stroke
			(width 0.2)
			(type default)
		)
		(layer "In1.Cu")
	)
	(gr_arc
		(start 113.561368 -2.600198)
		(mid 113.000028 -2.038858)
		(end 112.438688 -2.600198)
		(stroke
			(width 0.2)
			(type default)
		)
		(layer "In1.Cu")
	)
	(gr_arc
		(start 113.641886 -55.999888)
		(mid 113.999899 -56.358282)
		(end 114.358166 -56.000142)
		(stroke
			(width 0.2)
			(type default)
		)
		(layer "In1.Cu")
	)
	(gr_line
		(start 113.641886 -55.000144)
		(end 113.641886 -55.999888)
		(stroke
			(width 0.2)
			(type default)
		)
		(layer "In1.Cu")
	)
	(gr_arc
		(start 113.641886 -51.999896)
		(mid 113.999899 -52.35829)
		(end 114.358166 -52.00015)
		(stroke
			(width 0.2)
			(type default)
		)
		(layer "In1.Cu")
	)
	(gr_line
		(start 113.641886 -51.000152)
		(end 113.641886 -51.999896)
		(stroke
			(width 0.2)
			(type default)
		)
		(layer "In1.Cu")
	)
	(gr_arc
		(start 114.238786 -12.399772)
		(mid 114.799999 -12.961366)
		(end 115.361466 -12.400026)
		(stroke
			(width 0.2)
			(type default)
		)
		(layer "In1.Cu")
	)
	(gr_line
		(start 114.238786 -10.999978)
		(end 114.238786 -12.399772)
		(stroke
			(width 0.2)
			(type default)
		)
		(layer "In1.Cu")
	)
	(gr_arc
		(start 114.238786 -5.199888)
		(mid 114.799999 -5.761482)
		(end 115.361466 -5.200142)
		(stroke
			(width 0.2)
			(type default)
		)
		(layer "In1.Cu")
	)
	(gr_line
		(start 114.238786 -3.800094)
		(end 114.238786 -5.199888)
		(stroke
			(width 0.2)
			(type default)
		)
		(layer "In1.Cu")
	)
	(gr_line
		(start 114.358166 -56.000142)
		(end 114.358166 -55.000144)
		(stroke
			(width 0.2)
			(type default)
		)
		(layer "In1.Cu")
	)
	(gr_arc
		(start 114.358166 -55.000144)
		(mid 114.000026 -54.642004)
		(end 113.641886 -55.000144)
		(stroke
			(width 0.2)
			(type default)
		)
		(layer "In1.Cu")
	)
	(gr_line
		(start 114.358166 -52.00015)
		(end 114.358166 -51.000152)
		(stroke
			(width 0.2)
			(type default)
		)
		(layer "In1.Cu")
	)
	(gr_arc
		(start 114.358166 -51.000152)
		(mid 114.000026 -50.642012)
		(end 113.641886 -51.000152)
		(stroke
			(width 0.2)
			(type default)
		)
		(layer "In1.Cu")
	)
	(gr_line
		(start 115.361466 -12.400026)
		(end 115.361466 -10.999978)
		(stroke
			(width 0.2)
			(type default)
		)
		(layer "In1.Cu")
	)
	(gr_arc
		(start 115.361466 -10.999978)
		(mid 114.800126 -10.438638)
		(end 114.238786 -10.999978)
		(stroke
			(width 0.2)
			(type default)
		)
		(layer "In1.Cu")
	)
	(gr_line
		(start 115.361466 -5.200142)
		(end 115.361466 -3.800094)
		(stroke
			(width 0.2)
			(type default)
		)
		(layer "In1.Cu")
	)
	(gr_arc
		(start 115.361466 -3.800094)
		(mid 114.800126 -3.238754)
		(end 114.238786 -3.800094)
		(stroke
			(width 0.2)
			(type default)
		)
		(layer "In1.Cu")
	)
	(gr_arc
		(start 115.641882 -55.999888)
		(mid 115.999895 -56.358282)
		(end 116.358162 -56.000142)
		(stroke
			(width 0.2)
			(type default)
		)
		(layer "In1.Cu")
	)
	(gr_line
		(start 115.641882 -55.000144)
		(end 115.641882 -55.999888)
		(stroke
			(width 0.2)
			(type default)
		)
		(layer "In1.Cu")
	)
	(gr_arc
		(start 115.641882 -52.999894)
		(mid 115.999895 -53.358288)
		(end 116.358162 -53.000148)
		(stroke
			(width 0.2)
			(type default)
		)
		(layer "In1.Cu")
	)
	(gr_line
		(start 115.641882 -52.00015)
		(end 115.641882 -52.999894)
		(stroke
			(width 0.2)
			(type default)
		)
		(layer "In1.Cu")
	)
	(gr_arc
		(start 116.03863 -11.199876)
		(mid 116.599843 -11.76147)
		(end 117.16131 -11.20013)
		(stroke
			(width 0.2)
			(type default)
		)
		(layer "In1.Cu")
	)
	(gr_line
		(start 116.03863 -9.800082)
		(end 116.03863 -11.199876)
		(stroke
			(width 0.2)
			(type default)
		)
		(layer "In1.Cu")
	)
	(gr_arc
		(start 116.03863 -3.999738)
		(mid 116.599843 -4.561332)
		(end 117.16131 -3.999992)
		(stroke
			(width 0.2)
			(type default)
		)
		(layer "In1.Cu")
	)
	(gr_line
		(start 116.03863 -2.600198)
		(end 116.03863 -3.999738)
		(stroke
			(width 0.2)
			(type default)
		)
		(layer "In1.Cu")
	)
	(gr_line
		(start 116.358162 -56.000142)
		(end 116.358162 -55.000144)
		(stroke
			(width 0.2)
			(type default)
		)
		(layer "In1.Cu")
	)
	(gr_arc
		(start 116.358162 -55.000144)
		(mid 116.000022 -54.642004)
		(end 115.641882 -55.000144)
		(stroke
			(width 0.2)
			(type default)
		)
		(layer "In1.Cu")
	)
	(gr_line
		(start 116.358162 -53.000148)
		(end 116.358162 -52.00015)
		(stroke
			(width 0.2)
			(type default)
		)
		(layer "In1.Cu")
	)
	(gr_arc
		(start 116.358162 -52.00015)
		(mid 116.000022 -51.64201)
		(end 115.641882 -52.00015)
		(stroke
			(width 0.2)
			(type default)
		)
		(layer "In1.Cu")
	)
	(gr_arc
		(start 116.64188 -55.999888)
		(mid 116.999893 -56.358282)
		(end 117.35816 -56.000142)
		(stroke
			(width 0.2)
			(type default)
		)
		(layer "In1.Cu")
	)
	(gr_line
		(start 116.64188 -55.000144)
		(end 116.64188 -55.999888)
		(stroke
			(width 0.2)
			(type default)
		)
		(layer "In1.Cu")
	)
	(gr_arc
		(start 116.64188 -51.999896)
		(mid 116.999893 -52.35829)
		(end 117.35816 -52.00015)
		(stroke
			(width 0.2)
			(type default)
		)
		(layer "In1.Cu")
	)
	(gr_line
		(start 116.64188 -51.000152)
		(end 116.64188 -51.999896)
		(stroke
			(width 0.2)
			(type default)
		)
		(layer "In1.Cu")
	)
	(gr_line
		(start 117.16131 -11.20013)
		(end 117.16131 -9.800082)
		(stroke
			(width 0.2)
			(type default)
		)
		(layer "In1.Cu")
	)
	(gr_arc
		(start 117.16131 -9.800082)
		(mid 116.59997 -9.238742)
		(end 116.03863 -9.800082)
		(stroke
			(width 0.2)
			(type default)
		)
		(layer "In1.Cu")
	)
	(gr_line
		(start 117.16131 -3.999992)
		(end 117.16131 -2.600198)
		(stroke
			(width 0.2)
			(type default)
		)
		(layer "In1.Cu")
	)
	(gr_arc
		(start 117.16131 -2.600198)
		(mid 116.59997 -2.038858)
		(end 116.03863 -2.600198)
		(stroke
			(width 0.2)
			(type default)
		)
		(layer "In1.Cu")
	)
	(gr_line
		(start 117.35816 -56.000142)
		(end 117.35816 -55.000144)
		(stroke
			(width 0.2)
			(type default)
		)
		(layer "In1.Cu")
	)
	(gr_arc
		(start 117.35816 -55.000144)
		(mid 117.00002 -54.642004)
		(end 116.64188 -55.000144)
		(stroke
			(width 0.2)
			(type default)
		)
		(layer "In1.Cu")
	)
	(gr_line
		(start 117.35816 -52.00015)
		(end 117.35816 -51.000152)
		(stroke
			(width 0.2)
			(type default)
		)
		(layer "In1.Cu")
	)
	(gr_arc
		(start 117.35816 -51.000152)
		(mid 117.00002 -50.642012)
		(end 116.64188 -51.000152)
		(stroke
			(width 0.2)
			(type default)
		)
		(layer "In1.Cu")
	)
	(gr_arc
		(start 117.641878 -55.999888)
		(mid 117.999891 -56.358282)
		(end 118.358158 -56.000142)
		(stroke
			(width 0.2)
			(type default)
		)
		(layer "In1.Cu")
	)
	(gr_line
		(start 117.641878 -55.000144)
		(end 117.641878 -55.999888)
		(stroke
			(width 0.2)
			(type default)
		)
		(layer "In1.Cu")
	)
	(gr_arc
		(start 117.641878 -52.999894)
		(mid 117.999891 -53.358288)
		(end 118.358158 -53.000148)
		(stroke
			(width 0.2)
			(type default)
		)
		(layer "In1.Cu")
	)
	(gr_line
		(start 117.641878 -52.00015)
		(end 117.641878 -52.999894)
		(stroke
			(width 0.2)
			(type default)
		)
		(layer "In1.Cu")
	)
	(gr_arc
		(start 117.838728 -12.399772)
		(mid 118.399941 -12.961366)
		(end 118.961408 -12.400026)
		(stroke
			(width 0.2)
			(type default)
		)
		(layer "In1.Cu")
	)
	(gr_line
		(start 117.838728 -10.999978)
		(end 117.838728 -12.399772)
		(stroke
			(width 0.2)
			(type default)
		)
		(layer "In1.Cu")
	)
	(gr_arc
		(start 117.838728 -5.199888)
		(mid 118.399941 -5.761482)
		(end 118.961408 -5.200142)
		(stroke
			(width 0.2)
			(type default)
		)
		(layer "In1.Cu")
	)
	(gr_line
		(start 117.838728 -3.800094)
		(end 117.838728 -5.199888)
		(stroke
			(width 0.2)
			(type default)
		)
		(layer "In1.Cu")
	)
	(gr_line
		(start 118.358158 -56.000142)
		(end 118.358158 -55.000144)
		(stroke
			(width 0.2)
			(type default)
		)
		(layer "In1.Cu")
	)
	(gr_arc
		(start 118.358158 -55.000144)
		(mid 118.000018 -54.642004)
		(end 117.641878 -55.000144)
		(stroke
			(width 0.2)
			(type default)
		)
		(layer "In1.Cu")
	)
	(gr_line
		(start 118.358158 -53.000148)
		(end 118.358158 -52.00015)
		(stroke
			(width 0.2)
			(type default)
		)
		(layer "In1.Cu")
	)
	(gr_arc
		(start 118.358158 -52.00015)
		(mid 118.000018 -51.64201)
		(end 117.641878 -52.00015)
		(stroke
			(width 0.2)
			(type default)
		)
		(layer "In1.Cu")
	)
	(gr_arc
		(start 118.641876 -55.999888)
		(mid 118.999889 -56.358282)
		(end 119.358156 -56.000142)
		(stroke
			(width 0.2)
			(type default)
		)
		(layer "In1.Cu")
	)
	(gr_line
		(start 118.641876 -55.000144)
		(end 118.641876 -55.999888)
		(stroke
			(width 0.2)
			(type default)
		)
		(layer "In1.Cu")
	)
	(gr_arc
		(start 118.641876 -51.999896)
		(mid 118.999889 -52.35829)
		(end 119.358156 -52.00015)
		(stroke
			(width 0.2)
			(type default)
		)
		(layer "In1.Cu")
	)
	(gr_line
		(start 118.641876 -51.000152)
		(end 118.641876 -51.999896)
		(stroke
			(width 0.2)
			(type default)
		)
		(layer "In1.Cu")
	)
	(gr_line
		(start 118.961408 -12.400026)
		(end 118.961408 -10.999978)
		(stroke
			(width 0.2)
			(type default)
		)
		(layer "In1.Cu")
	)
	(gr_arc
		(start 118.961408 -10.999978)
		(mid 118.400068 -10.438638)
		(end 117.838728 -10.999978)
		(stroke
			(width 0.2)
			(type default)
		)
		(layer "In1.Cu")
	)
	(gr_line
		(start 118.961408 -5.200142)
		(end 118.961408 -3.800094)
		(stroke
			(width 0.2)
			(type default)
		)
		(layer "In1.Cu")
	)
	(gr_arc
		(start 118.961408 -3.800094)
		(mid 118.400068 -3.238754)
		(end 117.838728 -3.800094)
		(stroke
			(width 0.2)
			(type default)
		)
		(layer "In1.Cu")
	)
	(gr_line
		(start 119.358156 -56.000142)
		(end 119.358156 -55.000144)
		(stroke
			(width 0.2)
			(type default)
		)
		(layer "In1.Cu")
	)
	(gr_arc
		(start 119.358156 -55.000144)
		(mid 119.000016 -54.642004)
		(end 118.641876 -55.000144)
		(stroke
			(width 0.2)
			(type default)
		)
		(layer "In1.Cu")
	)
	(gr_line
		(start 119.358156 -52.00015)
		(end 119.358156 -51.000152)
		(stroke
			(width 0.2)
			(type default)
		)
		(layer "In1.Cu")
	)
	(gr_arc
		(start 119.358156 -51.000152)
		(mid 119.000016 -50.642012)
		(end 118.641876 -51.000152)
		(stroke
			(width 0.2)
			(type default)
		)
		(layer "In1.Cu")
	)
	(gr_arc
		(start 119.638826 -11.199876)
		(mid 120.200039 -11.76147)
		(end 120.761506 -11.20013)
		(stroke
			(width 0.2)
			(type default)
		)
		(layer "In1.Cu")
	)
	(gr_line
		(start 119.638826 -9.800082)
		(end 119.638826 -11.199876)
		(stroke
			(width 0.2)
			(type default)
		)
		(layer "In1.Cu")
	)
	(gr_arc
		(start 119.638826 -3.999738)
		(mid 120.200039 -4.561332)
		(end 120.761506 -3.999992)
		(stroke
			(width 0.2)
			(type default)
		)
		(layer "In1.Cu")
	)
	(gr_line
		(start 119.638826 -2.600198)
		(end 119.638826 -3.999738)
		(stroke
			(width 0.2)
			(type default)
		)
		(layer "In1.Cu")
	)
	(gr_arc
		(start 119.641874 -55.999888)
		(mid 119.999887 -56.358282)
		(end 120.358154 -56.000142)
		(stroke
			(width 0.2)
			(type default)
		)
		(layer "In1.Cu")
	)
	(gr_line
		(start 119.641874 -55.000144)
		(end 119.641874 -55.999888)
		(stroke
			(width 0.2)
			(type default)
		)
		(layer "In1.Cu")
	)
	(gr_arc
		(start 119.641874 -52.999894)
		(mid 119.999887 -53.358288)
		(end 120.358154 -53.000148)
		(stroke
			(width 0.2)
			(type default)
		)
		(layer "In1.Cu")
	)
	(gr_line
		(start 119.641874 -52.00015)
		(end 119.641874 -52.999894)
		(stroke
			(width 0.2)
			(type default)
		)
		(layer "In1.Cu")
	)
	(gr_line
		(start 120.358154 -56.000142)
		(end 120.358154 -55.000144)
		(stroke
			(width 0.2)
			(type default)
		)
		(layer "In1.Cu")
	)
	(gr_arc
		(start 120.358154 -55.000144)
		(mid 120.000014 -54.642004)
		(end 119.641874 -55.000144)
		(stroke
			(width 0.2)
			(type default)
		)
		(layer "In1.Cu")
	)
	(gr_line
		(start 120.358154 -53.000148)
		(end 120.358154 -52.00015)
		(stroke
			(width 0.2)
			(type default)
		)
		(layer "In1.Cu")
	)
	(gr_arc
		(start 120.358154 -52.00015)
		(mid 120.000014 -51.64201)
		(end 119.641874 -52.00015)
		(stroke
			(width 0.2)
			(type default)
		)
		(layer "In1.Cu")
	)
	(gr_arc
		(start 120.641872 -55.999888)
		(mid 120.999885 -56.358282)
		(end 121.358152 -56.000142)
		(stroke
			(width 0.2)
			(type default)
		)
		(layer "In1.Cu")
	)
	(gr_line
		(start 120.641872 -55.000144)
		(end 120.641872 -55.999888)
		(stroke
			(width 0.2)
			(type default)
		)
		(layer "In1.Cu")
	)
	(gr_arc
		(start 120.641872 -51.999896)
		(mid 120.999885 -52.35829)
		(end 121.358152 -52.00015)
		(stroke
			(width 0.2)
			(type default)
		)
		(layer "In1.Cu")
	)
	(gr_line
		(start 120.641872 -51.000152)
		(end 120.641872 -51.999896)
		(stroke
			(width 0.2)
			(type default)
		)
		(layer "In1.Cu")
	)
	(gr_line
		(start 120.761506 -11.20013)
		(end 120.761506 -9.800082)
		(stroke
			(width 0.2)
			(type default)
		)
		(layer "In1.Cu")
	)
	(gr_arc
		(start 120.761506 -9.800082)
		(mid 120.200166 -9.238742)
		(end 119.638826 -9.800082)
		(stroke
			(width 0.2)
			(type default)
		)
		(layer "In1.Cu")
	)
	(gr_line
		(start 120.761506 -3.999992)
		(end 120.761506 -2.600198)
		(stroke
			(width 0.2)
			(type default)
		)
		(layer "In1.Cu")
	)
	(gr_arc
		(start 120.761506 -2.600198)
		(mid 120.200166 -2.038858)
		(end 119.638826 -2.600198)
		(stroke
			(width 0.2)
			(type default)
		)
		(layer "In1.Cu")
	)
	(gr_line
		(start 120.79224 -127.32639)
		(end 112.499902 -126.000002)
		(stroke
			(width 1.524)
			(type default)
		)
		(layer "In1.Cu")
	)
	(gr_line
		(start 121.358152 -56.000142)
		(end 121.358152 -55.000144)
		(stroke
			(width 0.2)
			(type default)
		)
		(layer "In1.Cu")
	)
	(gr_arc
		(start 121.358152 -55.000144)
		(mid 121.000012 -54.642004)
		(end 120.641872 -55.000144)
		(stroke
			(width 0.2)
			(type default)
		)
		(layer "In1.Cu")
	)
	(gr_line
		(start 121.358152 -52.00015)
		(end 121.358152 -51.000152)
		(stroke
			(width 0.2)
			(type default)
		)
		(layer "In1.Cu")
	)
	(gr_arc
		(start 121.358152 -51.000152)
		(mid 121.000012 -50.642012)
		(end 120.641872 -51.000152)
		(stroke
			(width 0.2)
			(type default)
		)
		(layer "In1.Cu")
	)
	(gr_arc
		(start 121.43867 -12.399772)
		(mid 121.999883 -12.961366)
		(end 122.56135 -12.400026)
		(stroke
			(width 0.2)
			(type default)
		)
		(layer "In1.Cu")
	)
	(gr_line
		(start 121.43867 -10.999978)
		(end 121.43867 -12.399772)
		(stroke
			(width 0.2)
			(type default)
		)
		(layer "In1.Cu")
	)
	(gr_arc
		(start 121.43867 -5.199888)
		(mid 121.999883 -5.761482)
		(end 122.56135 -5.200142)
		(stroke
			(width 0.2)
			(type default)
		)
		(layer "In1.Cu")
	)
	(gr_line
		(start 121.43867 -3.800094)
		(end 121.43867 -5.199888)
		(stroke
			(width 0.2)
			(type default)
		)
		(layer "In1.Cu")
	)
	(gr_arc
		(start 121.64187 -55.999888)
		(mid 121.999883 -56.358282)
		(end 122.35815 -56.000142)
		(stroke
			(width 0.2)
			(type default)
		)
		(layer "In1.Cu")
	)
	(gr_line
		(start 121.64187 -55.000144)
		(end 121.64187 -55.999888)
		(stroke
			(width 0.2)
			(type default)
		)
		(layer "In1.Cu")
	)
	(gr_arc
		(start 121.64187 -52.999894)
		(mid 121.999883 -53.358288)
		(end 122.35815 -53.000148)
		(stroke
			(width 0.2)
			(type default)
		)
		(layer "In1.Cu")
	)
	(gr_line
		(start 121.64187 -52.00015)
		(end 121.64187 -52.999894)
		(stroke
			(width 0.2)
			(type default)
		)
		(layer "In1.Cu")
	)
	(gr_line
		(start 122.35815 -56.000142)
		(end 122.35815 -55.000144)
		(stroke
			(width 0.2)
			(type default)
		)
		(layer "In1.Cu")
	)
	(gr_arc
		(start 122.35815 -55.000144)
		(mid 122.00001 -54.642004)
		(end 121.64187 -55.000144)
		(stroke
			(width 0.2)
			(type default)
		)
		(layer "In1.Cu")
	)
	(gr_line
		(start 122.35815 -53.000148)
		(end 122.35815 -52.00015)
		(stroke
			(width 0.2)
			(type default)
		)
		(layer "In1.Cu")
	)
	(gr_arc
		(start 122.35815 -52.00015)
		(mid 122.00001 -51.64201)
		(end 121.64187 -52.00015)
		(stroke
			(width 0.2)
			(type default)
		)
		(layer "In1.Cu")
	)
	(gr_line
		(start 122.56135 -12.400026)
		(end 122.56135 -10.999978)
		(stroke
			(width 0.2)
			(type default)
		)
		(layer "In1.Cu")
	)
	(gr_arc
		(start 122.56135 -10.999978)
		(mid 122.00001 -10.438638)
		(end 121.43867 -10.999978)
		(stroke
			(width 0.2)
			(type default)
		)
		(layer "In1.Cu")
	)
	(gr_line
		(start 122.56135 -5.200142)
		(end 122.56135 -3.800094)
		(stroke
			(width 0.2)
			(type default)
		)
		(layer "In1.Cu")
	)
	(gr_arc
		(start 122.56135 -3.800094)
		(mid 122.00001 -3.238754)
		(end 121.43867 -3.800094)
		(stroke
			(width 0.2)
			(type default)
		)
		(layer "In1.Cu")
	)
	(gr_arc
		(start 122.641868 -55.999888)
		(mid 122.999881 -56.358282)
		(end 123.358148 -56.000142)
		(stroke
			(width 0.2)
			(type default)
		)
		(layer "In1.Cu")
	)
	(gr_line
		(start 122.641868 -55.000144)
		(end 122.641868 -55.999888)
		(stroke
			(width 0.2)
			(type default)
		)
		(layer "In1.Cu")
	)
	(gr_arc
		(start 122.641868 -51.999896)
		(mid 122.999881 -52.35829)
		(end 123.358148 -52.00015)
		(stroke
			(width 0.2)
			(type default)
		)
		(layer "In1.Cu")
	)
	(gr_line
		(start 122.641868 -51.000152)
		(end 122.641868 -51.999896)
		(stroke
			(width 0.2)
			(type default)
		)
		(layer "In1.Cu")
	)
	(gr_arc
		(start 123.238768 -11.199876)
		(mid 123.799981 -11.76147)
		(end 124.361448 -11.20013)
		(stroke
			(width 0.2)
			(type default)
		)
		(layer "In1.Cu")
	)
	(gr_line
		(start 123.238768 -9.800082)
		(end 123.238768 -11.199876)
		(stroke
			(width 0.2)
			(type default)
		)
		(layer "In1.Cu")
	)
	(gr_arc
		(start 123.238768 -3.999738)
		(mid 123.799981 -4.561332)
		(end 124.361448 -3.999992)
		(stroke
			(width 0.2)
			(type default)
		)
		(layer "In1.Cu")
	)
	(gr_line
		(start 123.238768 -2.600198)
		(end 123.238768 -3.999738)
		(stroke
			(width 0.2)
			(type default)
		)
		(layer "In1.Cu")
	)
	(gr_line
		(start 123.358148 -56.000142)
		(end 123.358148 -55.000144)
		(stroke
			(width 0.2)
			(type default)
		)
		(layer "In1.Cu")
	)
	(gr_arc
		(start 123.358148 -55.000144)
		(mid 123.000008 -54.642004)
		(end 122.641868 -55.000144)
		(stroke
			(width 0.2)
			(type default)
		)
		(layer "In1.Cu")
	)
	(gr_line
		(start 123.358148 -52.00015)
		(end 123.358148 -51.000152)
		(stroke
			(width 0.2)
			(type default)
		)
		(layer "In1.Cu")
	)
	(gr_arc
		(start 123.358148 -51.000152)
		(mid 123.000008 -50.642012)
		(end 122.641868 -51.000152)
		(stroke
			(width 0.2)
			(type default)
		)
		(layer "In1.Cu")
	)
	(gr_arc
		(start 123.641866 -55.999888)
		(mid 123.999879 -56.358282)
		(end 124.358146 -56.000142)
		(stroke
			(width 0.2)
			(type default)
		)
		(layer "In1.Cu")
	)
	(gr_line
		(start 123.641866 -55.000144)
		(end 123.641866 -55.999888)
		(stroke
			(width 0.2)
			(type default)
		)
		(layer "In1.Cu")
	)
	(gr_arc
		(start 123.641866 -52.999894)
		(mid 123.999879 -53.358288)
		(end 124.358146 -53.000148)
		(stroke
			(width 0.2)
			(type default)
		)
		(layer "In1.Cu")
	)
	(gr_line
		(start 123.641866 -52.00015)
		(end 123.641866 -52.999894)
		(stroke
			(width 0.2)
			(type default)
		)
		(layer "In1.Cu")
	)
	(gr_arc
		(start 124.225558 -47.001684)
		(mid 124.682631 -47.459138)
		(end 125.139958 -47.001938)
		(stroke
			(width 0.2)
			(type default)
		)
		(layer "In1.Cu")
	)
	(gr_line
		(start 124.225558 -45.858938)
		(end 124.225558 -47.001684)
		(stroke
			(width 0.2)
			(type default)
		)
		(layer "In1.Cu")
	)
	(gr_line
		(start 124.358146 -56.000142)
		(end 124.358146 -55.000144)
		(stroke
			(width 0.2)
			(type default)
		)
		(layer "In1.Cu")
	)
	(gr_arc
		(start 124.358146 -55.000144)
		(mid 124.000006 -54.642004)
		(end 123.641866 -55.000144)
		(stroke
			(width 0.2)
			(type default)
		)
		(layer "In1.Cu")
	)
	(gr_line
		(start 124.358146 -53.000148)
		(end 124.358146 -52.00015)
		(stroke
			(width 0.2)
			(type default)
		)
		(layer "In1.Cu")
	)
	(gr_arc
		(start 124.358146 -52.00015)
		(mid 124.000006 -51.64201)
		(end 123.641866 -52.00015)
		(stroke
			(width 0.2)
			(type default)
		)
		(layer "In1.Cu")
	)
	(gr_line
		(start 124.361448 -11.20013)
		(end 124.361448 -9.800082)
		(stroke
			(width 0.2)
			(type default)
		)
		(layer "In1.Cu")
	)
	(gr_arc
		(start 124.361448 -9.800082)
		(mid 123.800108 -9.238742)
		(end 123.238768 -9.800082)
		(stroke
			(width 0.2)
			(type default)
		)
		(layer "In1.Cu")
	)
	(gr_line
		(start 124.361448 -3.999992)
		(end 124.361448 -2.600198)
		(stroke
			(width 0.2)
			(type default)
		)
		(layer "In1.Cu")
	)
	(gr_arc
		(start 124.361448 -2.600198)
		(mid 123.800108 -2.038858)
		(end 123.238768 -2.600198)
		(stroke
			(width 0.2)
			(type default)
		)
		(layer "In1.Cu")
	)
	(gr_line
		(start 125.002544 -142.999968)
		(end 125.002544 -132.263642)
		(stroke
			(width 1.524)
			(type default)
		)
		(layer "In1.Cu")
	)
	(gr_arc
		(start 125.002544 -142.999968)
		(mid 125.58832 -144.414185)
		(end 127.00254 -144.999964)
		(stroke
			(width 1.524)
			(type default)
		)
		(layer "In1.Cu")
	)
	(gr_arc
		(start 125.002544 -132.263642)
		(mid 123.807045 -129.019301)
		(end 120.79224 -127.32639)
		(stroke
			(width 1.524)
			(type default)
		)
		(layer "In1.Cu")
	)
	(gr_arc
		(start 125.038866 -12.399772)
		(mid 125.600079 -12.961366)
		(end 126.161546 -12.400026)
		(stroke
			(width 0.2)
			(type default)
		)
		(layer "In1.Cu")
	)
	(gr_line
		(start 125.038866 -10.999978)
		(end 125.038866 -12.399772)
		(stroke
			(width 0.2)
			(type default)
		)
		(layer "In1.Cu")
	)
	(gr_arc
		(start 125.038866 -5.199888)
		(mid 125.600079 -5.761482)
		(end 126.161546 -5.200142)
		(stroke
			(width 0.2)
			(type default)
		)
		(layer "In1.Cu")
	)
	(gr_line
		(start 125.038866 -3.800094)
		(end 125.038866 -5.199888)
		(stroke
			(width 0.2)
			(type default)
		)
		(layer "In1.Cu")
	)
	(gr_line
		(start 125.139958 -47.001938)
		(end 125.139958 -45.858938)
		(stroke
			(width 0.2)
			(type default)
		)
		(layer "In1.Cu")
	)
	(gr_arc
		(start 125.139958 -45.858938)
		(mid 124.682758 -45.401738)
		(end 124.225558 -45.858938)
		(stroke
			(width 0.2)
			(type default)
		)
		(layer "In1.Cu")
	)
	(gr_arc
		(start 125.374146 -45.15358)
		(mid 125.389025 -45.189501)
		(end 125.424946 -45.20438)
		(stroke
			(width 0.2)
			(type default)
		)
		(layer "In1.Cu")
	)
	(gr_line
		(start 125.374146 -44.34078)
		(end 125.374146 -45.15358)
		(stroke
			(width 0.2)
			(type default)
		)
		(layer "In1.Cu")
	)
	(gr_line
		(start 125.424946 -45.20438)
		(end 125.628146 -45.20438)
		(stroke
			(width 0.2)
			(type default)
		)
		(layer "In1.Cu")
	)
	(gr_arc
		(start 125.424946 -44.28998)
		(mid 125.389025 -44.304859)
		(end 125.374146 -44.34078)
		(stroke
			(width 0.2)
			(type default)
		)
		(layer "In1.Cu")
	)
	(gr_arc
		(start 125.628146 -45.20438)
		(mid 125.664067 -45.189501)
		(end 125.678946 -45.15358)
		(stroke
			(width 0.2)
			(type default)
		)
		(layer "In1.Cu")
	)
	(gr_line
		(start 125.628146 -44.28998)
		(end 125.424946 -44.28998)
		(stroke
			(width 0.2)
			(type default)
		)
		(layer "In1.Cu")
	)
	(gr_line
		(start 125.678946 -45.15358)
		(end 125.678946 -44.34078)
		(stroke
			(width 0.2)
			(type default)
		)
		(layer "In1.Cu")
	)
	(gr_arc
		(start 125.678946 -44.34078)
		(mid 125.664067 -44.304859)
		(end 125.628146 -44.28998)
		(stroke
			(width 0.2)
			(type default)
		)
		(layer "In1.Cu")
	)
	(gr_arc
		(start 125.958346 -45.15358)
		(mid 125.973225 -45.189501)
		(end 126.009146 -45.20438)
		(stroke
			(width 0.2)
			(type default)
		)
		(layer "In1.Cu")
	)
	(gr_line
		(start 125.958346 -44.34078)
		(end 125.958346 -45.15358)
		(stroke
			(width 0.2)
			(type default)
		)
		(layer "In1.Cu")
	)
	(gr_line
		(start 126.000002 -77.35824)
		(end 127 -77.35824)
		(stroke
			(width 0.2)
			(type default)
		)
		(layer "In1.Cu")
	)
	(gr_line
		(start 126.000002 -76.358242)
		(end 127 -76.358242)
		(stroke
			(width 0.2)
			(type default)
		)
		(layer "In1.Cu")
	)
	(gr_line
		(start 126.000002 -75.358244)
		(end 127 -75.358244)
		(stroke
			(width 0.2)
			(type default)
		)
		(layer "In1.Cu")
	)
	(gr_line
		(start 126.000002 -74.358246)
		(end 127 -74.358246)
		(stroke
			(width 0.2)
			(type default)
		)
		(layer "In1.Cu")
	)
	(gr_line
		(start 126.000002 -73.358248)
		(end 127 -73.358248)
		(stroke
			(width 0.2)
			(type default)
		)
		(layer "In1.Cu")
	)
	(gr_line
		(start 126.000002 -72.35825)
		(end 127 -72.35825)
		(stroke
			(width 0.2)
			(type default)
		)
		(layer "In1.Cu")
	)
	(gr_line
		(start 126.000002 -71.358252)
		(end 127 -71.358252)
		(stroke
			(width 0.2)
			(type default)
		)
		(layer "In1.Cu")
	)
	(gr_line
		(start 126.000002 -70.358254)
		(end 127 -70.358254)
		(stroke
			(width 0.2)
			(type default)
		)
		(layer "In1.Cu")
	)
	(gr_line
		(start 126.000002 -69.358256)
		(end 127 -69.358256)
		(stroke
			(width 0.2)
			(type default)
		)
		(layer "In1.Cu")
	)
	(gr_line
		(start 126.000002 -68.358258)
		(end 127 -68.358258)
		(stroke
			(width 0.2)
			(type default)
		)
		(layer "In1.Cu")
	)
	(gr_line
		(start 126.000002 -66.358262)
		(end 127 -66.358262)
		(stroke
			(width 0.2)
			(type default)
		)
		(layer "In1.Cu")
	)
	(gr_line
		(start 126.000002 -65.358264)
		(end 127 -65.358264)
		(stroke
			(width 0.2)
			(type default)
		)
		(layer "In1.Cu")
	)
	(gr_line
		(start 126.000002 -64.358266)
		(end 127 -64.358266)
		(stroke
			(width 0.2)
			(type default)
		)
		(layer "In1.Cu")
	)
	(gr_line
		(start 126.000002 -63.358268)
		(end 127 -63.358268)
		(stroke
			(width 0.2)
			(type default)
		)
		(layer "In1.Cu")
	)
	(gr_line
		(start 126.000002 -62.35827)
		(end 127 -62.35827)
		(stroke
			(width 0.2)
			(type default)
		)
		(layer "In1.Cu")
	)
	(gr_line
		(start 126.000002 -61.358272)
		(end 127 -61.358272)
		(stroke
			(width 0.2)
			(type default)
		)
		(layer "In1.Cu")
	)
	(gr_line
		(start 126.000002 -60.358274)
		(end 127 -60.358274)
		(stroke
			(width 0.2)
			(type default)
		)
		(layer "In1.Cu")
	)
	(gr_line
		(start 126.000002 -59.358276)
		(end 127 -59.358276)
		(stroke
			(width 0.2)
			(type default)
		)
		(layer "In1.Cu")
	)
	(gr_line
		(start 126.000002 -58.358278)
		(end 127 -58.358278)
		(stroke
			(width 0.2)
			(type default)
		)
		(layer "In1.Cu")
	)
	(gr_line
		(start 126.000002 -57.35828)
		(end 127 -57.35828)
		(stroke
			(width 0.2)
			(type default)
		)
		(layer "In1.Cu")
	)
	(gr_line
		(start 126.000002 -56.358282)
		(end 127 -56.358282)
		(stroke
			(width 0.2)
			(type default)
		)
		(layer "In1.Cu")
	)
	(gr_line
		(start 126.000002 -55.358284)
		(end 127 -55.358284)
		(stroke
			(width 0.2)
			(type default)
		)
		(layer "In1.Cu")
	)
	(gr_line
		(start 126.000002 -54.358286)
		(end 127 -54.358286)
		(stroke
			(width 0.2)
			(type default)
		)
		(layer "In1.Cu")
	)
	(gr_arc
		(start 126.000256 -76.64196)
		(mid 125.641862 -76.999973)
		(end 126.000002 -77.35824)
		(stroke
			(width 0.2)
			(type default)
		)
		(layer "In1.Cu")
	)
	(gr_arc
		(start 126.000256 -75.641962)
		(mid 125.641862 -75.999975)
		(end 126.000002 -76.358242)
		(stroke
			(width 0.2)
			(type default)
		)
		(layer "In1.Cu")
	)
	(gr_arc
		(start 126.000256 -74.641964)
		(mid 125.641862 -74.999977)
		(end 126.000002 -75.358244)
		(stroke
			(width 0.2)
			(type default)
		)
		(layer "In1.Cu")
	)
	(gr_arc
		(start 126.000256 -73.641966)
		(mid 125.641862 -73.999979)
		(end 126.000002 -74.358246)
		(stroke
			(width 0.2)
			(type default)
		)
		(layer "In1.Cu")
	)
	(gr_arc
		(start 126.000256 -72.641968)
		(mid 125.641862 -72.999981)
		(end 126.000002 -73.358248)
		(stroke
			(width 0.2)
			(type default)
		)
		(layer "In1.Cu")
	)
	(gr_arc
		(start 126.000256 -71.64197)
		(mid 125.641862 -71.999983)
		(end 126.000002 -72.35825)
		(stroke
			(width 0.2)
			(type default)
		)
		(layer "In1.Cu")
	)
	(gr_arc
		(start 126.000256 -70.641972)
		(mid 125.641862 -70.999985)
		(end 126.000002 -71.358252)
		(stroke
			(width 0.2)
			(type default)
		)
		(layer "In1.Cu")
	)
	(gr_arc
		(start 126.000256 -69.641974)
		(mid 125.641862 -69.999987)
		(end 126.000002 -70.358254)
		(stroke
			(width 0.2)
			(type default)
		)
		(layer "In1.Cu")
	)
	(gr_arc
		(start 126.000256 -68.641976)
		(mid 125.641862 -68.999989)
		(end 126.000002 -69.358256)
		(stroke
			(width 0.2)
			(type default)
		)
		(layer "In1.Cu")
	)
	(gr_arc
		(start 126.000256 -67.641978)
		(mid 125.641862 -67.999991)
		(end 126.000002 -68.358258)
		(stroke
			(width 0.2)
			(type default)
		)
		(layer "In1.Cu")
	)
	(gr_arc
		(start 126.000256 -65.641982)
		(mid 125.641862 -65.999995)
		(end 126.000002 -66.358262)
		(stroke
			(width 0.2)
			(type default)
		)
		(layer "In1.Cu")
	)
	(gr_arc
		(start 126.000256 -64.641984)
		(mid 125.641862 -64.999997)
		(end 126.000002 -65.358264)
		(stroke
			(width 0.2)
			(type default)
		)
		(layer "In1.Cu")
	)
	(gr_arc
		(start 126.000256 -63.641986)
		(mid 125.641862 -63.999999)
		(end 126.000002 -64.358266)
		(stroke
			(width 0.2)
			(type default)
		)
		(layer "In1.Cu")
	)
	(gr_arc
		(start 126.000256 -62.641988)
		(mid 125.641862 -63.000001)
		(end 126.000002 -63.358268)
		(stroke
			(width 0.2)
			(type default)
		)
		(layer "In1.Cu")
	)
	(gr_arc
		(start 126.000256 -61.64199)
		(mid 125.641862 -62.000003)
		(end 126.000002 -62.35827)
		(stroke
			(width 0.2)
			(type default)
		)
		(layer "In1.Cu")
	)
	(gr_arc
		(start 126.000256 -60.641992)
		(mid 125.641862 -61.000005)
		(end 126.000002 -61.358272)
		(stroke
			(width 0.2)
			(type default)
		)
		(layer "In1.Cu")
	)
	(gr_arc
		(start 126.000256 -59.641994)
		(mid 125.641862 -60.000007)
		(end 126.000002 -60.358274)
		(stroke
			(width 0.2)
			(type default)
		)
		(layer "In1.Cu")
	)
	(gr_arc
		(start 126.000256 -58.641996)
		(mid 125.641862 -59.000009)
		(end 126.000002 -59.358276)
		(stroke
			(width 0.2)
			(type default)
		)
		(layer "In1.Cu")
	)
	(gr_arc
		(start 126.000256 -57.641998)
		(mid 125.641862 -58.000011)
		(end 126.000002 -58.358278)
		(stroke
			(width 0.2)
			(type default)
		)
		(layer "In1.Cu")
	)
	(gr_arc
		(start 126.000256 -56.642)
		(mid 125.641862 -57.000013)
		(end 126.000002 -57.35828)
		(stroke
			(width 0.2)
			(type default)
		)
		(layer "In1.Cu")
	)
	(gr_arc
		(start 126.000256 -55.642002)
		(mid 125.641862 -56.000015)
		(end 126.000002 -56.358282)
		(stroke
			(width 0.2)
			(type default)
		)
		(layer "In1.Cu")
	)
	(gr_arc
		(start 126.000256 -54.642004)
		(mid 125.641862 -55.000017)
		(end 126.000002 -55.358284)
		(stroke
			(width 0.2)
			(type default)
		)
		(layer "In1.Cu")
	)
	(gr_arc
		(start 126.000256 -53.642006)
		(mid 125.641862 -54.000019)
		(end 126.000002 -54.358286)
		(stroke
			(width 0.2)
			(type default)
		)
		(layer "In1.Cu")
	)
	(gr_line
		(start 126.009146 -45.20438)
		(end 126.212346 -45.20438)
		(stroke
			(width 0.2)
			(type default)
		)
		(layer "In1.Cu")
	)
	(gr_arc
		(start 126.009146 -44.28998)
		(mid 125.973225 -44.304859)
		(end 125.958346 -44.34078)
		(stroke
			(width 0.2)
			(type default)
		)
		(layer "In1.Cu")
	)
	(gr_line
		(start 126.161546 -12.400026)
		(end 126.161546 -10.999978)
		(stroke
			(width 0.2)
			(type default)
		)
		(layer "In1.Cu")
	)
	(gr_arc
		(start 126.161546 -10.999978)
		(mid 125.600206 -10.438638)
		(end 125.038866 -10.999978)
		(stroke
			(width 0.2)
			(type default)
		)
		(layer "In1.Cu")
	)
	(gr_line
		(start 126.161546 -5.200142)
		(end 126.161546 -3.800094)
		(stroke
			(width 0.2)
			(type default)
		)
		(layer "In1.Cu")
	)
	(gr_arc
		(start 126.161546 -3.800094)
		(mid 125.600206 -3.238754)
		(end 125.038866 -3.800094)
		(stroke
			(width 0.2)
			(type default)
		)
		(layer "In1.Cu")
	)
	(gr_arc
		(start 126.212346 -45.20438)
		(mid 126.248267 -45.189501)
		(end 126.263146 -45.15358)
		(stroke
			(width 0.2)
			(type default)
		)
		(layer "In1.Cu")
	)
	(gr_line
		(start 126.212346 -44.28998)
		(end 126.009146 -44.28998)
		(stroke
			(width 0.2)
			(type default)
		)
		(layer "In1.Cu")
	)
	(gr_line
		(start 126.263146 -45.15358)
		(end 126.263146 -44.34078)
		(stroke
			(width 0.2)
			(type default)
		)
		(layer "In1.Cu")
	)
	(gr_arc
		(start 126.263146 -44.34078)
		(mid 126.248267 -44.304859)
		(end 126.212346 -44.28998)
		(stroke
			(width 0.2)
			(type default)
		)
		(layer "In1.Cu")
	)
	(gr_arc
		(start 126.619508 -46.986952)
		(mid 127.076581 -47.444406)
		(end 127.533908 -46.987206)
		(stroke
			(width 0.2)
			(type default)
		)
		(layer "In1.Cu")
	)
	(gr_line
		(start 126.619508 -45.844206)
		(end 126.619508 -46.986952)
		(stroke
			(width 0.2)
			(type default)
		)
		(layer "In1.Cu")
	)
	(gr_arc
		(start 126.83871 -11.199876)
		(mid 127.399923 -11.76147)
		(end 127.96139 -11.20013)
		(stroke
			(width 0.2)
			(type default)
		)
		(layer "In1.Cu")
	)
	(gr_line
		(start 126.83871 -9.800082)
		(end 126.83871 -11.199876)
		(stroke
			(width 0.2)
			(type default)
		)
		(layer "In1.Cu")
	)
	(gr_arc
		(start 126.83871 -3.999738)
		(mid 127.399923 -4.561332)
		(end 127.96139 -3.999992)
		(stroke
			(width 0.2)
			(type default)
		)
		(layer "In1.Cu")
	)
	(gr_line
		(start 126.83871 -2.600198)
		(end 126.83871 -3.999738)
		(stroke
			(width 0.2)
			(type default)
		)
		(layer "In1.Cu")
	)
	(gr_arc
		(start 127 -77.35824)
		(mid 127.35814 -77.0001)
		(end 127 -76.64196)
		(stroke
			(width 0.2)
			(type default)
		)
		(layer "In1.Cu")
	)
	(gr_line
		(start 127 -76.64196)
		(end 126.000256 -76.64196)
		(stroke
			(width 0.2)
			(type default)
		)
		(layer "In1.Cu")
	)
	(gr_arc
		(start 127 -76.358242)
		(mid 127.35814 -76.000102)
		(end 127 -75.641962)
		(stroke
			(width 0.2)
			(type default)
		)
		(layer "In1.Cu")
	)
	(gr_line
		(start 127 -75.641962)
		(end 126.000256 -75.641962)
		(stroke
			(width 0.2)
			(type default)
		)
		(layer "In1.Cu")
	)
	(gr_arc
		(start 127 -75.358244)
		(mid 127.35814 -75.000104)
		(end 127 -74.641964)
		(stroke
			(width 0.2)
			(type default)
		)
		(layer "In1.Cu")
	)
	(gr_line
		(start 127 -74.641964)
		(end 126.000256 -74.641964)
		(stroke
			(width 0.2)
			(type default)
		)
		(layer "In1.Cu")
	)
	(gr_arc
		(start 127 -74.358246)
		(mid 127.35814 -74.000106)
		(end 127 -73.641966)
		(stroke
			(width 0.2)
			(type default)
		)
		(layer "In1.Cu")
	)
	(gr_line
		(start 127 -73.641966)
		(end 126.000256 -73.641966)
		(stroke
			(width 0.2)
			(type default)
		)
		(layer "In1.Cu")
	)
	(gr_arc
		(start 127 -73.358248)
		(mid 127.35814 -73.000108)
		(end 127 -72.641968)
		(stroke
			(width 0.2)
			(type default)
		)
		(layer "In1.Cu")
	)
	(gr_line
		(start 127 -72.641968)
		(end 126.000256 -72.641968)
		(stroke
			(width 0.2)
			(type default)
		)
		(layer "In1.Cu")
	)
	(gr_arc
		(start 127 -72.35825)
		(mid 127.35814 -72.00011)
		(end 127 -71.64197)
		(stroke
			(width 0.2)
			(type default)
		)
		(layer "In1.Cu")
	)
	(gr_line
		(start 127 -71.64197)
		(end 126.000256 -71.64197)
		(stroke
			(width 0.2)
			(type default)
		)
		(layer "In1.Cu")
	)
	(gr_arc
		(start 127 -71.358252)
		(mid 127.35814 -71.000112)
		(end 127 -70.641972)
		(stroke
			(width 0.2)
			(type default)
		)
		(layer "In1.Cu")
	)
	(gr_line
		(start 127 -70.641972)
		(end 126.000256 -70.641972)
		(stroke
			(width 0.2)
			(type default)
		)
		(layer "In1.Cu")
	)
	(gr_arc
		(start 127 -70.358254)
		(mid 127.35814 -70.000114)
		(end 127 -69.641974)
		(stroke
			(width 0.2)
			(type default)
		)
		(layer "In1.Cu")
	)
	(gr_line
		(start 127 -69.641974)
		(end 126.000256 -69.641974)
		(stroke
			(width 0.2)
			(type default)
		)
		(layer "In1.Cu")
	)
	(gr_arc
		(start 127 -69.358256)
		(mid 127.35814 -69.000116)
		(end 127 -68.641976)
		(stroke
			(width 0.2)
			(type default)
		)
		(layer "In1.Cu")
	)
	(gr_line
		(start 127 -68.641976)
		(end 126.000256 -68.641976)
		(stroke
			(width 0.2)
			(type default)
		)
		(layer "In1.Cu")
	)
	(gr_arc
		(start 127 -68.358258)
		(mid 127.35814 -68.000118)
		(end 127 -67.641978)
		(stroke
			(width 0.2)
			(type default)
		)
		(layer "In1.Cu")
	)
	(gr_line
		(start 127 -67.641978)
		(end 126.000256 -67.641978)
		(stroke
			(width 0.2)
			(type default)
		)
		(layer "In1.Cu")
	)
	(gr_arc
		(start 127 -66.358262)
		(mid 127.35814 -66.000122)
		(end 127 -65.641982)
		(stroke
			(width 0.2)
			(type default)
		)
		(layer "In1.Cu")
	)
	(gr_line
		(start 127 -65.641982)
		(end 126.000256 -65.641982)
		(stroke
			(width 0.2)
			(type default)
		)
		(layer "In1.Cu")
	)
	(gr_arc
		(start 127 -65.358264)
		(mid 127.35814 -65.000124)
		(end 127 -64.641984)
		(stroke
			(width 0.2)
			(type default)
		)
		(layer "In1.Cu")
	)
	(gr_line
		(start 127 -64.641984)
		(end 126.000256 -64.641984)
		(stroke
			(width 0.2)
			(type default)
		)
		(layer "In1.Cu")
	)
	(gr_arc
		(start 127 -64.358266)
		(mid 127.35814 -64.000126)
		(end 127 -63.641986)
		(stroke
			(width 0.2)
			(type default)
		)
		(layer "In1.Cu")
	)
	(gr_line
		(start 127 -63.641986)
		(end 126.000256 -63.641986)
		(stroke
			(width 0.2)
			(type default)
		)
		(layer "In1.Cu")
	)
	(gr_arc
		(start 127 -63.358268)
		(mid 127.35814 -63.000128)
		(end 127 -62.641988)
		(stroke
			(width 0.2)
			(type default)
		)
		(layer "In1.Cu")
	)
	(gr_line
		(start 127 -62.641988)
		(end 126.000256 -62.641988)
		(stroke
			(width 0.2)
			(type default)
		)
		(layer "In1.Cu")
	)
	(gr_arc
		(start 127 -62.35827)
		(mid 127.35814 -62.00013)
		(end 127 -61.64199)
		(stroke
			(width 0.2)
			(type default)
		)
		(layer "In1.Cu")
	)
	(gr_line
		(start 127 -61.64199)
		(end 126.000256 -61.64199)
		(stroke
			(width 0.2)
			(type default)
		)
		(layer "In1.Cu")
	)
	(gr_arc
		(start 127 -61.358272)
		(mid 127.35814 -61.000132)
		(end 127 -60.641992)
		(stroke
			(width 0.2)
			(type default)
		)
		(layer "In1.Cu")
	)
	(gr_line
		(start 127 -60.641992)
		(end 126.000256 -60.641992)
		(stroke
			(width 0.2)
			(type default)
		)
		(layer "In1.Cu")
	)
	(gr_arc
		(start 127 -60.358274)
		(mid 127.35814 -60.000134)
		(end 127 -59.641994)
		(stroke
			(width 0.2)
			(type default)
		)
		(layer "In1.Cu")
	)
	(gr_line
		(start 127 -59.641994)
		(end 126.000256 -59.641994)
		(stroke
			(width 0.2)
			(type default)
		)
		(layer "In1.Cu")
	)
	(gr_arc
		(start 127 -59.358276)
		(mid 127.35814 -59.000136)
		(end 127 -58.641996)
		(stroke
			(width 0.2)
			(type default)
		)
		(layer "In1.Cu")
	)
	(gr_line
		(start 127 -58.641996)
		(end 126.000256 -58.641996)
		(stroke
			(width 0.2)
			(type default)
		)
		(layer "In1.Cu")
	)
	(gr_arc
		(start 127 -58.358278)
		(mid 127.35814 -58.000138)
		(end 127 -57.641998)
		(stroke
			(width 0.2)
			(type default)
		)
		(layer "In1.Cu")
	)
	(gr_line
		(start 127 -57.641998)
		(end 126.000256 -57.641998)
		(stroke
			(width 0.2)
			(type default)
		)
		(layer "In1.Cu")
	)
	(gr_arc
		(start 127 -57.35828)
		(mid 127.35814 -57.00014)
		(end 127 -56.642)
		(stroke
			(width 0.2)
			(type default)
		)
		(layer "In1.Cu")
	)
	(gr_line
		(start 127 -56.642)
		(end 126.000256 -56.642)
		(stroke
			(width 0.2)
			(type default)
		)
		(layer "In1.Cu")
	)
	(gr_arc
		(start 127 -56.358282)
		(mid 127.35814 -56.000142)
		(end 127 -55.642002)
		(stroke
			(width 0.2)
			(type default)
		)
		(layer "In1.Cu")
	)
	(gr_line
		(start 127 -55.642002)
		(end 126.000256 -55.642002)
		(stroke
			(width 0.2)
			(type default)
		)
		(layer "In1.Cu")
	)
	(gr_arc
		(start 127 -55.358284)
		(mid 127.35814 -55.000144)
		(end 127 -54.642004)
		(stroke
			(width 0.2)
			(type default)
		)
		(layer "In1.Cu")
	)
	(gr_line
		(start 127 -54.642004)
		(end 126.000256 -54.642004)
		(stroke
			(width 0.2)
			(type default)
		)
		(layer "In1.Cu")
	)
	(gr_arc
		(start 127 -54.358286)
		(mid 127.35814 -54.000146)
		(end 127 -53.642006)
		(stroke
			(width 0.2)
			(type default)
		)
		(layer "In1.Cu")
	)
	(gr_line
		(start 127 -53.642006)
		(end 126.000256 -53.642006)
		(stroke
			(width 0.2)
			(type default)
		)
		(layer "In1.Cu")
	)
	(gr_line
		(start 127 -53.358288)
		(end 127.999998 -53.358288)
		(stroke
			(width 0.2)
			(type default)
		)
		(layer "In1.Cu")
	)
	(gr_arc
		(start 127.000254 -52.642008)
		(mid 126.64186 -53.000021)
		(end 127 -53.358288)
		(stroke
			(width 0.2)
			(type default)
		)
		(layer "In1.Cu")
	)
	(gr_line
		(start 127.533908 -46.987206)
		(end 127.533908 -45.844206)
		(stroke
			(width 0.2)
			(type default)
		)
		(layer "In1.Cu")
	)
	(gr_arc
		(start 127.533908 -45.844206)
		(mid 127.076708 -45.387006)
		(end 126.619508 -45.844206)
		(stroke
			(width 0.2)
			(type default)
		)
		(layer "In1.Cu")
	)
	(gr_arc
		(start 127.84963 -45.138848)
		(mid 127.864509 -45.174769)
		(end 127.90043 -45.189648)
		(stroke
			(width 0.2)
			(type default)
		)
		(layer "In1.Cu")
	)
	(gr_line
		(start 127.84963 -44.326048)
		(end 127.84963 -45.138848)
		(stroke
			(width 0.2)
			(type default)
		)
		(layer "In1.Cu")
	)
	(gr_line
		(start 127.90043 -45.189648)
		(end 128.10363 -45.189648)
		(stroke
			(width 0.2)
			(type default)
		)
		(layer "In1.Cu")
	)
	(gr_arc
		(start 127.90043 -44.275248)
		(mid 127.864509 -44.290127)
		(end 127.84963 -44.326048)
		(stroke
			(width 0.2)
			(type default)
		)
		(layer "In1.Cu")
	)
	(gr_line
		(start 127.96139 -11.20013)
		(end 127.96139 -9.800082)
		(stroke
			(width 0.2)
			(type default)
		)
		(layer "In1.Cu")
	)
	(gr_arc
		(start 127.96139 -9.800082)
		(mid 127.40005 -9.238742)
		(end 126.83871 -9.800082)
		(stroke
			(width 0.2)
			(type default)
		)
		(layer "In1.Cu")
	)
	(gr_line
		(start 127.96139 -3.999992)
		(end 127.96139 -2.600198)
		(stroke
			(width 0.2)
			(type default)
		)
		(layer "In1.Cu")
	)
	(gr_arc
		(start 127.96139 -2.600198)
		(mid 127.40005 -2.038858)
		(end 126.83871 -2.600198)
		(stroke
			(width 0.2)
			(type default)
		)
		(layer "In1.Cu")
	)
	(gr_arc
		(start 127.999998 -53.358288)
		(mid 128.358138 -53.000148)
		(end 127.999998 -52.642008)
		(stroke
			(width 0.2)
			(type default)
		)
		(layer "In1.Cu")
	)
	(gr_line
		(start 127.999998 -52.642008)
		(end 127.000254 -52.642008)
		(stroke
			(width 0.2)
			(type default)
		)
		(layer "In1.Cu")
	)
	(gr_arc
		(start 128.10363 -45.189648)
		(mid 128.139551 -45.174769)
		(end 128.15443 -45.138848)
		(stroke
			(width 0.2)
			(type default)
		)
		(layer "In1.Cu")
	)
	(gr_line
		(start 128.10363 -44.275248)
		(end 127.90043 -44.275248)
		(stroke
			(width 0.2)
			(type default)
		)
		(layer "In1.Cu")
	)
	(gr_line
		(start 128.15443 -45.138848)
		(end 128.15443 -44.326048)
		(stroke
			(width 0.2)
			(type default)
		)
		(layer "In1.Cu")
	)
	(gr_arc
		(start 128.15443 -44.326048)
		(mid 128.139551 -44.290127)
		(end 128.10363 -44.275248)
		(stroke
			(width 0.2)
			(type default)
		)
		(layer "In1.Cu")
	)
	(gr_arc
		(start 128.43383 -45.138848)
		(mid 128.448709 -45.174769)
		(end 128.48463 -45.189648)
		(stroke
			(width 0.2)
			(type default)
		)
		(layer "In1.Cu")
	)
	(gr_line
		(start 128.43383 -44.326048)
		(end 128.43383 -45.138848)
		(stroke
			(width 0.2)
			(type default)
		)
		(layer "In1.Cu")
	)
	(gr_line
		(start 128.48463 -45.189648)
		(end 128.68783 -45.189648)
		(stroke
			(width 0.2)
			(type default)
		)
		(layer "In1.Cu")
	)
	(gr_arc
		(start 128.48463 -44.275248)
		(mid 128.448709 -44.290127)
		(end 128.43383 -44.326048)
		(stroke
			(width 0.2)
			(type default)
		)
		(layer "In1.Cu")
	)
	(gr_arc
		(start 128.638808 -12.399772)
		(mid 129.200021 -12.961366)
		(end 129.761488 -12.400026)
		(stroke
			(width 0.2)
			(type default)
		)
		(layer "In1.Cu")
	)
	(gr_line
		(start 128.638808 -10.999978)
		(end 128.638808 -12.399772)
		(stroke
			(width 0.2)
			(type default)
		)
		(layer "In1.Cu")
	)
	(gr_arc
		(start 128.638808 -5.199888)
		(mid 129.200021 -5.761482)
		(end 129.761488 -5.200142)
		(stroke
			(width 0.2)
			(type default)
		)
		(layer "In1.Cu")
	)
	(gr_line
		(start 128.638808 -3.800094)
		(end 128.638808 -5.199888)
		(stroke
			(width 0.2)
			(type default)
		)
		(layer "In1.Cu")
	)
	(gr_arc
		(start 128.68783 -45.189648)
		(mid 128.723751 -45.174769)
		(end 128.73863 -45.138848)
		(stroke
			(width 0.2)
			(type default)
		)
		(layer "In1.Cu")
	)
	(gr_line
		(start 128.68783 -44.275248)
		(end 128.48463 -44.275248)
		(stroke
			(width 0.2)
			(type default)
		)
		(layer "In1.Cu")
	)
	(gr_line
		(start 128.73863 -45.138848)
		(end 128.73863 -44.326048)
		(stroke
			(width 0.2)
			(type default)
		)
		(layer "In1.Cu")
	)
	(gr_arc
		(start 128.73863 -44.326048)
		(mid 128.723751 -44.290127)
		(end 128.68783 -44.275248)
		(stroke
			(width 0.2)
			(type default)
		)
		(layer "In1.Cu")
	)
	(gr_line
		(start 128.999996 -72.35825)
		(end 129.999994 -72.35825)
		(stroke
			(width 0.2)
			(type default)
		)
		(layer "In1.Cu")
	)
	(gr_line
		(start 128.999996 -70.358254)
		(end 129.999994 -70.358254)
		(stroke
			(width 0.2)
			(type default)
		)
		(layer "In1.Cu")
	)
	(gr_line
		(start 128.999996 -68.358258)
		(end 129.999994 -68.358258)
		(stroke
			(width 0.2)
			(type default)
		)
		(layer "In1.Cu")
	)
	(gr_line
		(start 128.999996 -65.358264)
		(end 129.999994 -65.358264)
		(stroke
			(width 0.2)
			(type default)
		)
		(layer "In1.Cu")
	)
	(gr_line
		(start 128.999996 -63.358268)
		(end 129.999994 -63.358268)
		(stroke
			(width 0.2)
			(type default)
		)
		(layer "In1.Cu")
	)
	(gr_line
		(start 128.999996 -61.358272)
		(end 129.999994 -61.358272)
		(stroke
			(width 0.2)
			(type default)
		)
		(layer "In1.Cu")
	)
	(gr_arc
		(start 129.00025 -71.64197)
		(mid 128.641856 -71.999983)
		(end 128.999996 -72.35825)
		(stroke
			(width 0.2)
			(type default)
		)
		(layer "In1.Cu")
	)
	(gr_arc
		(start 129.00025 -69.641974)
		(mid 128.641856 -69.999987)
		(end 128.999996 -70.358254)
		(stroke
			(width 0.2)
			(type default)
		)
		(layer "In1.Cu")
	)
	(gr_arc
		(start 129.00025 -67.641978)
		(mid 128.641856 -67.999991)
		(end 128.999996 -68.358258)
		(stroke
			(width 0.2)
			(type default)
		)
		(layer "In1.Cu")
	)
	(gr_arc
		(start 129.00025 -64.641984)
		(mid 128.641856 -64.999997)
		(end 128.999996 -65.358264)
		(stroke
			(width 0.2)
			(type default)
		)
		(layer "In1.Cu")
	)
	(gr_arc
		(start 129.00025 -62.641988)
		(mid 128.641856 -63.000001)
		(end 128.999996 -63.358268)
		(stroke
			(width 0.2)
			(type default)
		)
		(layer "In1.Cu")
	)
	(gr_arc
		(start 129.00025 -60.641992)
		(mid 128.641856 -61.000005)
		(end 128.999996 -61.358272)
		(stroke
			(width 0.2)
			(type default)
		)
		(layer "In1.Cu")
	)
	(gr_arc
		(start 129.191258 -46.97222)
		(mid 129.648331 -47.429674)
		(end 130.105658 -46.972474)
		(stroke
			(width 0.2)
			(type default)
		)
		(layer "In1.Cu")
	)
	(gr_line
		(start 129.191258 -45.829474)
		(end 129.191258 -46.97222)
		(stroke
			(width 0.2)
			(type default)
		)
		(layer "In1.Cu")
	)
	(gr_line
		(start 129.761488 -12.400026)
		(end 129.761488 -10.999978)
		(stroke
			(width 0.2)
			(type default)
		)
		(layer "In1.Cu")
	)
	(gr_arc
		(start 129.761488 -10.999978)
		(mid 129.200148 -10.438638)
		(end 128.638808 -10.999978)
		(stroke
			(width 0.2)
			(type default)
		)
		(layer "In1.Cu")
	)
	(gr_line
		(start 129.761488 -5.200142)
		(end 129.761488 -3.800094)
		(stroke
			(width 0.2)
			(type default)
		)
		(layer "In1.Cu")
	)
	(gr_arc
		(start 129.761488 -3.800094)
		(mid 129.200148 -3.238754)
		(end 128.638808 -3.800094)
		(stroke
			(width 0.2)
			(type default)
		)
		(layer "In1.Cu")
	)
	(gr_line
		(start 129.999994 -73.358248)
		(end 130.999992 -73.358248)
		(stroke
			(width 0.2)
			(type default)
		)
		(layer "In1.Cu")
	)
	(gr_arc
		(start 129.999994 -72.35825)
		(mid 130.358134 -72.00011)
		(end 129.999994 -71.64197)
		(stroke
			(width 0.2)
			(type default)
		)
		(layer "In1.Cu")
	)
	(gr_line
		(start 129.999994 -71.64197)
		(end 129.00025 -71.64197)
		(stroke
			(width 0.2)
			(type default)
		)
		(layer "In1.Cu")
	)
	(gr_line
		(start 129.999994 -71.358252)
		(end 130.999992 -71.358252)
		(stroke
			(width 0.2)
			(type default)
		)
		(layer "In1.Cu")
	)
	(gr_arc
		(start 129.999994 -70.358254)
		(mid 130.358134 -70.000114)
		(end 129.999994 -69.641974)
		(stroke
			(width 0.2)
			(type default)
		)
		(layer "In1.Cu")
	)
	(gr_line
		(start 129.999994 -69.641974)
		(end 129.00025 -69.641974)
		(stroke
			(width 0.2)
			(type default)
		)
		(layer "In1.Cu")
	)
	(gr_line
		(start 129.999994 -69.358256)
		(end 130.999992 -69.358256)
		(stroke
			(width 0.2)
			(type default)
		)
		(layer "In1.Cu")
	)
	(gr_arc
		(start 129.999994 -68.358258)
		(mid 130.358134 -68.000118)
		(end 129.999994 -67.641978)
		(stroke
			(width 0.2)
			(type default)
		)
		(layer "In1.Cu")
	)
	(gr_line
		(start 129.999994 -67.641978)
		(end 129.00025 -67.641978)
		(stroke
			(width 0.2)
			(type default)
		)
		(layer "In1.Cu")
	)
	(gr_line
		(start 129.999994 -66.358262)
		(end 130.999992 -66.358262)
		(stroke
			(width 0.2)
			(type default)
		)
		(layer "In1.Cu")
	)
	(gr_arc
		(start 129.999994 -65.358264)
		(mid 130.358134 -65.000124)
		(end 129.999994 -64.641984)
		(stroke
			(width 0.2)
			(type default)
		)
		(layer "In1.Cu")
	)
	(gr_line
		(start 129.999994 -64.641984)
		(end 129.00025 -64.641984)
		(stroke
			(width 0.2)
			(type default)
		)
		(layer "In1.Cu")
	)
	(gr_line
		(start 129.999994 -64.358266)
		(end 130.999992 -64.358266)
		(stroke
			(width 0.2)
			(type default)
		)
		(layer "In1.Cu")
	)
	(gr_arc
		(start 129.999994 -63.358268)
		(mid 130.358134 -63.000128)
		(end 129.999994 -62.641988)
		(stroke
			(width 0.2)
			(type default)
		)
		(layer "In1.Cu")
	)
	(gr_line
		(start 129.999994 -62.641988)
		(end 129.00025 -62.641988)
		(stroke
			(width 0.2)
			(type default)
		)
		(layer "In1.Cu")
	)
	(gr_line
		(start 129.999994 -62.35827)
		(end 130.999992 -62.35827)
		(stroke
			(width 0.2)
			(type default)
		)
		(layer "In1.Cu")
	)
	(gr_arc
		(start 129.999994 -61.358272)
		(mid 130.358134 -61.000132)
		(end 129.999994 -60.641992)
		(stroke
			(width 0.2)
			(type default)
		)
		(layer "In1.Cu")
	)
	(gr_line
		(start 129.999994 -60.641992)
		(end 129.00025 -60.641992)
		(stroke
			(width 0.2)
			(type default)
		)
		(layer "In1.Cu")
	)
	(gr_arc
		(start 130.000248 -72.641968)
		(mid 129.641854 -72.999981)
		(end 129.999994 -73.358248)
		(stroke
			(width 0.2)
			(type default)
		)
		(layer "In1.Cu")
	)
	(gr_arc
		(start 130.000248 -70.641972)
		(mid 129.641854 -70.999985)
		(end 129.999994 -71.358252)
		(stroke
			(width 0.2)
			(type default)
		)
		(layer "In1.Cu")
	)
	(gr_arc
		(start 130.000248 -68.641976)
		(mid 129.641854 -68.999989)
		(end 129.999994 -69.358256)
		(stroke
			(width 0.2)
			(type default)
		)
		(layer "In1.Cu")
	)
	(gr_arc
		(start 130.000248 -65.641982)
		(mid 129.641854 -65.999995)
		(end 129.999994 -66.358262)
		(stroke
			(width 0.2)
			(type default)
		)
		(layer "In1.Cu")
	)
	(gr_arc
		(start 130.000248 -63.641986)
		(mid 129.641854 -63.999999)
		(end 129.999994 -64.358266)
		(stroke
			(width 0.2)
			(type default)
		)
		(layer "In1.Cu")
	)
	(gr_arc
		(start 130.000248 -61.64199)
		(mid 129.641854 -62.000003)
		(end 129.999994 -62.35827)
		(stroke
			(width 0.2)
			(type default)
		)
		(layer "In1.Cu")
	)
	(gr_line
		(start 130.105658 -46.972474)
		(end 130.105658 -45.829474)
		(stroke
			(width 0.2)
			(type default)
		)
		(layer "In1.Cu")
	)
	(gr_arc
		(start 130.105658 -45.829474)
		(mid 129.648458 -45.372274)
		(end 129.191258 -45.829474)
		(stroke
			(width 0.2)
			(type default)
		)
		(layer "In1.Cu")
	)
	(gr_arc
		(start 130.42138 -45.124116)
		(mid 130.436259 -45.160037)
		(end 130.47218 -45.174916)
		(stroke
			(width 0.2)
			(type default)
		)
		(layer "In1.Cu")
	)
	(gr_line
		(start 130.42138 -44.311316)
		(end 130.42138 -45.124116)
		(stroke
			(width 0.2)
			(type default)
		)
		(layer "In1.Cu")
	)
	(gr_arc
		(start 130.438652 -11.199876)
		(mid 130.999865 -11.76147)
		(end 131.561332 -11.20013)
		(stroke
			(width 0.2)
			(type default)
		)
		(layer "In1.Cu")
	)
	(gr_line
		(start 130.438652 -9.800082)
		(end 130.438652 -11.199876)
		(stroke
			(width 0.2)
			(type default)
		)
		(layer "In1.Cu")
	)
	(gr_arc
		(start 130.438652 -3.999738)
		(mid 130.999865 -4.561332)
		(end 131.561332 -3.999992)
		(stroke
			(width 0.2)
			(type default)
		)
		(layer "In1.Cu")
	)
	(gr_line
		(start 130.438652 -2.600198)
		(end 130.438652 -3.999738)
		(stroke
			(width 0.2)
			(type default)
		)
		(layer "In1.Cu")
	)
	(gr_line
		(start 130.47218 -45.174916)
		(end 130.67538 -45.174916)
		(stroke
			(width 0.2)
			(type default)
		)
		(layer "In1.Cu")
	)
	(gr_arc
		(start 130.47218 -44.260516)
		(mid 130.436259 -44.275395)
		(end 130.42138 -44.311316)
		(stroke
			(width 0.2)
			(type default)
		)
		(layer "In1.Cu")
	)
	(gr_arc
		(start 130.67538 -45.174916)
		(mid 130.711301 -45.160037)
		(end 130.72618 -45.124116)
		(stroke
			(width 0.2)
			(type default)
		)
		(layer "In1.Cu")
	)
	(gr_line
		(start 130.67538 -44.260516)
		(end 130.47218 -44.260516)
		(stroke
			(width 0.2)
			(type default)
		)
		(layer "In1.Cu")
	)
	(gr_line
		(start 130.72618 -45.124116)
		(end 130.72618 -44.311316)
		(stroke
			(width 0.2)
			(type default)
		)
		(layer "In1.Cu")
	)
	(gr_arc
		(start 130.72618 -44.311316)
		(mid 130.711301 -44.275395)
		(end 130.67538 -44.260516)
		(stroke
			(width 0.2)
			(type default)
		)
		(layer "In1.Cu")
	)
	(gr_arc
		(start 130.999992 -73.358248)
		(mid 131.358132 -73.000108)
		(end 130.999992 -72.641968)
		(stroke
			(width 0.2)
			(type default)
		)
		(layer "In1.Cu")
	)
	(gr_line
		(start 130.999992 -72.641968)
		(end 130.000248 -72.641968)
		(stroke
			(width 0.2)
			(type default)
		)
		(layer "In1.Cu")
	)
	(gr_arc
		(start 130.999992 -71.358252)
		(mid 131.358132 -71.000112)
		(end 130.999992 -70.641972)
		(stroke
			(width 0.2)
			(type default)
		)
		(layer "In1.Cu")
	)
	(gr_line
		(start 130.999992 -70.641972)
		(end 130.000248 -70.641972)
		(stroke
			(width 0.2)
			(type default)
		)
		(layer "In1.Cu")
	)
	(gr_arc
		(start 130.999992 -69.358256)
		(mid 131.358132 -69.000116)
		(end 130.999992 -68.641976)
		(stroke
			(width 0.2)
			(type default)
		)
		(layer "In1.Cu")
	)
	(gr_line
		(start 130.999992 -68.641976)
		(end 130.000248 -68.641976)
		(stroke
			(width 0.2)
			(type default)
		)
		(layer "In1.Cu")
	)
	(gr_arc
		(start 130.999992 -66.358262)
		(mid 131.358132 -66.000122)
		(end 130.999992 -65.641982)
		(stroke
			(width 0.2)
			(type default)
		)
		(layer "In1.Cu")
	)
	(gr_line
		(start 130.999992 -65.641982)
		(end 130.000248 -65.641982)
		(stroke
			(width 0.2)
			(type default)
		)
		(layer "In1.Cu")
	)
	(gr_arc
		(start 130.999992 -64.358266)
		(mid 131.358132 -64.000126)
		(end 130.999992 -63.641986)
		(stroke
			(width 0.2)
			(type default)
		)
		(layer "In1.Cu")
	)
	(gr_line
		(start 130.999992 -63.641986)
		(end 130.000248 -63.641986)
		(stroke
			(width 0.2)
			(type default)
		)
		(layer "In1.Cu")
	)
	(gr_arc
		(start 130.999992 -62.35827)
		(mid 131.358132 -62.00013)
		(end 130.999992 -61.64199)
		(stroke
			(width 0.2)
			(type default)
		)
		(layer "In1.Cu")
	)
	(gr_line
		(start 130.999992 -61.64199)
		(end 130.000248 -61.64199)
		(stroke
			(width 0.2)
			(type default)
		)
		(layer "In1.Cu")
	)
	(gr_arc
		(start 131.00558 -45.124116)
		(mid 131.020459 -45.160037)
		(end 131.05638 -45.174916)
		(stroke
			(width 0.2)
			(type default)
		)
		(layer "In1.Cu")
	)
	(gr_line
		(start 131.00558 -44.311316)
		(end 131.00558 -45.124116)
		(stroke
			(width 0.2)
			(type default)
		)
		(layer "In1.Cu")
	)
	(gr_line
		(start 131.05638 -45.174916)
		(end 131.25958 -45.174916)
		(stroke
			(width 0.2)
			(type default)
		)
		(layer "In1.Cu")
	)
	(gr_arc
		(start 131.05638 -44.260516)
		(mid 131.020459 -44.275395)
		(end 131.00558 -44.311316)
		(stroke
			(width 0.2)
			(type default)
		)
		(layer "In1.Cu")
	)
	(gr_arc
		(start 131.25958 -45.174916)
		(mid 131.295501 -45.160037)
		(end 131.31038 -45.124116)
		(stroke
			(width 0.2)
			(type default)
		)
		(layer "In1.Cu")
	)
	(gr_line
		(start 131.25958 -44.260516)
		(end 131.05638 -44.260516)
		(stroke
			(width 0.2)
			(type default)
		)
		(layer "In1.Cu")
	)
	(gr_line
		(start 131.31038 -45.124116)
		(end 131.31038 -44.311316)
		(stroke
			(width 0.2)
			(type default)
		)
		(layer "In1.Cu")
	)
	(gr_arc
		(start 131.31038 -44.311316)
		(mid 131.295501 -44.275395)
		(end 131.25958 -44.260516)
		(stroke
			(width 0.2)
			(type default)
		)
		(layer "In1.Cu")
	)
	(gr_line
		(start 131.561332 -11.20013)
		(end 131.561332 -9.800082)
		(stroke
			(width 0.2)
			(type default)
		)
		(layer "In1.Cu")
	)
	(gr_arc
		(start 131.561332 -9.800082)
		(mid 130.999992 -9.238742)
		(end 130.438652 -9.800082)
		(stroke
			(width 0.2)
			(type default)
		)
		(layer "In1.Cu")
	)
	(gr_line
		(start 131.561332 -3.999992)
		(end 131.561332 -2.600198)
		(stroke
			(width 0.2)
			(type default)
		)
		(layer "In1.Cu")
	)
	(gr_arc
		(start 131.561332 -2.600198)
		(mid 130.999992 -2.038858)
		(end 130.438652 -2.600198)
		(stroke
			(width 0.2)
			(type default)
		)
		(layer "In1.Cu")
	)
	(gr_arc
		(start 131.763008 -46.957488)
		(mid 132.220081 -47.414942)
		(end 132.677408 -46.957742)
		(stroke
			(width 0.2)
			(type default)
		)
		(layer "In1.Cu")
	)
	(gr_line
		(start 131.763008 -45.814742)
		(end 131.763008 -46.957488)
		(stroke
			(width 0.2)
			(type default)
		)
		(layer "In1.Cu")
	)
	(gr_arc
		(start 132.23875 -12.399772)
		(mid 132.799963 -12.961366)
		(end 133.36143 -12.400026)
		(stroke
			(width 0.2)
			(type default)
		)
		(layer "In1.Cu")
	)
	(gr_line
		(start 132.23875 -10.999978)
		(end 132.23875 -12.399772)
		(stroke
			(width 0.2)
			(type default)
		)
		(layer "In1.Cu")
	)
	(gr_arc
		(start 132.23875 -5.199888)
		(mid 132.799963 -5.761482)
		(end 133.36143 -5.200142)
		(stroke
			(width 0.2)
			(type default)
		)
		(layer "In1.Cu")
	)
	(gr_line
		(start 132.23875 -3.800094)
		(end 132.23875 -5.199888)
		(stroke
			(width 0.2)
			(type default)
		)
		(layer "In1.Cu")
	)
	(gr_line
		(start 132.677408 -46.957742)
		(end 132.677408 -45.814742)
		(stroke
			(width 0.2)
			(type default)
		)
		(layer "In1.Cu")
	)
	(gr_arc
		(start 132.677408 -45.814742)
		(mid 132.220208 -45.357542)
		(end 131.763008 -45.814742)
		(stroke
			(width 0.2)
			(type default)
		)
		(layer "In1.Cu")
	)
	(gr_arc
		(start 132.99313 -45.109384)
		(mid 133.008009 -45.145305)
		(end 133.04393 -45.160184)
		(stroke
			(width 0.2)
			(type default)
		)
		(layer "In1.Cu")
	)
	(gr_line
		(start 132.99313 -44.296584)
		(end 132.99313 -45.109384)
		(stroke
			(width 0.2)
			(type default)
		)
		(layer "In1.Cu")
	)
	(gr_line
		(start 133.04393 -45.160184)
		(end 133.24713 -45.160184)
		(stroke
			(width 0.2)
			(type default)
		)
		(layer "In1.Cu")
	)
	(gr_arc
		(start 133.04393 -44.245784)
		(mid 133.008009 -44.260663)
		(end 132.99313 -44.296584)
		(stroke
			(width 0.2)
			(type default)
		)
		(layer "In1.Cu")
	)
	(gr_arc
		(start 133.24713 -45.160184)
		(mid 133.283051 -45.145305)
		(end 133.29793 -45.109384)
		(stroke
			(width 0.2)
			(type default)
		)
		(layer "In1.Cu")
	)
	(gr_line
		(start 133.24713 -44.245784)
		(end 133.04393 -44.245784)
		(stroke
			(width 0.2)
			(type default)
		)
		(layer "In1.Cu")
	)
	(gr_line
		(start 133.29793 -45.109384)
		(end 133.29793 -44.296584)
		(stroke
			(width 0.2)
			(type default)
		)
		(layer "In1.Cu")
	)
	(gr_arc
		(start 133.29793 -44.296584)
		(mid 133.283051 -44.260663)
		(end 133.24713 -44.245784)
		(stroke
			(width 0.2)
			(type default)
		)
		(layer "In1.Cu")
	)
	(gr_line
		(start 133.36143 -12.400026)
		(end 133.36143 -10.999978)
		(stroke
			(width 0.2)
			(type default)
		)
		(layer "In1.Cu")
	)
	(gr_arc
		(start 133.36143 -10.999978)
		(mid 132.80009 -10.438638)
		(end 132.23875 -10.999978)
		(stroke
			(width 0.2)
			(type default)
		)
		(layer "In1.Cu")
	)
	(gr_line
		(start 133.36143 -5.200142)
		(end 133.36143 -3.800094)
		(stroke
			(width 0.2)
			(type default)
		)
		(layer "In1.Cu")
	)
	(gr_arc
		(start 133.36143 -3.800094)
		(mid 132.80009 -3.238754)
		(end 132.23875 -3.800094)
		(stroke
			(width 0.2)
			(type default)
		)
		(layer "In1.Cu")
	)
	(gr_arc
		(start 133.57733 -45.109384)
		(mid 133.592209 -45.145305)
		(end 133.62813 -45.160184)
		(stroke
			(width 0.2)
			(type default)
		)
		(layer "In1.Cu")
	)
	(gr_line
		(start 133.57733 -44.296584)
		(end 133.57733 -45.109384)
		(stroke
			(width 0.2)
			(type default)
		)
		(layer "In1.Cu")
	)
	(gr_line
		(start 133.62813 -45.160184)
		(end 133.83133 -45.160184)
		(stroke
			(width 0.2)
			(type default)
		)
		(layer "In1.Cu")
	)
	(gr_arc
		(start 133.62813 -44.245784)
		(mid 133.592209 -44.260663)
		(end 133.57733 -44.296584)
		(stroke
			(width 0.2)
			(type default)
		)
		(layer "In1.Cu")
	)
	(gr_arc
		(start 133.83133 -45.160184)
		(mid 133.867251 -45.145305)
		(end 133.88213 -45.109384)
		(stroke
			(width 0.2)
			(type default)
		)
		(layer "In1.Cu")
	)
	(gr_line
		(start 133.83133 -44.245784)
		(end 133.62813 -44.245784)
		(stroke
			(width 0.2)
			(type default)
		)
		(layer "In1.Cu")
	)
	(gr_line
		(start 133.88213 -45.109384)
		(end 133.88213 -44.296584)
		(stroke
			(width 0.2)
			(type default)
		)
		(layer "In1.Cu")
	)
	(gr_arc
		(start 133.88213 -44.296584)
		(mid 133.867251 -44.260663)
		(end 133.83133 -44.245784)
		(stroke
			(width 0.2)
			(type default)
		)
		(layer "In1.Cu")
	)
	(gr_arc
		(start 134.038848 -11.199876)
		(mid 134.600061 -11.76147)
		(end 135.161528 -11.20013)
		(stroke
			(width 0.2)
			(type default)
		)
		(layer "In1.Cu")
	)
	(gr_line
		(start 134.038848 -9.800082)
		(end 134.038848 -11.199876)
		(stroke
			(width 0.2)
			(type default)
		)
		(layer "In1.Cu")
	)
	(gr_arc
		(start 134.038848 -3.999738)
		(mid 134.600061 -4.561332)
		(end 135.161528 -3.999992)
		(stroke
			(width 0.2)
			(type default)
		)
		(layer "In1.Cu")
	)
	(gr_line
		(start 134.038848 -2.600198)
		(end 134.038848 -3.999738)
		(stroke
			(width 0.2)
			(type default)
		)
		(layer "In1.Cu")
	)
	(gr_line
		(start 135.161528 -11.20013)
		(end 135.161528 -9.800082)
		(stroke
			(width 0.2)
			(type default)
		)
		(layer "In1.Cu")
	)
	(gr_arc
		(start 135.161528 -9.800082)
		(mid 134.600188 -9.238742)
		(end 134.038848 -9.800082)
		(stroke
			(width 0.2)
			(type default)
		)
		(layer "In1.Cu")
	)
	(gr_line
		(start 135.161528 -3.999992)
		(end 135.161528 -2.600198)
		(stroke
			(width 0.2)
			(type default)
		)
		(layer "In1.Cu")
	)
	(gr_arc
		(start 135.161528 -2.600198)
		(mid 134.600188 -2.038858)
		(end 134.038848 -2.600198)
		(stroke
			(width 0.2)
			(type default)
		)
		(layer "In1.Cu")
	)
	(gr_arc
		(start 135.724392 -77.932534)
		(mid 135.739271 -77.968455)
		(end 135.775192 -77.983334)
		(stroke
			(width 0.2)
			(type default)
		)
		(layer "In1.Cu")
	)
	(gr_line
		(start 135.724392 -77.729334)
		(end 135.724392 -77.932534)
		(stroke
			(width 0.2)
			(type default)
		)
		(layer "In1.Cu")
	)
	(gr_arc
		(start 135.724392 -77.373734)
		(mid 135.739271 -77.409655)
		(end 135.775192 -77.424534)
		(stroke
			(width 0.2)
			(type default)
		)
		(layer "In1.Cu")
	)
	(gr_line
		(start 135.724392 -77.170534)
		(end 135.724392 -77.373734)
		(stroke
			(width 0.2)
			(type default)
		)
		(layer "In1.Cu")
	)
	(gr_arc
		(start 135.770112 -79.831692)
		(mid 135.784991 -79.867613)
		(end 135.820912 -79.882492)
		(stroke
			(width 0.2)
			(type default)
		)
		(layer "In1.Cu")
	)
	(gr_line
		(start 135.770112 -79.628492)
		(end 135.770112 -79.831692)
		(stroke
			(width 0.2)
			(type default)
		)
		(layer "In1.Cu")
	)
	(gr_arc
		(start 135.770112 -79.272892)
		(mid 135.784991 -79.308813)
		(end 135.820912 -79.323692)
		(stroke
			(width 0.2)
			(type default)
		)
		(layer "In1.Cu")
	)
	(gr_line
		(start 135.770112 -79.069692)
		(end 135.770112 -79.272892)
		(stroke
			(width 0.2)
			(type default)
		)
		(layer "In1.Cu")
	)
	(gr_line
		(start 135.775192 -77.983334)
		(end 136.587992 -77.983334)
		(stroke
			(width 0.2)
			(type default)
		)
		(layer "In1.Cu")
	)
	(gr_arc
		(start 135.775192 -77.678534)
		(mid 135.739271 -77.693413)
		(end 135.724392 -77.729334)
		(stroke
			(width 0.2)
			(type default)
		)
		(layer "In1.Cu")
	)
	(gr_line
		(start 135.775192 -77.424534)
		(end 136.587992 -77.424534)
		(stroke
			(width 0.2)
			(type default)
		)
		(layer "In1.Cu")
	)
	(gr_arc
		(start 135.775192 -77.119734)
		(mid 135.739271 -77.134613)
		(end 135.724392 -77.170534)
		(stroke
			(width 0.2)
			(type default)
		)
		(layer "In1.Cu")
	)
	(gr_arc
		(start 135.7884 -81.2292)
		(mid 135.803279 -81.265121)
		(end 135.8392 -81.28)
		(stroke
			(width 0.2)
			(type default)
		)
		(layer "In1.Cu")
	)
	(gr_line
		(start 135.7884 -81.026)
		(end 135.7884 -81.2292)
		(stroke
			(width 0.2)
			(type default)
		)
		(layer "In1.Cu")
	)
	(gr_arc
		(start 135.7884 -80.6704)
		(mid 135.803279 -80.706321)
		(end 135.8392 -80.7212)
		(stroke
			(width 0.2)
			(type default)
		)
		(layer "In1.Cu")
	)
	(gr_line
		(start 135.7884 -80.4672)
		(end 135.7884 -80.6704)
		(stroke
			(width 0.2)
			(type default)
		)
		(layer "In1.Cu")
	)
	(gr_arc
		(start 135.791702 -76.01712)
		(mid 135.806581 -76.053041)
		(end 135.842502 -76.06792)
		(stroke
			(width 0.2)
			(type default)
		)
		(layer "In1.Cu")
	)
	(gr_line
		(start 135.791702 -75.81392)
		(end 135.791702 -76.01712)
		(stroke
			(width 0.2)
			(type default)
		)
		(layer "In1.Cu")
	)
	(gr_arc
		(start 135.791702 -75.45832)
		(mid 135.806581 -75.494241)
		(end 135.842502 -75.50912)
		(stroke
			(width 0.2)
			(type default)
		)
		(layer "In1.Cu")
	)
	(gr_line
		(start 135.791702 -75.25512)
		(end 135.791702 -75.45832)
		(stroke
			(width 0.2)
			(type default)
		)
		(layer "In1.Cu")
	)
	(gr_line
		(start 135.820912 -79.882492)
		(end 136.633712 -79.882492)
		(stroke
			(width 0.2)
			(type default)
		)
		(layer "In1.Cu")
	)
	(gr_arc
		(start 135.820912 -79.577692)
		(mid 135.784991 -79.592571)
		(end 135.770112 -79.628492)
		(stroke
			(width 0.2)
			(type default)
		)
		(layer "In1.Cu")
	)
	(gr_line
		(start 135.820912 -79.323692)
		(end 136.633712 -79.323692)
		(stroke
			(width 0.2)
			(type default)
		)
		(layer "In1.Cu")
	)
	(gr_arc
		(start 135.820912 -79.018892)
		(mid 135.784991 -79.033771)
		(end 135.770112 -79.069692)
		(stroke
			(width 0.2)
			(type default)
		)
		(layer "In1.Cu")
	)
	(gr_arc
		(start 135.838692 -12.399772)
		(mid 136.399905 -12.961366)
		(end 136.961372 -12.400026)
		(stroke
			(width 0.2)
			(type default)
		)
		(layer "In1.Cu")
	)
	(gr_line
		(start 135.838692 -10.999978)
		(end 135.838692 -12.399772)
		(stroke
			(width 0.2)
			(type default)
		)
		(layer "In1.Cu")
	)
	(gr_arc
		(start 135.838692 -5.199888)
		(mid 136.399905 -5.761482)
		(end 136.961372 -5.200142)
		(stroke
			(width 0.2)
			(type default)
		)
		(layer "In1.Cu")
	)
	(gr_line
		(start 135.838692 -3.800094)
		(end 135.838692 -5.199888)
		(stroke
			(width 0.2)
			(type default)
		)
		(layer "In1.Cu")
	)
	(gr_line
		(start 135.8392 -81.28)
		(end 136.652 -81.28)
		(stroke
			(width 0.2)
			(type default)
		)
		(layer "In1.Cu")
	)
	(gr_arc
		(start 135.8392 -80.9752)
		(mid 135.803279 -80.990079)
		(end 135.7884 -81.026)
		(stroke
			(width 0.2)
			(type default)
		)
		(layer "In1.Cu")
	)
	(gr_line
		(start 135.8392 -80.7212)
		(end 136.652 -80.7212)
		(stroke
			(width 0.2)
			(type default)
		)
		(layer "In1.Cu")
	)
	(gr_arc
		(start 135.8392 -80.4164)
		(mid 135.803279 -80.431279)
		(end 135.7884 -80.4672)
		(stroke
			(width 0.2)
			(type default)
		)
		(layer "In1.Cu")
	)
	(gr_line
		(start 135.842502 -76.06792)
		(end 136.655302 -76.06792)
		(stroke
			(width 0.2)
			(type default)
		)
		(layer "In1.Cu")
	)
	(gr_arc
		(start 135.842502 -75.76312)
		(mid 135.806581 -75.777999)
		(end 135.791702 -75.81392)
		(stroke
			(width 0.2)
			(type default)
		)
		(layer "In1.Cu")
	)
	(gr_line
		(start 135.842502 -75.50912)
		(end 136.655302 -75.50912)
		(stroke
			(width 0.2)
			(type default)
		)
		(layer "In1.Cu")
	)
	(gr_arc
		(start 135.842502 -75.20432)
		(mid 135.806581 -75.219199)
		(end 135.791702 -75.25512)
		(stroke
			(width 0.2)
			(type default)
		)
		(layer "In1.Cu")
	)
	(gr_arc
		(start 136.587992 -77.983334)
		(mid 136.623913 -77.968455)
		(end 136.638792 -77.932534)
		(stroke
			(width 0.2)
			(type default)
		)
		(layer "In1.Cu")
	)
	(gr_line
		(start 136.587992 -77.678534)
		(end 135.775192 -77.678534)
		(stroke
			(width 0.2)
			(type default)
		)
		(layer "In1.Cu")
	)
	(gr_arc
		(start 136.587992 -77.424534)
		(mid 136.623913 -77.409655)
		(end 136.638792 -77.373734)
		(stroke
			(width 0.2)
			(type default)
		)
		(layer "In1.Cu")
	)
	(gr_line
		(start 136.587992 -77.119734)
		(end 135.775192 -77.119734)
		(stroke
			(width 0.2)
			(type default)
		)
		(layer "In1.Cu")
	)
	(gr_arc
		(start 136.633712 -79.882492)
		(mid 136.669633 -79.867613)
		(end 136.684512 -79.831692)
		(stroke
			(width 0.2)
			(type default)
		)
		(layer "In1.Cu")
	)
	(gr_line
		(start 136.633712 -79.577692)
		(end 135.820912 -79.577692)
		(stroke
			(width 0.2)
			(type default)
		)
		(layer "In1.Cu")
	)
	(gr_arc
		(start 136.633712 -79.323692)
		(mid 136.669633 -79.308813)
		(end 136.684512 -79.272892)
		(stroke
			(width 0.2)
			(type default)
		)
		(layer "In1.Cu")
	)
	(gr_line
		(start 136.633712 -79.018892)
		(end 135.820912 -79.018892)
		(stroke
			(width 0.2)
			(type default)
		)
		(layer "In1.Cu")
	)
	(gr_line
		(start 136.638792 -77.932534)
		(end 136.638792 -77.729334)
		(stroke
			(width 0.2)
			(type default)
		)
		(layer "In1.Cu")
	)
	(gr_arc
		(start 136.638792 -77.729334)
		(mid 136.623913 -77.693413)
		(end 136.587992 -77.678534)
		(stroke
			(width 0.2)
			(type default)
		)
		(layer "In1.Cu")
	)
	(gr_line
		(start 136.638792 -77.373734)
		(end 136.638792 -77.170534)
		(stroke
			(width 0.2)
			(type default)
		)
		(layer "In1.Cu")
	)
	(gr_arc
		(start 136.638792 -77.170534)
		(mid 136.623913 -77.134613)
		(end 136.587992 -77.119734)
		(stroke
			(width 0.2)
			(type default)
		)
		(layer "In1.Cu")
	)
	(gr_arc
		(start 136.652 -81.28)
		(mid 136.687921 -81.265121)
		(end 136.7028 -81.2292)
		(stroke
			(width 0.2)
			(type default)
		)
		(layer "In1.Cu")
	)
	(gr_line
		(start 136.652 -80.9752)
		(end 135.8392 -80.9752)
		(stroke
			(width 0.2)
			(type default)
		)
		(layer "In1.Cu")
	)
	(gr_arc
		(start 136.652 -80.7212)
		(mid 136.687921 -80.706321)
		(end 136.7028 -80.6704)
		(stroke
			(width 0.2)
			(type default)
		)
		(layer "In1.Cu")
	)
	(gr_line
		(start 136.652 -80.4164)
		(end 135.8392 -80.4164)
		(stroke
			(width 0.2)
			(type default)
		)
		(layer "In1.Cu")
	)
	(gr_arc
		(start 136.655302 -76.06792)
		(mid 136.691223 -76.053041)
		(end 136.706102 -76.01712)
		(stroke
			(width 0.2)
			(type default)
		)
		(layer "In1.Cu")
	)
	(gr_line
		(start 136.655302 -75.76312)
		(end 135.842502 -75.76312)
		(stroke
			(width 0.2)
			(type default)
		)
		(layer "In1.Cu")
	)
	(gr_arc
		(start 136.655302 -75.50912)
		(mid 136.691223 -75.494241)
		(end 136.706102 -75.45832)
		(stroke
			(width 0.2)
			(type default)
		)
		(layer "In1.Cu")
	)
	(gr_line
		(start 136.655302 -75.20432)
		(end 135.842502 -75.20432)
		(stroke
			(width 0.2)
			(type default)
		)
		(layer "In1.Cu")
	)
	(gr_line
		(start 136.684512 -79.831692)
		(end 136.684512 -79.628492)
		(stroke
			(width 0.2)
			(type default)
		)
		(layer "In1.Cu")
	)
	(gr_arc
		(start 136.684512 -79.628492)
		(mid 136.669633 -79.592571)
		(end 136.633712 -79.577692)
		(stroke
			(width 0.2)
			(type default)
		)
		(layer "In1.Cu")
	)
	(gr_line
		(start 136.684512 -79.272892)
		(end 136.684512 -79.069692)
		(stroke
			(width 0.2)
			(type default)
		)
		(layer "In1.Cu")
	)
	(gr_arc
		(start 136.684512 -79.069692)
		(mid 136.669633 -79.033771)
		(end 136.633712 -79.018892)
		(stroke
			(width 0.2)
			(type default)
		)
		(layer "In1.Cu")
	)
	(gr_line
		(start 136.7028 -81.2292)
		(end 136.7028 -81.026)
		(stroke
			(width 0.2)
			(type default)
		)
		(layer "In1.Cu")
	)
	(gr_arc
		(start 136.7028 -81.026)
		(mid 136.687921 -80.990079)
		(end 136.652 -80.9752)
		(stroke
			(width 0.2)
			(type default)
		)
		(layer "In1.Cu")
	)
	(gr_line
		(start 136.7028 -80.6704)
		(end 136.7028 -80.4672)
		(stroke
			(width 0.2)
			(type default)
		)
		(layer "In1.Cu")
	)
	(gr_arc
		(start 136.7028 -80.4672)
		(mid 136.687921 -80.431279)
		(end 136.652 -80.4164)
		(stroke
			(width 0.2)
			(type default)
		)
		(layer "In1.Cu")
	)
	(gr_line
		(start 136.706102 -76.01712)
		(end 136.706102 -75.81392)
		(stroke
			(width 0.2)
			(type default)
		)
		(layer "In1.Cu")
	)
	(gr_arc
		(start 136.706102 -75.81392)
		(mid 136.691223 -75.777999)
		(end 136.655302 -75.76312)
		(stroke
			(width 0.2)
			(type default)
		)
		(layer "In1.Cu")
	)
	(gr_line
		(start 136.706102 -75.45832)
		(end 136.706102 -75.25512)
		(stroke
			(width 0.2)
			(type default)
		)
		(layer "In1.Cu")
	)
	(gr_arc
		(start 136.706102 -75.25512)
		(mid 136.691223 -75.219199)
		(end 136.655302 -75.20432)
		(stroke
			(width 0.2)
			(type default)
		)
		(layer "In1.Cu")
	)
	(gr_line
		(start 136.961372 -12.400026)
		(end 136.961372 -10.999978)
		(stroke
			(width 0.2)
			(type default)
		)
		(layer "In1.Cu")
	)
	(gr_arc
		(start 136.961372 -10.999978)
		(mid 136.400032 -10.438638)
		(end 135.838692 -10.999978)
		(stroke
			(width 0.2)
			(type default)
		)
		(layer "In1.Cu")
	)
	(gr_line
		(start 136.961372 -5.200142)
		(end 136.961372 -3.800094)
		(stroke
			(width 0.2)
			(type default)
		)
		(layer "In1.Cu")
	)
	(gr_arc
		(start 136.961372 -3.800094)
		(mid 136.400032 -3.238754)
		(end 135.838692 -3.800094)
		(stroke
			(width 0.2)
			(type default)
		)
		(layer "In1.Cu")
	)
	(gr_arc
		(start 137.63879 -11.199876)
		(mid 138.200003 -11.76147)
		(end 138.76147 -11.20013)
		(stroke
			(width 0.2)
			(type default)
		)
		(layer "In1.Cu")
	)
	(gr_line
		(start 137.63879 -9.800082)
		(end 137.63879 -11.199876)
		(stroke
			(width 0.2)
			(type default)
		)
		(layer "In1.Cu")
	)
	(gr_arc
		(start 137.63879 -3.999738)
		(mid 138.200003 -4.561332)
		(end 138.76147 -3.999992)
		(stroke
			(width 0.2)
			(type default)
		)
		(layer "In1.Cu")
	)
	(gr_line
		(start 137.63879 -2.600198)
		(end 137.63879 -3.999738)
		(stroke
			(width 0.2)
			(type default)
		)
		(layer "In1.Cu")
	)
	(gr_line
		(start 138.479022 -76.90866)
		(end 139.622022 -76.90866)
		(stroke
			(width 0.2)
			(type default)
		)
		(layer "In1.Cu")
	)
	(gr_line
		(start 138.479022 -76.907898)
		(end 138.479022 -76.90866)
		(stroke
			(width 0.2)
			(type default)
		)
		(layer "In1.Cu")
	)
	(gr_arc
		(start 138.479022 -76.142342)
		(mid 138.096244 -76.52512)
		(end 138.479022 -76.907898)
		(stroke
			(width 0.2)
			(type default)
		)
		(layer "In1.Cu")
	)
	(gr_line
		(start 138.479022 -76.141834)
		(end 138.479022 -76.142342)
		(stroke
			(width 0.2)
			(type default)
		)
		(layer "In1.Cu")
	)
	(gr_line
		(start 138.479276 -76.14158)
		(end 138.479022 -76.141834)
		(stroke
			(width 0.2)
			(type default)
		)
		(layer "In1.Cu")
	)
	(gr_line
		(start 138.486134 -78.811374)
		(end 139.62888 -78.811374)
		(stroke
			(width 0.2)
			(type default)
		)
		(layer "In1.Cu")
	)
	(gr_line
		(start 138.486134 -78.810612)
		(end 138.486134 -78.811374)
		(stroke
			(width 0.2)
			(type default)
		)
		(layer "In1.Cu")
	)
	(gr_arc
		(start 138.486134 -78.045056)
		(mid 138.103356 -78.427834)
		(end 138.486134 -78.810612)
		(stroke
			(width 0.2)
			(type default)
		)
		(layer "In1.Cu")
	)
	(gr_line
		(start 138.486134 -78.044294)
		(end 138.486134 -78.045056)
		(stroke
			(width 0.2)
			(type default)
		)
		(layer "In1.Cu")
	)
	(gr_line
		(start 138.500612 -80.580992)
		(end 139.643612 -80.580992)
		(stroke
			(width 0.2)
			(type default)
		)
		(layer "In1.Cu")
	)
	(gr_line
		(start 138.500612 -80.58023)
		(end 138.500612 -80.580992)
		(stroke
			(width 0.2)
			(type default)
		)
		(layer "In1.Cu")
	)
	(gr_arc
		(start 138.500612 -79.814674)
		(mid 138.117834 -80.197452)
		(end 138.500612 -80.58023)
		(stroke
			(width 0.2)
			(type default)
		)
		(layer "In1.Cu")
	)
	(gr_line
		(start 138.500612 -79.814166)
		(end 138.500612 -79.814674)
		(stroke
			(width 0.2)
			(type default)
		)
		(layer "In1.Cu")
	)
	(gr_line
		(start 138.500866 -79.813912)
		(end 138.500612 -79.814166)
		(stroke
			(width 0.2)
			(type default)
		)
		(layer "In1.Cu")
	)
	(gr_line
		(start 138.739118 -65.426844)
		(end 139.881864 -65.426844)
		(stroke
			(width 0.2)
			(type default)
		)
		(layer "In1.Cu")
	)
	(gr_arc
		(start 138.739118 -64.517524)
		(mid 138.284458 -64.972184)
		(end 138.739118 -65.426844)
		(stroke
			(width 0.2)
			(type default)
		)
		(layer "In1.Cu")
	)
	(gr_line
		(start 138.76147 -11.20013)
		(end 138.76147 -9.800082)
		(stroke
			(width 0.2)
			(type default)
		)
		(layer "In1.Cu")
	)
	(gr_arc
		(start 138.76147 -9.800082)
		(mid 138.20013 -9.238742)
		(end 137.63879 -9.800082)
		(stroke
			(width 0.2)
			(type default)
		)
		(layer "In1.Cu")
	)
	(gr_line
		(start 138.76147 -3.999992)
		(end 138.76147 -2.600198)
		(stroke
			(width 0.2)
			(type default)
		)
		(layer "In1.Cu")
	)
	(gr_arc
		(start 138.76147 -2.600198)
		(mid 138.20013 -2.038858)
		(end 137.63879 -2.600198)
		(stroke
			(width 0.2)
			(type default)
		)
		(layer "In1.Cu")
	)
	(gr_line
		(start 138.80465 -63.499746)
		(end 139.947396 -63.499746)
		(stroke
			(width 0.2)
			(type default)
		)
		(layer "In1.Cu")
	)
	(gr_arc
		(start 138.80465 -62.590426)
		(mid 138.34999 -63.045086)
		(end 138.80465 -63.499746)
		(stroke
			(width 0.2)
			(type default)
		)
		(layer "In1.Cu")
	)
	(gr_line
		(start 138.843258 -82.691986)
		(end 139.986258 -82.691986)
		(stroke
			(width 0.2)
			(type default)
		)
		(layer "In1.Cu")
	)
	(gr_line
		(start 138.843258 -82.691224)
		(end 138.843258 -82.691986)
		(stroke
			(width 0.2)
			(type default)
		)
		(layer "In1.Cu")
	)
	(gr_arc
		(start 138.843258 -81.925668)
		(mid 138.46048 -82.308446)
		(end 138.843258 -82.691224)
		(stroke
			(width 0.2)
			(type default)
		)
		(layer "In1.Cu")
	)
	(gr_line
		(start 138.843258 -81.92516)
		(end 138.843258 -81.925668)
		(stroke
			(width 0.2)
			(type default)
		)
		(layer "In1.Cu")
	)
	(gr_line
		(start 138.843512 -81.924906)
		(end 138.843258 -81.92516)
		(stroke
			(width 0.2)
			(type default)
		)
		(layer "In1.Cu")
	)
	(gr_line
		(start 139.03071 -61.576712)
		(end 140.173456 -61.576712)
		(stroke
			(width 0.2)
			(type default)
		)
		(layer "In1.Cu")
	)
	(gr_arc
		(start 139.03071 -60.667392)
		(mid 138.57605 -61.122052)
		(end 139.03071 -61.576712)
		(stroke
			(width 0.2)
			(type default)
		)
		(layer "In1.Cu")
	)
	(gr_arc
		(start 139.438634 -12.399772)
		(mid 139.999847 -12.961366)
		(end 140.561314 -12.400026)
		(stroke
			(width 0.2)
			(type default)
		)
		(layer "In1.Cu")
	)
	(gr_line
		(start 139.438634 -10.999978)
		(end 139.438634 -12.399772)
		(stroke
			(width 0.2)
			(type default)
		)
		(layer "In1.Cu")
	)
	(gr_arc
		(start 139.438634 -5.199888)
		(mid 139.999847 -5.761482)
		(end 140.561314 -5.200142)
		(stroke
			(width 0.2)
			(type default)
		)
		(layer "In1.Cu")
	)
	(gr_line
		(start 139.438634 -3.800094)
		(end 139.438634 -5.199888)
		(stroke
			(width 0.2)
			(type default)
		)
		(layer "In1.Cu")
	)
	(gr_line
		(start 139.446 -59.35726)
		(end 140.588746 -59.35726)
		(stroke
			(width 0.2)
			(type default)
		)
		(layer "In1.Cu")
	)
	(gr_arc
		(start 139.446 -58.44794)
		(mid 138.99134 -58.9026)
		(end 139.446 -59.35726)
		(stroke
			(width 0.2)
			(type default)
		)
		(layer "In1.Cu")
	)
	(gr_line
		(start 139.622022 -76.90866)
		(end 139.622022 -76.907898)
		(stroke
			(width 0.2)
			(type default)
		)
		(layer "In1.Cu")
	)
	(gr_arc
		(start 139.622022 -76.907898)
		(mid 140.0048 -76.52512)
		(end 139.622022 -76.142342)
		(stroke
			(width 0.2)
			(type default)
		)
		(layer "In1.Cu")
	)
	(gr_line
		(start 139.622022 -76.142342)
		(end 139.622022 -76.14158)
		(stroke
			(width 0.2)
			(type default)
		)
		(layer "In1.Cu")
	)
	(gr_line
		(start 139.622022 -76.14158)
		(end 138.479276 -76.14158)
		(stroke
			(width 0.2)
			(type default)
		)
		(layer "In1.Cu")
	)
	(gr_line
		(start 139.62888 -78.811374)
		(end 139.629134 -78.81112)
		(stroke
			(width 0.2)
			(type default)
		)
		(layer "In1.Cu")
	)
	(gr_line
		(start 139.629134 -78.81112)
		(end 139.629134 -78.810612)
		(stroke
			(width 0.2)
			(type default)
		)
		(layer "In1.Cu")
	)
	(gr_arc
		(start 139.629134 -78.810612)
		(mid 140.011912 -78.427834)
		(end 139.629134 -78.045056)
		(stroke
			(width 0.2)
			(type default)
		)
		(layer "In1.Cu")
	)
	(gr_line
		(start 139.629134 -78.045056)
		(end 139.629134 -78.044294)
		(stroke
			(width 0.2)
			(type default)
		)
		(layer "In1.Cu")
	)
	(gr_line
		(start 139.629134 -78.044294)
		(end 138.486134 -78.044294)
		(stroke
			(width 0.2)
			(type default)
		)
		(layer "In1.Cu")
	)
	(gr_line
		(start 139.643612 -80.580992)
		(end 139.643612 -80.58023)
		(stroke
			(width 0.2)
			(type default)
		)
		(layer "In1.Cu")
	)
	(gr_arc
		(start 139.643612 -80.58023)
		(mid 140.02639 -80.197452)
		(end 139.643612 -79.814674)
		(stroke
			(width 0.2)
			(type default)
		)
		(layer "In1.Cu")
	)
	(gr_line
		(start 139.643612 -79.814674)
		(end 139.643612 -79.813912)
		(stroke
			(width 0.2)
			(type default)
		)
		(layer "In1.Cu")
	)
	(gr_line
		(start 139.643612 -79.813912)
		(end 138.500866 -79.813912)
		(stroke
			(width 0.2)
			(type default)
		)
		(layer "In1.Cu")
	)
	(gr_arc
		(start 139.881864 -65.426844)
		(mid 140.336778 -64.972311)
		(end 139.882118 -64.517524)
		(stroke
			(width 0.2)
			(type default)
		)
		(layer "In1.Cu")
	)
	(gr_line
		(start 139.882118 -64.517524)
		(end 138.739118 -64.517524)
		(stroke
			(width 0.2)
			(type default)
		)
		(layer "In1.Cu")
	)
	(gr_arc
		(start 139.947396 -63.499746)
		(mid 140.40231 -63.045213)
		(end 139.94765 -62.590426)
		(stroke
			(width 0.2)
			(type default)
		)
		(layer "In1.Cu")
	)
	(gr_line
		(start 139.94765 -62.590426)
		(end 138.80465 -62.590426)
		(stroke
			(width 0.2)
			(type default)
		)
		(layer "In1.Cu")
	)
	(gr_line
		(start 139.986258 -82.691986)
		(end 139.986258 -82.691224)
		(stroke
			(width 0.2)
			(type default)
		)
		(layer "In1.Cu")
	)
	(gr_arc
		(start 139.986258 -82.691224)
		(mid 140.369036 -82.308446)
		(end 139.986258 -81.925668)
		(stroke
			(width 0.2)
			(type default)
		)
		(layer "In1.Cu")
	)
	(gr_line
		(start 139.986258 -81.925668)
		(end 139.986258 -81.924906)
		(stroke
			(width 0.2)
			(type default)
		)
		(layer "In1.Cu")
	)
	(gr_line
		(start 139.986258 -81.924906)
		(end 138.843512 -81.924906)
		(stroke
			(width 0.2)
			(type default)
		)
		(layer "In1.Cu")
	)
	(gr_arc
		(start 140.173456 -61.576712)
		(mid 140.62837 -61.122179)
		(end 140.17371 -60.667392)
		(stroke
			(width 0.2)
			(type default)
		)
		(layer "In1.Cu")
	)
	(gr_line
		(start 140.17371 -60.667392)
		(end 139.03071 -60.667392)
		(stroke
			(width 0.2)
			(type default)
		)
		(layer "In1.Cu")
	)
	(gr_line
		(start 140.561314 -12.400026)
		(end 140.561314 -10.999978)
		(stroke
			(width 0.2)
			(type default)
		)
		(layer "In1.Cu")
	)
	(gr_arc
		(start 140.561314 -10.999978)
		(mid 139.999974 -10.438638)
		(end 139.438634 -10.999978)
		(stroke
			(width 0.2)
			(type default)
		)
		(layer "In1.Cu")
	)
	(gr_line
		(start 140.561314 -5.200142)
		(end 140.561314 -3.800094)
		(stroke
			(width 0.2)
			(type default)
		)
		(layer "In1.Cu")
	)
	(gr_arc
		(start 140.561314 -3.800094)
		(mid 139.999974 -3.238754)
		(end 139.438634 -3.800094)
		(stroke
			(width 0.2)
			(type default)
		)
		(layer "In1.Cu")
	)
	(gr_arc
		(start 140.588746 -59.35726)
		(mid 141.04366 -58.902727)
		(end 140.589 -58.44794)
		(stroke
			(width 0.2)
			(type default)
		)
		(layer "In1.Cu")
	)
	(gr_line
		(start 140.589 -58.44794)
		(end 139.446 -58.44794)
		(stroke
			(width 0.2)
			(type default)
		)
		(layer "In1.Cu")
	)
	(gr_arc
		(start 141.238732 -11.199876)
		(mid 141.799945 -11.76147)
		(end 142.361412 -11.20013)
		(stroke
			(width 0.2)
			(type default)
		)
		(layer "In1.Cu")
	)
	(gr_line
		(start 141.238732 -9.800082)
		(end 141.238732 -11.199876)
		(stroke
			(width 0.2)
			(type default)
		)
		(layer "In1.Cu")
	)
	(gr_arc
		(start 141.238732 -3.999738)
		(mid 141.799945 -4.561332)
		(end 142.361412 -3.999992)
		(stroke
			(width 0.2)
			(type default)
		)
		(layer "In1.Cu")
	)
	(gr_line
		(start 141.238732 -2.600198)
		(end 141.238732 -3.999738)
		(stroke
			(width 0.2)
			(type default)
		)
		(layer "In1.Cu")
	)
	(gr_arc
		(start 141.89456 -62.549786)
		(mid 141.909439 -62.585707)
		(end 141.94536 -62.600586)
		(stroke
			(width 0.2)
			(type default)
		)
		(layer "In1.Cu")
	)
	(gr_line
		(start 141.89456 -62.346586)
		(end 141.89456 -62.549786)
		(stroke
			(width 0.2)
			(type default)
		)
		(layer "In1.Cu")
	)
	(gr_arc
		(start 141.89456 -61.965586)
		(mid 141.909439 -62.001507)
		(end 141.94536 -62.016386)
		(stroke
			(width 0.2)
			(type default)
		)
		(layer "In1.Cu")
	)
	(gr_line
		(start 141.89456 -61.762386)
		(end 141.89456 -61.965586)
		(stroke
			(width 0.2)
			(type default)
		)
		(layer "In1.Cu")
	)
	(gr_line
		(start 141.94536 -62.600586)
		(end 142.75816 -62.600586)
		(stroke
			(width 0.2)
			(type default)
		)
		(layer "In1.Cu")
	)
	(gr_arc
		(start 141.94536 -62.295786)
		(mid 141.909439 -62.310665)
		(end 141.89456 -62.346586)
		(stroke
			(width 0.2)
			(type default)
		)
		(layer "In1.Cu")
	)
	(gr_line
		(start 141.94536 -62.016386)
		(end 142.75816 -62.016386)
		(stroke
			(width 0.2)
			(type default)
		)
		(layer "In1.Cu")
	)
	(gr_arc
		(start 141.94536 -61.711586)
		(mid 141.909439 -61.726465)
		(end 141.89456 -61.762386)
		(stroke
			(width 0.2)
			(type default)
		)
		(layer "In1.Cu")
	)
	(gr_arc
		(start 142.12062 -60.626752)
		(mid 142.135499 -60.662673)
		(end 142.17142 -60.677552)
		(stroke
			(width 0.2)
			(type default)
		)
		(layer "In1.Cu")
	)
	(gr_line
		(start 142.12062 -60.423552)
		(end 142.12062 -60.626752)
		(stroke
			(width 0.2)
			(type default)
		)
		(layer "In1.Cu")
	)
	(gr_arc
		(start 142.12062 -60.042552)
		(mid 142.135499 -60.078473)
		(end 142.17142 -60.093352)
		(stroke
			(width 0.2)
			(type default)
		)
		(layer "In1.Cu")
	)
	(gr_line
		(start 142.12062 -59.839352)
		(end 142.12062 -60.042552)
		(stroke
			(width 0.2)
			(type default)
		)
		(layer "In1.Cu")
	)
	(gr_line
		(start 142.17142 -60.677552)
		(end 142.98422 -60.677552)
		(stroke
			(width 0.2)
			(type default)
		)
		(layer "In1.Cu")
	)
	(gr_arc
		(start 142.17142 -60.372752)
		(mid 142.135499 -60.387631)
		(end 142.12062 -60.423552)
		(stroke
			(width 0.2)
			(type default)
		)
		(layer "In1.Cu")
	)
	(gr_line
		(start 142.17142 -60.093352)
		(end 142.98422 -60.093352)
		(stroke
			(width 0.2)
			(type default)
		)
		(layer "In1.Cu")
	)
	(gr_arc
		(start 142.17142 -59.788552)
		(mid 142.135499 -59.803431)
		(end 142.12062 -59.839352)
		(stroke
			(width 0.2)
			(type default)
		)
		(layer "In1.Cu")
	)
	(gr_arc
		(start 142.321026 -64.476884)
		(mid 142.335905 -64.512805)
		(end 142.371826 -64.527684)
		(stroke
			(width 0.2)
			(type default)
		)
		(layer "In1.Cu")
	)
	(gr_line
		(start 142.321026 -64.273684)
		(end 142.321026 -64.476884)
		(stroke
			(width 0.2)
			(type default)
		)
		(layer "In1.Cu")
	)
	(gr_arc
		(start 142.321026 -63.892684)
		(mid 142.335905 -63.928605)
		(end 142.371826 -63.943484)
		(stroke
			(width 0.2)
			(type default)
		)
		(layer "In1.Cu")
	)
	(gr_line
		(start 142.321026 -63.689484)
		(end 142.321026 -63.892684)
		(stroke
			(width 0.2)
			(type default)
		)
		(layer "In1.Cu")
	)
	(gr_line
		(start 142.361412 -11.20013)
		(end 142.361412 -9.800082)
		(stroke
			(width 0.2)
			(type default)
		)
		(layer "In1.Cu")
	)
	(gr_arc
		(start 142.361412 -9.800082)
		(mid 141.800072 -9.238742)
		(end 141.238732 -9.800082)
		(stroke
			(width 0.2)
			(type default)
		)
		(layer "In1.Cu")
	)
	(gr_line
		(start 142.361412 -3.999992)
		(end 142.361412 -2.600198)
		(stroke
			(width 0.2)
			(type default)
		)
		(layer "In1.Cu")
	)
	(gr_arc
		(start 142.361412 -2.600198)
		(mid 141.800072 -2.038858)
		(end 141.238732 -2.600198)
		(stroke
			(width 0.2)
			(type default)
		)
		(layer "In1.Cu")
	)
	(gr_line
		(start 142.371826 -64.527684)
		(end 143.184626 -64.527684)
		(stroke
			(width 0.2)
			(type default)
		)
		(layer "In1.Cu")
	)
	(gr_arc
		(start 142.371826 -64.222884)
		(mid 142.335905 -64.237763)
		(end 142.321026 -64.273684)
		(stroke
			(width 0.2)
			(type default)
		)
		(layer "In1.Cu")
	)
	(gr_line
		(start 142.371826 -63.943484)
		(end 143.184626 -63.943484)
		(stroke
			(width 0.2)
			(type default)
		)
		(layer "In1.Cu")
	)
	(gr_arc
		(start 142.371826 -63.638684)
		(mid 142.335905 -63.653563)
		(end 142.321026 -63.689484)
		(stroke
			(width 0.2)
			(type default)
		)
		(layer "In1.Cu")
	)
	(gr_arc
		(start 142.53591 -58.4073)
		(mid 142.550789 -58.443221)
		(end 142.58671 -58.4581)
		(stroke
			(width 0.2)
			(type default)
		)
		(layer "In1.Cu")
	)
	(gr_line
		(start 142.53591 -58.2041)
		(end 142.53591 -58.4073)
		(stroke
			(width 0.2)
			(type default)
		)
		(layer "In1.Cu")
	)
	(gr_arc
		(start 142.53591 -57.8231)
		(mid 142.550789 -57.859021)
		(end 142.58671 -57.8739)
		(stroke
			(width 0.2)
			(type default)
		)
		(layer "In1.Cu")
	)
	(gr_line
		(start 142.53591 -57.6199)
		(end 142.53591 -57.8231)
		(stroke
			(width 0.2)
			(type default)
		)
		(layer "In1.Cu")
	)
	(gr_line
		(start 142.58671 -58.4581)
		(end 143.39951 -58.4581)
		(stroke
			(width 0.2)
			(type default)
		)
		(layer "In1.Cu")
	)
	(gr_arc
		(start 142.58671 -58.1533)
		(mid 142.550789 -58.168179)
		(end 142.53591 -58.2041)
		(stroke
			(width 0.2)
			(type default)
		)
		(layer "In1.Cu")
	)
	(gr_line
		(start 142.58671 -57.8739)
		(end 143.39951 -57.8739)
		(stroke
			(width 0.2)
			(type default)
		)
		(layer "In1.Cu")
	)
	(gr_arc
		(start 142.58671 -57.5691)
		(mid 142.550789 -57.583979)
		(end 142.53591 -57.6199)
		(stroke
			(width 0.2)
			(type default)
		)
		(layer "In1.Cu")
	)
	(gr_arc
		(start 142.75816 -62.600586)
		(mid 142.794081 -62.585707)
		(end 142.80896 -62.549786)
		(stroke
			(width 0.2)
			(type default)
		)
		(layer "In1.Cu")
	)
	(gr_line
		(start 142.75816 -62.295786)
		(end 141.94536 -62.295786)
		(stroke
			(width 0.2)
			(type default)
		)
		(layer "In1.Cu")
	)
	(gr_arc
		(start 142.75816 -62.016386)
		(mid 142.794081 -62.001507)
		(end 142.80896 -61.965586)
		(stroke
			(width 0.2)
			(type default)
		)
		(layer "In1.Cu")
	)
	(gr_line
		(start 142.75816 -61.711586)
		(end 141.94536 -61.711586)
		(stroke
			(width 0.2)
			(type default)
		)
		(layer "In1.Cu")
	)
	(gr_line
		(start 142.80896 -62.549786)
		(end 142.80896 -62.346586)
		(stroke
			(width 0.2)
			(type default)
		)
		(layer "In1.Cu")
	)
	(gr_arc
		(start 142.80896 -62.346586)
		(mid 142.794081 -62.310665)
		(end 142.75816 -62.295786)
		(stroke
			(width 0.2)
			(type default)
		)
		(layer "In1.Cu")
	)
	(gr_line
		(start 142.80896 -61.965586)
		(end 142.80896 -61.762386)
		(stroke
			(width 0.2)
			(type default)
		)
		(layer "In1.Cu")
	)
	(gr_arc
		(start 142.80896 -61.762386)
		(mid 142.794081 -61.726465)
		(end 142.75816 -61.711586)
		(stroke
			(width 0.2)
			(type default)
		)
		(layer "In1.Cu")
	)
	(gr_arc
		(start 142.98422 -60.677552)
		(mid 143.020141 -60.662673)
		(end 143.03502 -60.626752)
		(stroke
			(width 0.2)
			(type default)
		)
		(layer "In1.Cu")
	)
	(gr_line
		(start 142.98422 -60.372752)
		(end 142.17142 -60.372752)
		(stroke
			(width 0.2)
			(type default)
		)
		(layer "In1.Cu")
	)
	(gr_arc
		(start 142.98422 -60.093352)
		(mid 143.020141 -60.078473)
		(end 143.03502 -60.042552)
		(stroke
			(width 0.2)
			(type default)
		)
		(layer "In1.Cu")
	)
	(gr_line
		(start 142.98422 -59.788552)
		(end 142.17142 -59.788552)
		(stroke
			(width 0.2)
			(type default)
		)
		(layer "In1.Cu")
	)
	(gr_line
		(start 143.03502 -60.626752)
		(end 143.03502 -60.423552)
		(stroke
			(width 0.2)
			(type default)
		)
		(layer "In1.Cu")
	)
	(gr_arc
		(start 143.03502 -60.423552)
		(mid 143.020141 -60.387631)
		(end 142.98422 -60.372752)
		(stroke
			(width 0.2)
			(type default)
		)
		(layer "In1.Cu")
	)
	(gr_line
		(start 143.03502 -60.042552)
		(end 143.03502 -59.839352)
		(stroke
			(width 0.2)
			(type default)
		)
		(layer "In1.Cu")
	)
	(gr_arc
		(start 143.03502 -59.839352)
		(mid 143.020141 -59.803431)
		(end 142.98422 -59.788552)
		(stroke
			(width 0.2)
			(type default)
		)
		(layer "In1.Cu")
	)
	(gr_arc
		(start 143.03883 -12.399772)
		(mid 143.600043 -12.961366)
		(end 144.16151 -12.400026)
		(stroke
			(width 0.2)
			(type default)
		)
		(layer "In1.Cu")
	)
	(gr_line
		(start 143.03883 -10.999978)
		(end 143.03883 -12.399772)
		(stroke
			(width 0.2)
			(type default)
		)
		(layer "In1.Cu")
	)
	(gr_arc
		(start 143.03883 -5.199888)
		(mid 143.600043 -5.761482)
		(end 144.16151 -5.200142)
		(stroke
			(width 0.2)
			(type default)
		)
		(layer "In1.Cu")
	)
	(gr_line
		(start 143.03883 -3.800094)
		(end 143.03883 -5.199888)
		(stroke
			(width 0.2)
			(type default)
		)
		(layer "In1.Cu")
	)
	(gr_arc
		(start 143.184626 -64.527684)
		(mid 143.220547 -64.512805)
		(end 143.235426 -64.476884)
		(stroke
			(width 0.2)
			(type default)
		)
		(layer "In1.Cu")
	)
	(gr_line
		(start 143.184626 -64.222884)
		(end 142.371826 -64.222884)
		(stroke
			(width 0.2)
			(type default)
		)
		(layer "In1.Cu")
	)
	(gr_arc
		(start 143.184626 -63.943484)
		(mid 143.220547 -63.928605)
		(end 143.235426 -63.892684)
		(stroke
			(width 0.2)
			(type default)
		)
		(layer "In1.Cu")
	)
	(gr_line
		(start 143.184626 -63.638684)
		(end 142.371826 -63.638684)
		(stroke
			(width 0.2)
			(type default)
		)
		(layer "In1.Cu")
	)
	(gr_line
		(start 143.235426 -64.476884)
		(end 143.235426 -64.273684)
		(stroke
			(width 0.2)
			(type default)
		)
		(layer "In1.Cu")
	)
	(gr_arc
		(start 143.235426 -64.273684)
		(mid 143.220547 -64.237763)
		(end 143.184626 -64.222884)
		(stroke
			(width 0.2)
			(type default)
		)
		(layer "In1.Cu")
	)
	(gr_line
		(start 143.235426 -63.892684)
		(end 143.235426 -63.689484)
		(stroke
			(width 0.2)
			(type default)
		)
		(layer "In1.Cu")
	)
	(gr_arc
		(start 143.235426 -63.689484)
		(mid 143.220547 -63.653563)
		(end 143.184626 -63.638684)
		(stroke
			(width 0.2)
			(type default)
		)
		(layer "In1.Cu")
	)
	(gr_arc
		(start 143.39951 -58.4581)
		(mid 143.435431 -58.443221)
		(end 143.45031 -58.4073)
		(stroke
			(width 0.2)
			(type default)
		)
		(layer "In1.Cu")
	)
	(gr_line
		(start 143.39951 -58.1533)
		(end 142.58671 -58.1533)
		(stroke
			(width 0.2)
			(type default)
		)
		(layer "In1.Cu")
	)
	(gr_arc
		(start 143.39951 -57.8739)
		(mid 143.435431 -57.859021)
		(end 143.45031 -57.8231)
		(stroke
			(width 0.2)
			(type default)
		)
		(layer "In1.Cu")
	)
	(gr_line
		(start 143.39951 -57.5691)
		(end 142.58671 -57.5691)
		(stroke
			(width 0.2)
			(type default)
		)
		(layer "In1.Cu")
	)
	(gr_line
		(start 143.45031 -58.4073)
		(end 143.45031 -58.2041)
		(stroke
			(width 0.2)
			(type default)
		)
		(layer "In1.Cu")
	)
	(gr_arc
		(start 143.45031 -58.2041)
		(mid 143.435431 -58.168179)
		(end 143.39951 -58.1533)
		(stroke
			(width 0.2)
			(type default)
		)
		(layer "In1.Cu")
	)
	(gr_line
		(start 143.45031 -57.8231)
		(end 143.45031 -57.6199)
		(stroke
			(width 0.2)
			(type default)
		)
		(layer "In1.Cu")
	)
	(gr_arc
		(start 143.45031 -57.6199)
		(mid 143.435431 -57.583979)
		(end 143.39951 -57.5691)
		(stroke
			(width 0.2)
			(type default)
		)
		(layer "In1.Cu")
	)
	(gr_line
		(start 144.16151 -12.400026)
		(end 144.16151 -10.999978)
		(stroke
			(width 0.2)
			(type default)
		)
		(layer "In1.Cu")
	)
	(gr_arc
		(start 144.16151 -10.999978)
		(mid 143.60017 -10.438638)
		(end 143.03883 -10.999978)
		(stroke
			(width 0.2)
			(type default)
		)
		(layer "In1.Cu")
	)
	(gr_line
		(start 144.16151 -5.200142)
		(end 144.16151 -3.800094)
		(stroke
			(width 0.2)
			(type default)
		)
		(layer "In1.Cu")
	)
	(gr_arc
		(start 144.16151 -3.800094)
		(mid 143.60017 -3.238754)
		(end 143.03883 -3.800094)
		(stroke
			(width 0.2)
			(type default)
		)
		(layer "In1.Cu")
	)
	(gr_arc
		(start 144.780762 -32.983932)
		(mid 144.787912 -33.022081)
		(end 144.819878 -33.04413)
		(stroke
			(width 0.2)
			(type default)
		)
		(layer "In1.Cu")
	)
	(gr_line
		(start 144.819878 -33.04413)
		(end 144.944084 -33.070546)
		(stroke
			(width 0.2)
			(type default)
		)
		(layer "In1.Cu")
	)
	(gr_line
		(start 144.822926 -32.78505)
		(end 144.780762 -32.983932)
		(stroke
			(width 0.2)
			(type default)
		)
		(layer "In1.Cu")
	)
	(gr_arc
		(start 144.838674 -11.199876)
		(mid 145.399887 -11.76147)
		(end 145.961354 -11.20013)
		(stroke
			(width 0.2)
			(type default)
		)
		(layer "In1.Cu")
	)
	(gr_line
		(start 144.838674 -9.800082)
		(end 144.838674 -11.199876)
		(stroke
			(width 0.2)
			(type default)
		)
		(layer "In1.Cu")
	)
	(gr_arc
		(start 144.838674 -3.999738)
		(mid 145.399887 -4.561332)
		(end 145.961354 -3.999992)
		(stroke
			(width 0.2)
			(type default)
		)
		(layer "In1.Cu")
	)
	(gr_line
		(start 144.838674 -2.600198)
		(end 144.838674 -3.999738)
		(stroke
			(width 0.2)
			(type default)
		)
		(layer "In1.Cu")
	)
	(gr_arc
		(start 144.883378 -32.745934)
		(mid 144.845051 -32.752972)
		(end 144.822926 -32.78505)
		(stroke
			(width 0.2)
			(type default)
		)
		(layer "In1.Cu")
	)
	(gr_arc
		(start 144.902174 -32.412432)
		(mid 144.909324 -32.450581)
		(end 144.94129 -32.47263)
		(stroke
			(width 0.2)
			(type default)
		)
		(layer "In1.Cu")
	)
	(gr_line
		(start 144.94129 -32.47263)
		(end 145.065496 -32.499046)
		(stroke
			(width 0.2)
			(type default)
		)
		(layer "In1.Cu")
	)
	(gr_line
		(start 144.944084 -33.070546)
		(end 145.490692 -33.186878)
		(stroke
			(width 0.2)
			(type default)
		)
		(layer "In1.Cu")
	)
	(gr_line
		(start 144.944338 -32.21355)
		(end 144.902174 -32.412432)
		(stroke
			(width 0.2)
			(type default)
		)
		(layer "In1.Cu")
	)
	(gr_arc
		(start 145.00479 -32.174434)
		(mid 144.966463 -32.181472)
		(end 144.944338 -32.21355)
		(stroke
			(width 0.2)
			(type default)
		)
		(layer "In1.Cu")
	)
	(gr_line
		(start 145.007584 -32.77235)
		(end 144.883378 -32.745934)
		(stroke
			(width 0.2)
			(type default)
		)
		(layer "In1.Cu")
	)
	(gr_line
		(start 145.065496 -32.499046)
		(end 145.612104 -32.615378)
		(stroke
			(width 0.2)
			(type default)
		)
		(layer "In1.Cu")
	)
	(gr_line
		(start 145.128996 -32.20085)
		(end 145.00479 -32.174434)
		(stroke
			(width 0.2)
			(type default)
		)
		(layer "In1.Cu")
	)
	(gr_line
		(start 145.490692 -33.186878)
		(end 145.614898 -33.213294)
		(stroke
			(width 0.2)
			(type default)
		)
		(layer "In1.Cu")
	)
	(gr_line
		(start 145.554192 -32.888682)
		(end 145.007584 -32.77235)
		(stroke
			(width 0.2)
			(type default)
		)
		(layer "In1.Cu")
	)
	(gr_line
		(start 145.612104 -32.615378)
		(end 145.73631 -32.641794)
		(stroke
			(width 0.2)
			(type default)
		)
		(layer "In1.Cu")
	)
	(gr_arc
		(start 145.614898 -33.213294)
		(mid 145.653225 -33.206256)
		(end 145.67535 -33.174178)
		(stroke
			(width 0.2)
			(type default)
		)
		(layer "In1.Cu")
	)
	(gr_line
		(start 145.67535 -33.174178)
		(end 145.717514 -32.975296)
		(stroke
			(width 0.2)
			(type default)
		)
		(layer "In1.Cu")
	)
	(gr_line
		(start 145.675604 -32.317182)
		(end 145.128996 -32.20085)
		(stroke
			(width 0.2)
			(type default)
		)
		(layer "In1.Cu")
	)
	(gr_line
		(start 145.678398 -32.915098)
		(end 145.554192 -32.888682)
		(stroke
			(width 0.2)
			(type default)
		)
		(layer "In1.Cu")
	)
	(gr_arc
		(start 145.717514 -32.975296)
		(mid 145.710364 -32.937147)
		(end 145.678398 -32.915098)
		(stroke
			(width 0.2)
			(type default)
		)
		(layer "In1.Cu")
	)
	(gr_arc
		(start 145.73631 -32.641794)
		(mid 145.774637 -32.634756)
		(end 145.796762 -32.602678)
		(stroke
			(width 0.2)
			(type default)
		)
		(layer "In1.Cu")
	)
	(gr_arc
		(start 145.781522 -47.045118)
		(mid 145.788672 -47.083267)
		(end 145.820638 -47.105316)
		(stroke
			(width 0.2)
			(type default)
		)
		(layer "In1.Cu")
	)
	(gr_line
		(start 145.796762 -32.602678)
		(end 145.838926 -32.403796)
		(stroke
			(width 0.2)
			(type default)
		)
		(layer "In1.Cu")
	)
	(gr_line
		(start 145.79981 -32.343598)
		(end 145.675604 -32.317182)
		(stroke
			(width 0.2)
			(type default)
		)
		(layer "In1.Cu")
	)
	(gr_line
		(start 145.820638 -47.105316)
		(end 145.944844 -47.131732)
		(stroke
			(width 0.2)
			(type default)
		)
		(layer "In1.Cu")
	)
	(gr_line
		(start 145.823686 -46.846236)
		(end 145.781522 -47.045118)
		(stroke
			(width 0.2)
			(type default)
		)
		(layer "In1.Cu")
	)
	(gr_arc
		(start 145.838926 -32.403796)
		(mid 145.831776 -32.365647)
		(end 145.79981 -32.343598)
		(stroke
			(width 0.2)
			(type default)
		)
		(layer "In1.Cu")
	)
	(gr_arc
		(start 145.839434 -33.377886)
		(mid 146.191732 -33.920176)
		(end 146.734022 -33.567878)
		(stroke
			(width 0.2)
			(type default)
		)
		(layer "In1.Cu")
	)
	(gr_arc
		(start 145.884138 -46.80712)
		(mid 145.845811 -46.814158)
		(end 145.823686 -46.846236)
		(stroke
			(width 0.2)
			(type default)
		)
		(layer "In1.Cu")
	)
	(gr_arc
		(start 145.902934 -46.473872)
		(mid 145.910084 -46.512021)
		(end 145.94205 -46.53407)
		(stroke
			(width 0.2)
			(type default)
		)
		(layer "In1.Cu")
	)
	(gr_line
		(start 145.94205 -46.53407)
		(end 146.066256 -46.560486)
		(stroke
			(width 0.2)
			(type default)
		)
		(layer "In1.Cu")
	)
	(gr_line
		(start 145.944844 -47.131732)
		(end 146.491452 -47.248064)
		(stroke
			(width 0.2)
			(type default)
		)
		(layer "In1.Cu")
	)
	(gr_line
		(start 145.945098 -46.27499)
		(end 145.902934 -46.473872)
		(stroke
			(width 0.2)
			(type default)
		)
		(layer "In1.Cu")
	)
	(gr_line
		(start 145.961354 -11.20013)
		(end 145.961354 -9.800082)
		(stroke
			(width 0.2)
			(type default)
		)
		(layer "In1.Cu")
	)
	(gr_arc
		(start 145.961354 -9.800082)
		(mid 145.400014 -9.238742)
		(end 144.838674 -9.800082)
		(stroke
			(width 0.2)
			(type default)
		)
		(layer "In1.Cu")
	)
	(gr_line
		(start 145.961354 -3.999992)
		(end 145.961354 -2.600198)
		(stroke
			(width 0.2)
			(type default)
		)
		(layer "In1.Cu")
	)
	(gr_arc
		(start 145.961354 -2.600198)
		(mid 145.400014 -2.038858)
		(end 144.838674 -2.600198)
		(stroke
			(width 0.2)
			(type default)
		)
		(layer "In1.Cu")
	)
	(gr_arc
		(start 146.00555 -46.235874)
		(mid 145.967223 -46.242912)
		(end 145.945098 -46.27499)
		(stroke
			(width 0.2)
			(type default)
		)
		(layer "In1.Cu")
	)
	(gr_line
		(start 146.008344 -46.833536)
		(end 145.884138 -46.80712)
		(stroke
			(width 0.2)
			(type default)
		)
		(layer "In1.Cu")
	)
	(gr_line
		(start 146.066256 -46.560486)
		(end 146.612864 -46.676818)
		(stroke
			(width 0.2)
			(type default)
		)
		(layer "In1.Cu")
	)
	(gr_line
		(start 146.077178 -32.259778)
		(end 145.839434 -33.377886)
		(stroke
			(width 0.2)
			(type default)
		)
		(layer "In1.Cu")
	)
	(gr_line
		(start 146.129756 -46.26229)
		(end 146.00555 -46.235874)
		(stroke
			(width 0.2)
			(type default)
		)
		(layer "In1.Cu")
	)
	(gr_line
		(start 146.491452 -47.248064)
		(end 146.615658 -47.27448)
		(stroke
			(width 0.2)
			(type default)
		)
		(layer "In1.Cu")
	)
	(gr_line
		(start 146.554952 -46.949868)
		(end 146.008344 -46.833536)
		(stroke
			(width 0.2)
			(type default)
		)
		(layer "In1.Cu")
	)
	(gr_line
		(start 146.612864 -46.676818)
		(end 146.73707 -46.703234)
		(stroke
			(width 0.2)
			(type default)
		)
		(layer "In1.Cu")
	)
	(gr_arc
		(start 146.615658 -47.27448)
		(mid 146.653985 -47.267442)
		(end 146.67611 -47.235364)
		(stroke
			(width 0.2)
			(type default)
		)
		(layer "In1.Cu")
	)
	(gr_arc
		(start 146.638772 -12.399772)
		(mid 147.199985 -12.961366)
		(end 147.761452 -12.400026)
		(stroke
			(width 0.2)
			(type default)
		)
		(layer "In1.Cu")
	)
	(gr_line
		(start 146.638772 -10.999978)
		(end 146.638772 -12.399772)
		(stroke
			(width 0.2)
			(type default)
		)
		(layer "In1.Cu")
	)
	(gr_arc
		(start 146.638772 -5.199888)
		(mid 147.199985 -5.761482)
		(end 147.761452 -5.200142)
		(stroke
			(width 0.2)
			(type default)
		)
		(layer "In1.Cu")
	)
	(gr_line
		(start 146.638772 -3.800094)
		(end 146.638772 -5.199888)
		(stroke
			(width 0.2)
			(type default)
		)
		(layer "In1.Cu")
	)
	(gr_line
		(start 146.67611 -47.235364)
		(end 146.718274 -47.036482)
		(stroke
			(width 0.2)
			(type default)
		)
		(layer "In1.Cu")
	)
	(gr_line
		(start 146.676364 -46.378622)
		(end 146.129756 -46.26229)
		(stroke
			(width 0.2)
			(type default)
		)
		(layer "In1.Cu")
	)
	(gr_line
		(start 146.679158 -46.976284)
		(end 146.554952 -46.949868)
		(stroke
			(width 0.2)
			(type default)
		)
		(layer "In1.Cu")
	)
	(gr_arc
		(start 146.718274 -47.036482)
		(mid 146.711124 -46.998333)
		(end 146.679158 -46.976284)
		(stroke
			(width 0.2)
			(type default)
		)
		(layer "In1.Cu")
	)
	(gr_line
		(start 146.734022 -33.567878)
		(end 146.969226 -32.460184)
		(stroke
			(width 0.2)
			(type default)
		)
		(layer "In1.Cu")
	)
	(gr_arc
		(start 146.73707 -46.703234)
		(mid 146.775397 -46.696196)
		(end 146.797522 -46.664118)
		(stroke
			(width 0.2)
			(type default)
		)
		(layer "In1.Cu")
	)
	(gr_line
		(start 146.797522 -46.664118)
		(end 146.839686 -46.465236)
		(stroke
			(width 0.2)
			(type default)
		)
		(layer "In1.Cu")
	)
	(gr_line
		(start 146.80057 -46.405038)
		(end 146.676364 -46.378622)
		(stroke
			(width 0.2)
			(type default)
		)
		(layer "In1.Cu")
	)
	(gr_arc
		(start 146.839686 -46.465236)
		(mid 146.832536 -46.427087)
		(end 146.80057 -46.405038)
		(stroke
			(width 0.2)
			(type default)
		)
		(layer "In1.Cu")
	)
	(gr_arc
		(start 146.84883 -51.043586)
		(mid 146.85598 -51.081735)
		(end 146.887946 -51.103784)
		(stroke
			(width 0.2)
			(type default)
		)
		(layer "In1.Cu")
	)
	(gr_arc
		(start 146.859752 -47.469298)
		(mid 147.21205 -48.011588)
		(end 147.75434 -47.65929)
		(stroke
			(width 0.2)
			(type default)
		)
		(layer "In1.Cu")
	)
	(gr_line
		(start 146.887946 -51.103784)
		(end 147.012152 -51.1302)
		(stroke
			(width 0.2)
			(type default)
		)
		(layer "In1.Cu")
	)
	(gr_line
		(start 146.890994 -50.844704)
		(end 146.84883 -51.043586)
		(stroke
			(width 0.2)
			(type default)
		)
		(layer "In1.Cu")
	)
	(gr_arc
		(start 146.951446 -50.805588)
		(mid 146.913119 -50.812626)
		(end 146.890994 -50.844704)
		(stroke
			(width 0.2)
			(type default)
		)
		(layer "In1.Cu")
	)
	(gr_arc
		(start 146.969226 -32.460184)
		(mid 146.624662 -31.908815)
		(end 146.077178 -32.259778)
		(stroke
			(width 0.2)
			(type default)
		)
		(layer "In1.Cu")
	)
	(gr_arc
		(start 146.970242 -50.47234)
		(mid 146.977392 -50.510489)
		(end 147.009358 -50.532538)
		(stroke
			(width 0.2)
			(type default)
		)
		(layer "In1.Cu")
	)
	(gr_arc
		(start 147.001738 -40.813228)
		(mid 147.008888 -40.851377)
		(end 147.040854 -40.873426)
		(stroke
			(width 0.2)
			(type default)
		)
		(layer "In1.Cu")
	)
	(gr_line
		(start 147.009358 -50.532538)
		(end 147.133564 -50.558954)
		(stroke
			(width 0.2)
			(type default)
		)
		(layer "In1.Cu")
	)
	(gr_line
		(start 147.012152 -51.1302)
		(end 147.55876 -51.246532)
		(stroke
			(width 0.2)
			(type default)
		)
		(layer "In1.Cu")
	)
	(gr_line
		(start 147.012406 -50.273458)
		(end 146.970242 -50.47234)
		(stroke
			(width 0.2)
			(type default)
		)
		(layer "In1.Cu")
	)
	(gr_line
		(start 147.040854 -40.873426)
		(end 147.16506 -40.899842)
		(stroke
			(width 0.2)
			(type default)
		)
		(layer "In1.Cu")
	)
	(gr_line
		(start 147.043902 -40.614346)
		(end 147.001738 -40.813228)
		(stroke
			(width 0.2)
			(type default)
		)
		(layer "In1.Cu")
	)
	(gr_arc
		(start 147.072858 -50.234342)
		(mid 147.034531 -50.24138)
		(end 147.012406 -50.273458)
		(stroke
			(width 0.2)
			(type default)
		)
		(layer "In1.Cu")
	)
	(gr_line
		(start 147.075652 -50.832004)
		(end 146.951446 -50.805588)
		(stroke
			(width 0.2)
			(type default)
		)
		(layer "In1.Cu")
	)
	(gr_line
		(start 147.097496 -46.35119)
		(end 146.859752 -47.469298)
		(stroke
			(width 0.2)
			(type default)
		)
		(layer "In1.Cu")
	)
	(gr_arc
		(start 147.104354 -40.57523)
		(mid 147.066027 -40.582268)
		(end 147.043902 -40.614346)
		(stroke
			(width 0.2)
			(type default)
		)
		(layer "In1.Cu")
	)
	(gr_arc
		(start 147.12315 -40.241982)
		(mid 147.1303 -40.280131)
		(end 147.162266 -40.30218)
		(stroke
			(width 0.2)
			(type default)
		)
		(layer "In1.Cu")
	)
	(gr_line
		(start 147.133564 -50.558954)
		(end 147.680172 -50.675286)
		(stroke
			(width 0.2)
			(type default)
		)
		(layer "In1.Cu")
	)
	(gr_line
		(start 147.162266 -40.30218)
		(end 147.286472 -40.328596)
		(stroke
			(width 0.2)
			(type default)
		)
		(layer "In1.Cu")
	)
	(gr_line
		(start 147.16506 -40.899842)
		(end 147.711668 -41.016174)
		(stroke
			(width 0.2)
			(type default)
		)
		(layer "In1.Cu")
	)
	(gr_line
		(start 147.165314 -40.0431)
		(end 147.12315 -40.241982)
		(stroke
			(width 0.2)
			(type default)
		)
		(layer "In1.Cu")
	)
	(gr_line
		(start 147.197064 -50.260758)
		(end 147.072858 -50.234342)
		(stroke
			(width 0.2)
			(type default)
		)
		(layer "In1.Cu")
	)
	(gr_arc
		(start 147.225766 -40.003984)
		(mid 147.187439 -40.011022)
		(end 147.165314 -40.0431)
		(stroke
			(width 0.2)
			(type default)
		)
		(layer "In1.Cu")
	)
	(gr_line
		(start 147.22856 -40.601646)
		(end 147.104354 -40.57523)
		(stroke
			(width 0.2)
			(type default)
		)
		(layer "In1.Cu")
	)
	(gr_line
		(start 147.286472 -40.328596)
		(end 147.83308 -40.444928)
		(stroke
			(width 0.2)
			(type default)
		)
		(layer "In1.Cu")
	)
	(gr_line
		(start 147.349972 -40.0304)
		(end 147.225766 -40.003984)
		(stroke
			(width 0.2)
			(type default)
		)
		(layer "In1.Cu")
	)
	(gr_line
		(start 147.55876 -51.246532)
		(end 147.682966 -51.272948)
		(stroke
			(width 0.2)
			(type default)
		)
		(layer "In1.Cu")
	)
	(gr_arc
		(start 147.601178 -35.731704)
		(mid 147.608328 -35.769853)
		(end 147.640294 -35.791902)
		(stroke
			(width 0.2)
			(type default)
		)
		(layer "In1.Cu")
	)
	(gr_line
		(start 147.62226 -50.948336)
		(end 147.075652 -50.832004)
		(stroke
			(width 0.2)
			(type default)
		)
		(layer "In1.Cu")
	)
	(gr_line
		(start 147.640294 -35.791902)
		(end 147.7645 -35.818318)
		(stroke
			(width 0.2)
			(type default)
		)
		(layer "In1.Cu")
	)
	(gr_line
		(start 147.643342 -35.532822)
		(end 147.601178 -35.731704)
		(stroke
			(width 0.2)
			(type default)
		)
		(layer "In1.Cu")
	)
	(gr_line
		(start 147.680172 -50.675286)
		(end 147.804378 -50.701702)
		(stroke
			(width 0.2)
			(type default)
		)
		(layer "In1.Cu")
	)
	(gr_arc
		(start 147.682966 -51.272948)
		(mid 147.721293 -51.26591)
		(end 147.743418 -51.233832)
		(stroke
			(width 0.2)
			(type default)
		)
		(layer "In1.Cu")
	)
	(gr_arc
		(start 147.703794 -35.493706)
		(mid 147.665467 -35.500744)
		(end 147.643342 -35.532822)
		(stroke
			(width 0.2)
			(type default)
		)
		(layer "In1.Cu")
	)
	(gr_line
		(start 147.711668 -41.016174)
		(end 147.835874 -41.04259)
		(stroke
			(width 0.2)
			(type default)
		)
		(layer "In1.Cu")
	)
	(gr_arc
		(start 147.72259 -35.160458)
		(mid 147.72974 -35.198607)
		(end 147.761706 -35.220656)
		(stroke
			(width 0.2)
			(type default)
		)
		(layer "In1.Cu")
	)
	(gr_line
		(start 147.743418 -51.233832)
		(end 147.785582 -51.03495)
		(stroke
			(width 0.2)
			(type default)
		)
		(layer "In1.Cu")
	)
	(gr_line
		(start 147.743672 -50.37709)
		(end 147.197064 -50.260758)
		(stroke
			(width 0.2)
			(type default)
		)
		(layer "In1.Cu")
	)
	(gr_line
		(start 147.746466 -50.974752)
		(end 147.62226 -50.948336)
		(stroke
			(width 0.2)
			(type default)
		)
		(layer "In1.Cu")
	)
	(gr_line
		(start 147.75434 -47.65929)
		(end 147.989544 -46.551596)
		(stroke
			(width 0.2)
			(type default)
		)
		(layer "In1.Cu")
	)
	(gr_line
		(start 147.761452 -12.400026)
		(end 147.761452 -10.999978)
		(stroke
			(width 0.2)
			(type default)
		)
		(layer "In1.Cu")
	)
	(gr_arc
		(start 147.761452 -10.999978)
		(mid 147.200112 -10.438638)
		(end 146.638772 -10.999978)
		(stroke
			(width 0.2)
			(type default)
		)
		(layer "In1.Cu")
	)
	(gr_line
		(start 147.761452 -5.200142)
		(end 147.761452 -3.800094)
		(stroke
			(width 0.2)
			(type default)
		)
		(layer "In1.Cu")
	)
	(gr_arc
		(start 147.761452 -3.800094)
		(mid 147.200112 -3.238754)
		(end 146.638772 -3.800094)
		(stroke
			(width 0.2)
			(type default)
		)
		(layer "In1.Cu")
	)
	(gr_line
		(start 147.761706 -35.220656)
		(end 147.885912 -35.247072)
		(stroke
			(width 0.2)
			(type default)
		)
		(layer "In1.Cu")
	)
	(gr_line
		(start 147.7645 -35.818318)
		(end 148.311108 -35.93465)
		(stroke
			(width 0.2)
			(type default)
		)
		(layer "In1.Cu")
	)
	(gr_line
		(start 147.764754 -34.961576)
		(end 147.72259 -35.160458)
		(stroke
			(width 0.2)
			(type default)
		)
		(layer "In1.Cu")
	)
	(gr_line
		(start 147.775168 -40.717978)
		(end 147.22856 -40.601646)
		(stroke
			(width 0.2)
			(type default)
		)
		(layer "In1.Cu")
	)
	(gr_arc
		(start 147.785582 -51.03495)
		(mid 147.778432 -50.996801)
		(end 147.746466 -50.974752)
		(stroke
			(width 0.2)
			(type default)
		)
		(layer "In1.Cu")
	)
	(gr_arc
		(start 147.804378 -50.701702)
		(mid 147.842705 -50.694664)
		(end 147.86483 -50.662586)
		(stroke
			(width 0.2)
			(type default)
		)
		(layer "In1.Cu")
	)
	(gr_arc
		(start 147.825206 -34.92246)
		(mid 147.786879 -34.929498)
		(end 147.764754 -34.961576)
		(stroke
			(width 0.2)
			(type default)
		)
		(layer "In1.Cu")
	)
	(gr_line
		(start 147.828 -35.520122)
		(end 147.703794 -35.493706)
		(stroke
			(width 0.2)
			(type default)
		)
		(layer "In1.Cu")
	)
	(gr_line
		(start 147.83308 -40.444928)
		(end 147.957286 -40.471344)
		(stroke
			(width 0.2)
			(type default)
		)
		(layer "In1.Cu")
	)
	(gr_arc
		(start 147.835874 -41.04259)
		(mid 147.874201 -41.035552)
		(end 147.896326 -41.003474)
		(stroke
			(width 0.2)
			(type default)
		)
		(layer "In1.Cu")
	)
	(gr_arc
		(start 147.846796 -55.001668)
		(mid 147.853946 -55.039817)
		(end 147.885912 -55.061866)
		(stroke
			(width 0.2)
			(type default)
		)
		(layer "In1.Cu")
	)
	(gr_line
		(start 147.86483 -50.662586)
		(end 147.906994 -50.463704)
		(stroke
			(width 0.2)
			(type default)
		)
		(layer "In1.Cu")
	)
	(gr_line
		(start 147.867878 -50.403506)
		(end 147.743672 -50.37709)
		(stroke
			(width 0.2)
			(type default)
		)
		(layer "In1.Cu")
	)
	(gr_line
		(start 147.885912 -55.061866)
		(end 148.010118 -55.088282)
		(stroke
			(width 0.2)
			(type default)
		)
		(layer "In1.Cu")
	)
	(gr_line
		(start 147.885912 -35.247072)
		(end 148.43252 -35.363404)
		(stroke
			(width 0.2)
			(type default)
		)
		(layer "In1.Cu")
	)
	(gr_line
		(start 147.88896 -54.802786)
		(end 147.846796 -55.001668)
		(stroke
			(width 0.2)
			(type default)
		)
		(layer "In1.Cu")
	)
	(gr_line
		(start 147.896326 -41.003474)
		(end 147.93849 -40.804592)
		(stroke
			(width 0.2)
			(type default)
		)
		(layer "In1.Cu")
	)
	(gr_line
		(start 147.89658 -40.146732)
		(end 147.349972 -40.0304)
		(stroke
			(width 0.2)
			(type default)
		)
		(layer "In1.Cu")
	)
	(gr_line
		(start 147.899374 -40.744394)
		(end 147.775168 -40.717978)
		(stroke
			(width 0.2)
			(type default)
		)
		(layer "In1.Cu")
	)
	(gr_arc
		(start 147.906994 -50.463704)
		(mid 147.899844 -50.425555)
		(end 147.867878 -50.403506)
		(stroke
			(width 0.2)
			(type default)
		)
		(layer "In1.Cu")
	)
	(gr_arc
		(start 147.907502 -51.437794)
		(mid 148.2598 -51.980084)
		(end 148.80209 -51.627786)
		(stroke
			(width 0.2)
			(type default)
		)
		(layer "In1.Cu")
	)
	(gr_arc
		(start 147.93849 -40.804592)
		(mid 147.93134 -40.766443)
		(end 147.899374 -40.744394)
		(stroke
			(width 0.2)
			(type default)
		)
		(layer "In1.Cu")
	)
	(gr_arc
		(start 147.949412 -54.76367)
		(mid 147.911085 -54.770708)
		(end 147.88896 -54.802786)
		(stroke
			(width 0.2)
			(type default)
		)
		(layer "In1.Cu")
	)
	(gr_line
		(start 147.949412 -34.948876)
		(end 147.825206 -34.92246)
		(stroke
			(width 0.2)
			(type default)
		)
		(layer "In1.Cu")
	)
	(gr_arc
		(start 147.957286 -40.471344)
		(mid 147.995613 -40.464306)
		(end 148.017738 -40.432228)
		(stroke
			(width 0.2)
			(type default)
		)
		(layer "In1.Cu")
	)
	(gr_arc
		(start 147.968462 -54.430422)
		(mid 147.975612 -54.468571)
		(end 148.007578 -54.49062)
		(stroke
			(width 0.2)
			(type default)
		)
		(layer "In1.Cu")
	)
	(gr_arc
		(start 147.989544 -46.551596)
		(mid 147.64498 -46.000227)
		(end 147.097496 -46.35119)
		(stroke
			(width 0.2)
			(type default)
		)
		(layer "In1.Cu")
	)
	(gr_line
		(start 148.007578 -54.49062)
		(end 148.131784 -54.517036)
		(stroke
			(width 0.2)
			(type default)
		)
		(layer "In1.Cu")
	)
	(gr_line
		(start 148.010118 -55.088282)
		(end 148.556726 -55.204614)
		(stroke
			(width 0.2)
			(type default)
		)
		(layer "In1.Cu")
	)
	(gr_line
		(start 148.010626 -54.23154)
		(end 147.968462 -54.430422)
		(stroke
			(width 0.2)
			(type default)
		)
		(layer "In1.Cu")
	)
	(gr_line
		(start 148.017738 -40.432228)
		(end 148.059902 -40.233346)
		(stroke
			(width 0.2)
			(type default)
		)
		(layer "In1.Cu")
	)
	(gr_line
		(start 148.020786 -40.173148)
		(end 147.89658 -40.146732)
		(stroke
			(width 0.2)
			(type default)
		)
		(layer "In1.Cu")
	)
	(gr_arc
		(start 148.04136 -44.833032)
		(mid 148.04851 -44.871181)
		(end 148.080476 -44.89323)
		(stroke
			(width 0.2)
			(type default)
		)
		(layer "In1.Cu")
	)
	(gr_arc
		(start 148.059902 -40.233346)
		(mid 148.052752 -40.195197)
		(end 148.020786 -40.173148)
		(stroke
			(width 0.2)
			(type default)
		)
		(layer "In1.Cu")
	)
	(gr_arc
		(start 148.071078 -54.192424)
		(mid 148.032751 -54.199462)
		(end 148.010626 -54.23154)
		(stroke
			(width 0.2)
			(type default)
		)
		(layer "In1.Cu")
	)
	(gr_line
		(start 148.073618 -54.790086)
		(end 147.949412 -54.76367)
		(stroke
			(width 0.2)
			(type default)
		)
		(layer "In1.Cu")
	)
	(gr_line
		(start 148.080476 -44.89323)
		(end 148.204682 -44.919646)
		(stroke
			(width 0.2)
			(type default)
		)
		(layer "In1.Cu")
	)
	(gr_line
		(start 148.083524 -44.63415)
		(end 148.04136 -44.833032)
		(stroke
			(width 0.2)
			(type default)
		)
		(layer "In1.Cu")
	)
	(gr_line
		(start 148.131784 -54.517036)
		(end 148.678392 -54.633368)
		(stroke
			(width 0.2)
			(type default)
		)
		(layer "In1.Cu")
	)
	(gr_arc
		(start 148.143976 -44.595034)
		(mid 148.105649 -44.602072)
		(end 148.083524 -44.63415)
		(stroke
			(width 0.2)
			(type default)
		)
		(layer "In1.Cu")
	)
	(gr_line
		(start 148.145246 -50.319686)
		(end 147.907502 -51.437794)
		(stroke
			(width 0.2)
			(type default)
		)
		(layer "In1.Cu")
	)
	(gr_arc
		(start 148.162772 -44.261532)
		(mid 148.169922 -44.299681)
		(end 148.201888 -44.32173)
		(stroke
			(width 0.2)
			(type default)
		)
		(layer "In1.Cu")
	)
	(gr_arc
		(start 148.179536 -41.25849)
		(mid 148.531834 -41.80078)
		(end 149.074124 -41.448482)
		(stroke
			(width 0.2)
			(type default)
		)
		(layer "In1.Cu")
	)
	(gr_line
		(start 148.195284 -54.21884)
		(end 148.071078 -54.192424)
		(stroke
			(width 0.2)
			(type default)
		)
		(layer "In1.Cu")
	)
	(gr_line
		(start 148.201888 -44.32173)
		(end 148.326094 -44.348146)
		(stroke
			(width 0.2)
			(type default)
		)
		(layer "In1.Cu")
	)
	(gr_line
		(start 148.204682 -44.919646)
		(end 148.75129 -45.035978)
		(stroke
			(width 0.2)
			(type default)
		)
		(layer "In1.Cu")
	)
	(gr_line
		(start 148.204936 -44.06265)
		(end 148.162772 -44.261532)
		(stroke
			(width 0.2)
			(type default)
		)
		(layer "In1.Cu")
	)
	(gr_arc
		(start 148.265388 -44.023534)
		(mid 148.227061 -44.030572)
		(end 148.204936 -44.06265)
		(stroke
			(width 0.2)
			(type default)
		)
		(layer "In1.Cu")
	)
	(gr_line
		(start 148.268182 -44.62145)
		(end 148.143976 -44.595034)
		(stroke
			(width 0.2)
			(type default)
		)
		(layer "In1.Cu")
	)
	(gr_line
		(start 148.311108 -35.93465)
		(end 148.435314 -35.961066)
		(stroke
			(width 0.2)
			(type default)
		)
		(layer "In1.Cu")
	)
	(gr_line
		(start 148.326094 -44.348146)
		(end 148.872702 -44.464478)
		(stroke
			(width 0.2)
			(type default)
		)
		(layer "In1.Cu")
	)
	(gr_line
		(start 148.374608 -35.636454)
		(end 147.828 -35.520122)
		(stroke
			(width 0.2)
			(type default)
		)
		(layer "In1.Cu")
	)
	(gr_line
		(start 148.389594 -44.04995)
		(end 148.265388 -44.023534)
		(stroke
			(width 0.2)
			(type default)
		)
		(layer "In1.Cu")
	)
	(gr_line
		(start 148.41728 -40.140382)
		(end 148.179536 -41.25849)
		(stroke
			(width 0.2)
			(type default)
		)
		(layer "In1.Cu")
	)
	(gr_line
		(start 148.43252 -35.363404)
		(end 148.556726 -35.38982)
		(stroke
			(width 0.2)
			(type default)
		)
		(layer "In1.Cu")
	)
	(gr_arc
		(start 148.435314 -35.961066)
		(mid 148.473641 -35.954028)
		(end 148.495766 -35.92195)
		(stroke
			(width 0.2)
			(type default)
		)
		(layer "In1.Cu")
	)
	(gr_arc
		(start 148.438616 -11.199876)
		(mid 148.999829 -11.76147)
		(end 149.561296 -11.20013)
		(stroke
			(width 0.2)
			(type default)
		)
		(layer "In1.Cu")
	)
	(gr_line
		(start 148.438616 -9.800082)
		(end 148.438616 -11.199876)
		(stroke
			(width 0.2)
			(type default)
		)
		(layer "In1.Cu")
	)
	(gr_arc
		(start 148.438616 -3.999738)
		(mid 148.999829 -4.561332)
		(end 149.561296 -3.999992)
		(stroke
			(width 0.2)
			(type default)
		)
		(layer "In1.Cu")
	)
	(gr_line
		(start 148.438616 -2.600198)
		(end 148.438616 -3.999738)
		(stroke
			(width 0.2)
			(type default)
		)
		(layer "In1.Cu")
	)
	(gr_line
		(start 148.495766 -35.92195)
		(end 148.53793 -35.723068)
		(stroke
			(width 0.2)
			(type default)
		)
		(layer "In1.Cu")
	)
	(gr_line
		(start 148.49602 -35.065208)
		(end 147.949412 -34.948876)
		(stroke
			(width 0.2)
			(type default)
		)
		(layer "In1.Cu")
	)
	(gr_line
		(start 148.498814 -35.66287)
		(end 148.374608 -35.636454)
		(stroke
			(width 0.2)
			(type default)
		)
		(layer "In1.Cu")
	)
	(gr_arc
		(start 148.53793 -35.723068)
		(mid 148.53078 -35.684919)
		(end 148.498814 -35.66287)
		(stroke
			(width 0.2)
			(type default)
		)
		(layer "In1.Cu")
	)
	(gr_line
		(start 148.556726 -55.204614)
		(end 148.680932 -55.23103)
		(stroke
			(width 0.2)
			(type default)
		)
		(layer "In1.Cu")
	)
	(gr_arc
		(start 148.556726 -35.38982)
		(mid 148.595053 -35.382782)
		(end 148.617178 -35.350704)
		(stroke
			(width 0.2)
			(type default)
		)
		(layer "In1.Cu")
	)
	(gr_line
		(start 148.617178 -35.350704)
		(end 148.659342 -35.151822)
		(stroke
			(width 0.2)
			(type default)
		)
		(layer "In1.Cu")
	)
	(gr_line
		(start 148.620226 -54.906418)
		(end 148.073618 -54.790086)
		(stroke
			(width 0.2)
			(type default)
		)
		(layer "In1.Cu")
	)
	(gr_line
		(start 148.620226 -35.091624)
		(end 148.49602 -35.065208)
		(stroke
			(width 0.2)
			(type default)
		)
		(layer "In1.Cu")
	)
	(gr_arc
		(start 148.659342 -35.151822)
		(mid 148.652192 -35.113673)
		(end 148.620226 -35.091624)
		(stroke
			(width 0.2)
			(type default)
		)
		(layer "In1.Cu")
	)
	(gr_line
		(start 148.678392 -54.633368)
		(end 148.802598 -54.659784)
		(stroke
			(width 0.2)
			(type default)
		)
		(layer "In1.Cu")
	)
	(gr_arc
		(start 148.680932 -55.23103)
		(mid 148.719259 -55.223992)
		(end 148.741384 -55.191914)
		(stroke
			(width 0.2)
			(type default)
		)
		(layer "In1.Cu")
	)
	(gr_arc
		(start 148.684742 -36.130992)
		(mid 149.03704 -36.673282)
		(end 149.57933 -36.320984)
		(stroke
			(width 0.2)
			(type default)
		)
		(layer "In1.Cu")
	)
	(gr_line
		(start 148.741384 -55.191914)
		(end 148.783548 -54.993032)
		(stroke
			(width 0.2)
			(type default)
		)
		(layer "In1.Cu")
	)
	(gr_line
		(start 148.741892 -54.335172)
		(end 148.195284 -54.21884)
		(stroke
			(width 0.2)
			(type default)
		)
		(layer "In1.Cu")
	)
	(gr_line
		(start 148.744432 -54.932834)
		(end 148.620226 -54.906418)
		(stroke
			(width 0.2)
			(type default)
		)
		(layer "In1.Cu")
	)
	(gr_line
		(start 148.75129 -45.035978)
		(end 148.875496 -45.062394)
		(stroke
			(width 0.2)
			(type default)
		)
		(layer "In1.Cu")
	)
	(gr_arc
		(start 148.783548 -54.993032)
		(mid 148.776398 -54.954883)
		(end 148.744432 -54.932834)
		(stroke
			(width 0.2)
			(type default)
		)
		(layer "In1.Cu")
	)
	(gr_line
		(start 148.80209 -51.627786)
		(end 149.037294 -50.520092)
		(stroke
			(width 0.2)
			(type default)
		)
		(layer "In1.Cu")
	)
	(gr_arc
		(start 148.802598 -54.659784)
		(mid 148.840925 -54.652746)
		(end 148.86305 -54.620668)
		(stroke
			(width 0.2)
			(type default)
		)
		(layer "In1.Cu")
	)
	(gr_line
		(start 148.81479 -44.737782)
		(end 148.268182 -44.62145)
		(stroke
			(width 0.2)
			(type default)
		)
		(layer "In1.Cu")
	)
	(gr_line
		(start 148.86305 -54.620668)
		(end 148.905214 -54.421786)
		(stroke
			(width 0.2)
			(type default)
		)
		(layer "In1.Cu")
	)
	(gr_line
		(start 148.866098 -54.361588)
		(end 148.741892 -54.335172)
		(stroke
			(width 0.2)
			(type default)
		)
		(layer "In1.Cu")
	)
	(gr_line
		(start 148.872702 -44.464478)
		(end 148.996908 -44.490894)
		(stroke
			(width 0.2)
			(type default)
		)
		(layer "In1.Cu")
	)
	(gr_arc
		(start 148.875496 -45.062394)
		(mid 148.913823 -45.055356)
		(end 148.935948 -45.023278)
		(stroke
			(width 0.2)
			(type default)
		)
		(layer "In1.Cu")
	)
	(gr_arc
		(start 148.905214 -54.421786)
		(mid 148.898064 -54.383637)
		(end 148.866098 -54.361588)
		(stroke
			(width 0.2)
			(type default)
		)
		(layer "In1.Cu")
	)
	(gr_line
		(start 148.922486 -35.012884)
		(end 148.684742 -36.130992)
		(stroke
			(width 0.2)
			(type default)
		)
		(layer "In1.Cu")
	)
	(gr_line
		(start 148.935948 -45.023278)
		(end 148.978112 -44.824396)
		(stroke
			(width 0.2)
			(type default)
		)
		(layer "In1.Cu")
	)
	(gr_line
		(start 148.936202 -44.166282)
		(end 148.389594 -44.04995)
		(stroke
			(width 0.2)
			(type default)
		)
		(layer "In1.Cu")
	)
	(gr_line
		(start 148.938996 -44.764198)
		(end 148.81479 -44.737782)
		(stroke
			(width 0.2)
			(type default)
		)
		(layer "In1.Cu")
	)
	(gr_arc
		(start 148.957792 -55.395876)
		(mid 149.302356 -55.947245)
		(end 149.84984 -55.596282)
		(stroke
			(width 0.2)
			(type default)
		)
		(layer "In1.Cu")
	)
	(gr_arc
		(start 148.978112 -44.824396)
		(mid 148.970962 -44.786247)
		(end 148.938996 -44.764198)
		(stroke
			(width 0.2)
			(type default)
		)
		(layer "In1.Cu")
	)
	(gr_arc
		(start 148.996908 -44.490894)
		(mid 149.035235 -44.483856)
		(end 149.05736 -44.451778)
		(stroke
			(width 0.2)
			(type default)
		)
		(layer "In1.Cu")
	)
	(gr_arc
		(start 149.037294 -50.520092)
		(mid 148.69273 -49.968723)
		(end 148.145246 -50.319686)
		(stroke
			(width 0.2)
			(type default)
		)
		(layer "In1.Cu")
	)
	(gr_line
		(start 149.05736 -44.451778)
		(end 149.099524 -44.252896)
		(stroke
			(width 0.2)
			(type default)
		)
		(layer "In1.Cu")
	)
	(gr_line
		(start 149.060408 -44.192698)
		(end 148.936202 -44.166282)
		(stroke
			(width 0.2)
			(type default)
		)
		(layer "In1.Cu")
	)
	(gr_line
		(start 149.074124 -41.448482)
		(end 149.309328 -40.340788)
		(stroke
			(width 0.2)
			(type default)
		)
		(layer "In1.Cu")
	)
	(gr_arc
		(start 149.099524 -44.252896)
		(mid 149.092374 -44.214747)
		(end 149.060408 -44.192698)
		(stroke
			(width 0.2)
			(type default)
		)
		(layer "In1.Cu")
	)
	(gr_arc
		(start 149.100286 -45.226986)
		(mid 149.452584 -45.769276)
		(end 149.994874 -45.416978)
		(stroke
			(width 0.2)
			(type default)
		)
		(layer "In1.Cu")
	)
	(gr_line
		(start 149.192996 -54.288182)
		(end 148.957792 -55.395876)
		(stroke
			(width 0.2)
			(type default)
		)
		(layer "In1.Cu")
	)
	(gr_arc
		(start 149.309328 -40.340788)
		(mid 148.964764 -39.789419)
		(end 148.41728 -40.140382)
		(stroke
			(width 0.2)
			(type default)
		)
		(layer "In1.Cu")
	)
	(gr_line
		(start 149.33803 -44.108878)
		(end 149.100286 -45.226986)
		(stroke
			(width 0.2)
			(type default)
		)
		(layer "In1.Cu")
	)
	(gr_arc
		(start 149.369272 -38.570916)
		(mid 149.376422 -38.609065)
		(end 149.408388 -38.631114)
		(stroke
			(width 0.2)
			(type default)
		)
		(layer "In1.Cu")
	)
	(gr_line
		(start 149.408388 -38.631114)
		(end 149.532594 -38.65753)
		(stroke
			(width 0.2)
			(type default)
		)
		(layer "In1.Cu")
	)
	(gr_line
		(start 149.411436 -38.372034)
		(end 149.369272 -38.570916)
		(stroke
			(width 0.2)
			(type default)
		)
		(layer "In1.Cu")
	)
	(gr_arc
		(start 149.471888 -38.332918)
		(mid 149.433561 -38.339956)
		(end 149.411436 -38.372034)
		(stroke
			(width 0.2)
			(type default)
		)
		(layer "In1.Cu")
	)
	(gr_arc
		(start 149.490684 -37.99967)
		(mid 149.497834 -38.037819)
		(end 149.5298 -38.059868)
		(stroke
			(width 0.2)
			(type default)
		)
		(layer "In1.Cu")
	)
	(gr_line
		(start 149.5298 -38.059868)
		(end 149.654006 -38.086284)
		(stroke
			(width 0.2)
			(type default)
		)
		(layer "In1.Cu")
	)
	(gr_line
		(start 149.532594 -38.65753)
		(end 150.079202 -38.773862)
		(stroke
			(width 0.2)
			(type default)
		)
		(layer "In1.Cu")
	)
	(gr_line
		(start 149.532848 -37.800788)
		(end 149.490684 -37.99967)
		(stroke
			(width 0.2)
			(type default)
		)
		(layer "In1.Cu")
	)
	(gr_line
		(start 149.561296 -11.20013)
		(end 149.561296 -9.800082)
		(stroke
			(width 0.2)
			(type default)
		)
		(layer "In1.Cu")
	)
	(gr_arc
		(start 149.561296 -9.800082)
		(mid 148.999956 -9.238742)
		(end 148.438616 -9.800082)
		(stroke
			(width 0.2)
			(type default)
		)
		(layer "In1.Cu")
	)
	(gr_line
		(start 149.561296 -3.999992)
		(end 149.561296 -2.600198)
		(stroke
			(width 0.2)
			(type default)
		)
		(layer "In1.Cu")
	)
	(gr_arc
		(start 149.561296 -2.600198)
		(mid 148.999956 -2.038858)
		(end 148.438616 -2.600198)
		(stroke
			(width 0.2)
			(type default)
		)
		(layer "In1.Cu")
	)
	(gr_line
		(start 149.57933 -36.320984)
		(end 149.814534 -35.21329)
		(stroke
			(width 0.2)
			(type default)
		)
		(layer "In1.Cu")
	)
	(gr_arc
		(start 149.5933 -37.761672)
		(mid 149.554973 -37.76871)
		(end 149.532848 -37.800788)
		(stroke
			(width 0.2)
			(type default)
		)
		(layer "In1.Cu")
	)
	(gr_line
		(start 149.596094 -38.359334)
		(end 149.471888 -38.332918)
		(stroke
			(width 0.2)
			(type default)
		)
		(layer "In1.Cu")
	)
	(gr_line
		(start 149.654006 -38.086284)
		(end 150.200614 -38.202616)
		(stroke
			(width 0.2)
			(type default)
		)
		(layer "In1.Cu")
	)
	(gr_line
		(start 149.717506 -37.788088)
		(end 149.5933 -37.761672)
		(stroke
			(width 0.2)
			(type default)
		)
		(layer "In1.Cu")
	)
	(gr_arc
		(start 149.814534 -35.21329)
		(mid 149.46997 -34.661921)
		(end 148.922486 -35.012884)
		(stroke
			(width 0.2)
			(type default)
		)
		(layer "In1.Cu")
	)
	(gr_line
		(start 149.84984 -55.596282)
		(end 150.087584 -54.478174)
		(stroke
			(width 0.2)
			(type default)
		)
		(layer "In1.Cu")
	)
	(gr_line
		(start 149.994874 -45.416978)
		(end 150.230078 -44.309284)
		(stroke
			(width 0.2)
			(type default)
		)
		(layer "In1.Cu")
	)
	(gr_line
		(start 150.079202 -38.773862)
		(end 150.203408 -38.800278)
		(stroke
			(width 0.2)
			(type default)
		)
		(layer "In1.Cu")
	)
	(gr_arc
		(start 150.087584 -54.478174)
		(mid 149.735286 -53.935884)
		(end 149.192996 -54.288182)
		(stroke
			(width 0.2)
			(type default)
		)
		(layer "In1.Cu")
	)
	(gr_line
		(start 150.142702 -38.475666)
		(end 149.596094 -38.359334)
		(stroke
			(width 0.2)
			(type default)
		)
		(layer "In1.Cu")
	)
	(gr_line
		(start 150.200614 -38.202616)
		(end 150.32482 -38.229032)
		(stroke
			(width 0.2)
			(type default)
		)
		(layer "In1.Cu")
	)
	(gr_arc
		(start 150.203408 -38.800278)
		(mid 150.241735 -38.79324)
		(end 150.26386 -38.761162)
		(stroke
			(width 0.2)
			(type default)
		)
		(layer "In1.Cu")
	)
	(gr_arc
		(start 150.230078 -44.309284)
		(mid 149.885514 -43.757915)
		(end 149.33803 -44.108878)
		(stroke
			(width 0.2)
			(type default)
		)
		(layer "In1.Cu")
	)
	(gr_line
		(start 150.26386 -38.761162)
		(end 150.306024 -38.56228)
		(stroke
			(width 0.2)
			(type default)
		)
		(layer "In1.Cu")
	)
	(gr_line
		(start 150.264114 -37.90442)
		(end 149.717506 -37.788088)
		(stroke
			(width 0.2)
			(type default)
		)
		(layer "In1.Cu")
	)
	(gr_line
		(start 150.266908 -38.502082)
		(end 150.142702 -38.475666)
		(stroke
			(width 0.2)
			(type default)
		)
		(layer "In1.Cu")
	)
	(gr_arc
		(start 150.306024 -38.56228)
		(mid 150.298874 -38.524131)
		(end 150.266908 -38.502082)
		(stroke
			(width 0.2)
			(type default)
		)
		(layer "In1.Cu")
	)
	(gr_arc
		(start 150.32482 -38.229032)
		(mid 150.363147 -38.221994)
		(end 150.385272 -38.189916)
		(stroke
			(width 0.2)
			(type default)
		)
		(layer "In1.Cu")
	)
	(gr_line
		(start 150.385272 -38.189916)
		(end 150.427436 -37.991034)
		(stroke
			(width 0.2)
			(type default)
		)
		(layer "In1.Cu")
	)
	(gr_line
		(start 150.38832 -37.930836)
		(end 150.264114 -37.90442)
		(stroke
			(width 0.2)
			(type default)
		)
		(layer "In1.Cu")
	)
	(gr_arc
		(start 150.427436 -37.991034)
		(mid 150.420286 -37.952885)
		(end 150.38832 -37.930836)
		(stroke
			(width 0.2)
			(type default)
		)
		(layer "In1.Cu")
	)
	(gr_arc
		(start 150.54707 -39.016178)
		(mid 150.899368 -39.558468)
		(end 151.441658 -39.20617)
		(stroke
			(width 0.2)
			(type default)
		)
		(layer "In1.Cu")
	)
	(gr_line
		(start 150.784814 -37.89807)
		(end 150.54707 -39.016178)
		(stroke
			(width 0.2)
			(type default)
		)
		(layer "In1.Cu")
	)
	(gr_line
		(start 151.441658 -39.20617)
		(end 151.676862 -38.098476)
		(stroke
			(width 0.2)
			(type default)
		)
		(layer "In1.Cu")
	)
	(gr_arc
		(start 151.676862 -38.098476)
		(mid 151.332298 -37.547107)
		(end 150.784814 -37.89807)
		(stroke
			(width 0.2)
			(type default)
		)
		(layer "In1.Cu")
	)
	(gr_line
		(start 165.399974 -37.183568)
		(end 166.199566 -37.183568)
		(stroke
			(width 0.2)
			(type default)
		)
		(layer "In1.Cu")
	)
	(gr_arc
		(start 165.399974 -36.416488)
		(mid 165.016434 -36.800028)
		(end 165.399974 -37.183568)
		(stroke
			(width 0.2)
			(type default)
		)
		(layer "In1.Cu")
	)
	(gr_line
		(start 165.399974 -34.783522)
		(end 166.199566 -34.783522)
		(stroke
			(width 0.2)
			(type default)
		)
		(layer "In1.Cu")
	)
	(gr_arc
		(start 165.399974 -34.016442)
		(mid 165.016434 -34.399982)
		(end 165.399974 -34.783522)
		(stroke
			(width 0.2)
			(type default)
		)
		(layer "In1.Cu")
	)
	(gr_arc
		(start 165.741858 -24.055578)
		(mid 166.125271 -24.439372)
		(end 166.508938 -24.055832)
		(stroke
			(width 0.2)
			(type default)
		)
		(layer "In1.Cu")
	)
	(gr_line
		(start 165.741858 -23.166832)
		(end 165.741858 -24.055578)
		(stroke
			(width 0.2)
			(type default)
		)
		(layer "In1.Cu")
	)
	(gr_arc
		(start 165.81628 -38.399974)
		(mid 166.19982 -38.783514)
		(end 166.58336 -38.399974)
		(stroke
			(width 0.2)
			(type default)
		)
		(layer "In1.Cu")
	)
	(gr_line
		(start 165.81628 -37.599874)
		(end 165.81628 -38.399974)
		(stroke
			(width 0.2)
			(type default)
		)
		(layer "In1.Cu")
	)
	(gr_arc
		(start 165.81628 -35.999928)
		(mid 166.19982 -36.383468)
		(end 166.58336 -35.999928)
		(stroke
			(width 0.2)
			(type default)
		)
		(layer "In1.Cu")
	)
	(gr_line
		(start 165.81628 -35.199828)
		(end 165.81628 -35.999928)
		(stroke
			(width 0.2)
			(type default)
		)
		(layer "In1.Cu")
	)
	(gr_arc
		(start 165.81628 -33.599882)
		(mid 166.19982 -33.983422)
		(end 166.58336 -33.599882)
		(stroke
			(width 0.2)
			(type default)
		)
		(layer "In1.Cu")
	)
	(gr_line
		(start 165.81628 -32.800036)
		(end 165.81628 -33.599882)
		(stroke
			(width 0.2)
			(type default)
		)
		(layer "In1.Cu")
	)
	(gr_arc
		(start 165.81628 -31.199836)
		(mid 166.19982 -31.583376)
		(end 166.58336 -31.199836)
		(stroke
			(width 0.2)
			(type default)
		)
		(layer "In1.Cu")
	)
	(gr_line
		(start 165.81628 -30.39999)
		(end 165.81628 -31.199836)
		(stroke
			(width 0.2)
			(type default)
		)
		(layer "In1.Cu")
	)
	(gr_arc
		(start 166.199566 -37.183568)
		(mid 166.58336 -36.800155)
		(end 166.19982 -36.416488)
		(stroke
			(width 0.2)
			(type default)
		)
		(layer "In1.Cu")
	)
	(gr_arc
		(start 166.199566 -34.783522)
		(mid 166.58336 -34.400109)
		(end 166.19982 -34.016442)
		(stroke
			(width 0.2)
			(type default)
		)
		(layer "In1.Cu")
	)
	(gr_line
		(start 166.19982 -36.416488)
		(end 165.399974 -36.416488)
		(stroke
			(width 0.2)
			(type default)
		)
		(layer "In1.Cu")
	)
	(gr_line
		(start 166.19982 -34.016442)
		(end 165.399974 -34.016442)
		(stroke
			(width 0.2)
			(type default)
		)
		(layer "In1.Cu")
	)
	(gr_line
		(start 166.19982 -29.98343)
		(end 166.999412 -29.983684)
		(stroke
			(width 0.2)
			(type default)
		)
		(layer "In1.Cu")
	)
	(gr_line
		(start 166.200074 -32.383476)
		(end 166.999666 -32.383476)
		(stroke
			(width 0.2)
			(type default)
		)
		(layer "In1.Cu")
	)
	(gr_arc
		(start 166.200074 -31.616396)
		(mid 165.816534 -31.999936)
		(end 166.200074 -32.383476)
		(stroke
			(width 0.2)
			(type default)
		)
		(layer "In1.Cu")
	)
	(gr_arc
		(start 166.200074 -29.21635)
		(mid 165.81628 -29.599763)
		(end 166.19982 -29.98343)
		(stroke
			(width 0.2)
			(type default)
		)
		(layer "In1.Cu")
	)
	(gr_line
		(start 166.508938 -24.055832)
		(end 166.508938 -23.166832)
		(stroke
			(width 0.2)
			(type default)
		)
		(layer "In1.Cu")
	)
	(gr_arc
		(start 166.508938 -23.166832)
		(mid 166.125398 -22.783292)
		(end 165.741858 -23.166832)
		(stroke
			(width 0.2)
			(type default)
		)
		(layer "In1.Cu")
	)
	(gr_line
		(start 166.58336 -38.399974)
		(end 166.58336 -37.600128)
		(stroke
			(width 0.2)
			(type default)
		)
		(layer "In1.Cu")
	)
	(gr_arc
		(start 166.58336 -37.600128)
		(mid 166.199947 -37.216334)
		(end 165.81628 -37.599874)
		(stroke
			(width 0.2)
			(type default)
		)
		(layer "In1.Cu")
	)
	(gr_line
		(start 166.58336 -35.999928)
		(end 166.58336 -35.200082)
		(stroke
			(width 0.2)
			(type default)
		)
		(layer "In1.Cu")
	)
	(gr_arc
		(start 166.58336 -35.200082)
		(mid 166.199947 -34.816288)
		(end 165.81628 -35.199828)
		(stroke
			(width 0.2)
			(type default)
		)
		(layer "In1.Cu")
	)
	(gr_line
		(start 166.58336 -33.599882)
		(end 166.58336 -32.80029)
		(stroke
			(width 0.2)
			(type default)
		)
		(layer "In1.Cu")
	)
	(gr_arc
		(start 166.58336 -32.80029)
		(mid 166.199947 -32.416496)
		(end 165.81628 -32.800036)
		(stroke
			(width 0.2)
			(type default)
		)
		(layer "In1.Cu")
	)
	(gr_line
		(start 166.58336 -31.199836)
		(end 166.58336 -30.400244)
		(stroke
			(width 0.2)
			(type default)
		)
		(layer "In1.Cu")
	)
	(gr_arc
		(start 166.58336 -30.400244)
		(mid 166.199947 -30.01645)
		(end 165.81628 -30.39999)
		(stroke
			(width 0.2)
			(type default)
		)
		(layer "In1.Cu")
	)
	(gr_arc
		(start 166.999412 -29.983684)
		(mid 167.383206 -29.600271)
		(end 166.999666 -29.216604)
		(stroke
			(width 0.2)
			(type default)
		)
		(layer "In1.Cu")
	)
	(gr_arc
		(start 166.999666 -32.383476)
		(mid 167.38346 -32.000063)
		(end 166.99992 -31.616396)
		(stroke
			(width 0.2)
			(type default)
		)
		(layer "In1.Cu")
	)
	(gr_line
		(start 166.999666 -29.216604)
		(end 166.200074 -29.21635)
		(stroke
			(width 0.2)
			(type default)
		)
		(layer "In1.Cu")
	)
	(gr_line
		(start 166.99992 -31.616396)
		(end 166.200074 -31.616396)
		(stroke
			(width 0.2)
			(type default)
		)
		(layer "In1.Cu")
	)
	(gr_line
		(start 167.441626 -30.400244)
		(end 167.44188 -31.199582)
		(stroke
			(width 0.2)
			(type default)
		)
		(layer "In1.Cu")
	)
	(gr_arc
		(start 167.44188 -31.199582)
		(mid 167.80002 -31.557976)
		(end 168.15816 -31.199582)
		(stroke
			(width 0.2)
			(type default)
		)
		(layer "In1.Cu")
	)
	(gr_arc
		(start 167.776398 -24.012652)
		(mid 168.159811 -24.396446)
		(end 168.543478 -24.012906)
		(stroke
			(width 0.2)
			(type default)
		)
		(layer "In1.Cu")
	)
	(gr_line
		(start 167.776398 -23.123906)
		(end 167.776398 -24.012652)
		(stroke
			(width 0.2)
			(type default)
		)
		(layer "In1.Cu")
	)
	(gr_arc
		(start 168.157906 -30.39999)
		(mid 167.799639 -30.04185)
		(end 167.441626 -30.400244)
		(stroke
			(width 0.2)
			(type default)
		)
		(layer "In1.Cu")
	)
	(gr_line
		(start 168.15816 -31.199582)
		(end 168.157906 -30.39999)
		(stroke
			(width 0.2)
			(type default)
		)
		(layer "In1.Cu")
	)
	(gr_arc
		(start 168.241726 -31.199582)
		(mid 168.599739 -31.557976)
		(end 168.958006 -31.199836)
		(stroke
			(width 0.2)
			(type default)
		)
		(layer "In1.Cu")
	)
	(gr_line
		(start 168.241726 -30.39999)
		(end 168.241726 -31.199582)
		(stroke
			(width 0.2)
			(type default)
		)
		(layer "In1.Cu")
	)
	(gr_line
		(start 168.543478 -24.012906)
		(end 168.543478 -23.123906)
		(stroke
			(width 0.2)
			(type default)
		)
		(layer "In1.Cu")
	)
	(gr_arc
		(start 168.543478 -23.123906)
		(mid 168.159938 -22.740366)
		(end 167.776398 -23.123906)
		(stroke
			(width 0.2)
			(type default)
		)
		(layer "In1.Cu")
	)
	(gr_line
		(start 168.958006 -31.199836)
		(end 168.958006 -30.39999)
		(stroke
			(width 0.2)
			(type default)
		)
		(layer "In1.Cu")
	)
	(gr_arc
		(start 168.958006 -30.39999)
		(mid 168.599866 -30.04185)
		(end 168.241726 -30.39999)
		(stroke
			(width 0.2)
			(type default)
		)
		(layer "In1.Cu")
	)
	(gr_arc
		(start 169.833544 -24.004016)
		(mid 170.216957 -24.38781)
		(end 170.600624 -24.00427)
		(stroke
			(width 0.2)
			(type default)
		)
		(layer "In1.Cu")
	)
	(gr_line
		(start 169.833544 -23.11527)
		(end 169.833544 -24.004016)
		(stroke
			(width 0.2)
			(type default)
		)
		(layer "In1.Cu")
	)
	(gr_line
		(start 169.841672 -30.400244)
		(end 169.841926 -31.199836)
		(stroke
			(width 0.2)
			(type default)
		)
		(layer "In1.Cu")
	)
	(gr_arc
		(start 169.841926 -31.199836)
		(mid 170.200066 -31.55823)
		(end 170.558206 -31.199836)
		(stroke
			(width 0.2)
			(type default)
		)
		(layer "In1.Cu")
	)
	(gr_arc
		(start 170.557952 -30.39999)
		(mid 170.199685 -30.04185)
		(end 169.841672 -30.400244)
		(stroke
			(width 0.2)
			(type default)
		)
		(layer "In1.Cu")
	)
	(gr_line
		(start 170.558206 -31.199836)
		(end 170.557952 -30.39999)
		(stroke
			(width 0.2)
			(type default)
		)
		(layer "In1.Cu")
	)
	(gr_line
		(start 170.600624 -24.00427)
		(end 170.600624 -23.11527)
		(stroke
			(width 0.2)
			(type default)
		)
		(layer "In1.Cu")
	)
	(gr_arc
		(start 170.600624 -23.11527)
		(mid 170.217084 -22.73173)
		(end 169.833544 -23.11527)
		(stroke
			(width 0.2)
			(type default)
		)
		(layer "In1.Cu")
	)
	(gr_line
		(start 170.641772 -30.400244)
		(end 170.642026 -31.199836)
		(stroke
			(width 0.2)
			(type default)
		)
		(layer "In1.Cu")
	)
	(gr_arc
		(start 170.642026 -31.199836)
		(mid 171.000166 -31.55823)
		(end 171.358306 -31.199836)
		(stroke
			(width 0.2)
			(type default)
		)
		(layer "In1.Cu")
	)
	(gr_arc
		(start 171.358052 -30.39999)
		(mid 170.999785 -30.04185)
		(end 170.641772 -30.400244)
		(stroke
			(width 0.2)
			(type default)
		)
		(layer "In1.Cu")
	)
	(gr_line
		(start 171.358306 -31.199836)
		(end 171.358052 -30.39999)
		(stroke
			(width 0.2)
			(type default)
		)
		(layer "In1.Cu")
	)
	(gr_arc
		(start 171.88561 -24.00173)
		(mid 172.269023 -24.385524)
		(end 172.65269 -24.001984)
		(stroke
			(width 0.2)
			(type default)
		)
		(layer "In1.Cu")
	)
	(gr_line
		(start 171.88561 -23.112984)
		(end 171.88561 -24.00173)
		(stroke
			(width 0.2)
			(type default)
		)
		(layer "In1.Cu")
	)
	(gr_line
		(start 172.241718 -30.400244)
		(end 172.241972 -31.199836)
		(stroke
			(width 0.2)
			(type default)
		)
		(layer "In1.Cu")
	)
	(gr_arc
		(start 172.241972 -31.199836)
		(mid 172.600112 -31.55823)
		(end 172.958252 -31.199836)
		(stroke
			(width 0.2)
			(type default)
		)
		(layer "In1.Cu")
	)
	(gr_line
		(start 172.65269 -24.001984)
		(end 172.65269 -23.112984)
		(stroke
			(width 0.2)
			(type default)
		)
		(layer "In1.Cu")
	)
	(gr_arc
		(start 172.65269 -23.112984)
		(mid 172.26915 -22.729444)
		(end 171.88561 -23.112984)
		(stroke
			(width 0.2)
			(type default)
		)
		(layer "In1.Cu")
	)
	(gr_arc
		(start 172.957998 -30.39999)
		(mid 172.599731 -30.04185)
		(end 172.241718 -30.400244)
		(stroke
			(width 0.2)
			(type default)
		)
		(layer "In1.Cu")
	)
	(gr_line
		(start 172.958252 -31.199836)
		(end 172.957998 -30.39999)
		(stroke
			(width 0.2)
			(type default)
		)
		(layer "In1.Cu")
	)
	(gr_line
		(start 173.041818 -30.400244)
		(end 173.042072 -31.199836)
		(stroke
			(width 0.2)
			(type default)
		)
		(layer "In1.Cu")
	)
	(gr_arc
		(start 173.042072 -31.199836)
		(mid 173.400212 -31.55823)
		(end 173.758352 -31.199836)
		(stroke
			(width 0.2)
			(type default)
		)
		(layer "In1.Cu")
	)
	(gr_arc
		(start 173.758098 -30.39999)
		(mid 173.399831 -30.04185)
		(end 173.041818 -30.400244)
		(stroke
			(width 0.2)
			(type default)
		)
		(layer "In1.Cu")
	)
	(gr_line
		(start 173.758352 -31.199836)
		(end 173.758098 -30.39999)
		(stroke
			(width 0.2)
			(type default)
		)
		(layer "In1.Cu")
	)
	(gr_arc
		(start 173.931326 -24.001222)
		(mid 174.314739 -24.385016)
		(end 174.698406 -24.001476)
		(stroke
			(width 0.2)
			(type default)
		)
		(layer "In1.Cu")
	)
	(gr_line
		(start 173.931326 -23.112476)
		(end 173.931326 -24.001222)
		(stroke
			(width 0.2)
			(type default)
		)
		(layer "In1.Cu")
	)
	(gr_line
		(start 174.641764 -30.400244)
		(end 174.642018 -31.199836)
		(stroke
			(width 0.2)
			(type default)
		)
		(layer "In1.Cu")
	)
	(gr_arc
		(start 174.642018 -31.199836)
		(mid 175.000158 -31.55823)
		(end 175.358298 -31.199836)
		(stroke
			(width 0.2)
			(type default)
		)
		(layer "In1.Cu")
	)
	(gr_line
		(start 174.698406 -24.001476)
		(end 174.698406 -23.112476)
		(stroke
			(width 0.2)
			(type default)
		)
		(layer "In1.Cu")
	)
	(gr_arc
		(start 174.698406 -23.112476)
		(mid 174.314866 -22.728936)
		(end 173.931326 -23.112476)
		(stroke
			(width 0.2)
			(type default)
		)
		(layer "In1.Cu")
	)
	(gr_arc
		(start 175.358044 -30.39999)
		(mid 174.999777 -30.04185)
		(end 174.641764 -30.400244)
		(stroke
			(width 0.2)
			(type default)
		)
		(layer "In1.Cu")
	)
	(gr_line
		(start 175.358298 -31.199836)
		(end 175.358044 -30.39999)
		(stroke
			(width 0.2)
			(type default)
		)
		(layer "In1.Cu")
	)
	(gr_arc
		(start 175.441864 -31.199836)
		(mid 175.799877 -31.55823)
		(end 176.158144 -31.20009)
		(stroke
			(width 0.2)
			(type default)
		)
		(layer "In1.Cu")
	)
	(gr_line
		(start 175.441864 -30.400244)
		(end 175.441864 -31.199836)
		(stroke
			(width 0.2)
			(type default)
		)
		(layer "In1.Cu")
	)
	(gr_arc
		(start 175.98517 -23.992078)
		(mid 176.368583 -24.375872)
		(end 176.75225 -23.992332)
		(stroke
			(width 0.2)
			(type default)
		)
		(layer "In1.Cu")
	)
	(gr_line
		(start 175.98517 -23.103332)
		(end 175.98517 -23.992078)
		(stroke
			(width 0.2)
			(type default)
		)
		(layer "In1.Cu")
	)
	(gr_line
		(start 176.158144 -31.20009)
		(end 176.158144 -30.400244)
		(stroke
			(width 0.2)
			(type default)
		)
		(layer "In1.Cu")
	)
	(gr_arc
		(start 176.158144 -30.400244)
		(mid 175.800004 -30.042104)
		(end 175.441864 -30.400244)
		(stroke
			(width 0.2)
			(type default)
		)
		(layer "In1.Cu")
	)
	(gr_line
		(start 176.75225 -23.992332)
		(end 176.75225 -23.103332)
		(stroke
			(width 0.2)
			(type default)
		)
		(layer "In1.Cu")
	)
	(gr_arc
		(start 176.75225 -23.103332)
		(mid 176.36871 -22.719792)
		(end 175.98517 -23.103332)
		(stroke
			(width 0.2)
			(type default)
		)
		(layer "In1.Cu")
	)
	(gr_arc
		(start 178.023774 -24.005286)
		(mid 178.407187 -24.38908)
		(end 178.790854 -24.00554)
		(stroke
			(width 0.2)
			(type default)
		)
		(layer "In1.Cu")
	)
	(gr_line
		(start 178.023774 -23.11654)
		(end 178.023774 -24.005286)
		(stroke
			(width 0.2)
			(type default)
		)
		(layer "In1.Cu")
	)
	(gr_line
		(start 178.790854 -24.00554)
		(end 178.790854 -23.11654)
		(stroke
			(width 0.2)
			(type default)
		)
		(layer "In1.Cu")
	)
	(gr_arc
		(start 178.790854 -23.11654)
		(mid 178.407314 -22.733)
		(end 178.023774 -23.11654)
		(stroke
			(width 0.2)
			(type default)
		)
		(layer "In1.Cu")
	)
	(gr_arc
		(start 179.438554 -12.399772)
		(mid 179.999767 -12.961366)
		(end 180.561234 -12.400026)
		(stroke
			(width 0.2)
			(type default)
		)
		(layer "In1.Cu")
	)
	(gr_line
		(start 179.438554 -10.999978)
		(end 179.438554 -12.399772)
		(stroke
			(width 0.2)
			(type default)
		)
		(layer "In1.Cu")
	)
	(gr_arc
		(start 179.438554 -8.79983)
		(mid 179.999767 -9.361424)
		(end 180.561234 -8.800084)
		(stroke
			(width 0.2)
			(type default)
		)
		(layer "In1.Cu")
	)
	(gr_line
		(start 179.438554 -7.400036)
		(end 179.438554 -8.79983)
		(stroke
			(width 0.2)
			(type default)
		)
		(layer "In1.Cu")
	)
	(gr_arc
		(start 179.438554 -5.199888)
		(mid 179.999767 -5.761482)
		(end 180.561234 -5.200142)
		(stroke
			(width 0.2)
			(type default)
		)
		(layer "In1.Cu")
	)
	(gr_line
		(start 179.438554 -3.800094)
		(end 179.438554 -5.199888)
		(stroke
			(width 0.2)
			(type default)
		)
		(layer "In1.Cu")
	)
	(gr_arc
		(start 180.052472 -24.485092)
		(mid 180.435885 -24.868886)
		(end 180.819552 -24.485346)
		(stroke
			(width 0.2)
			(type default)
		)
		(layer "In1.Cu")
	)
	(gr_line
		(start 180.052472 -23.596346)
		(end 180.052472 -24.485092)
		(stroke
			(width 0.2)
			(type default)
		)
		(layer "In1.Cu")
	)
	(gr_line
		(start 180.561234 -12.400026)
		(end 180.561234 -10.999978)
		(stroke
			(width 0.2)
			(type default)
		)
		(layer "In1.Cu")
	)
	(gr_arc
		(start 180.561234 -10.999978)
		(mid 179.999894 -10.438638)
		(end 179.438554 -10.999978)
		(stroke
			(width 0.2)
			(type default)
		)
		(layer "In1.Cu")
	)
	(gr_line
		(start 180.561234 -8.800084)
		(end 180.561234 -7.400036)
		(stroke
			(width 0.2)
			(type default)
		)
		(layer "In1.Cu")
	)
	(gr_arc
		(start 180.561234 -7.400036)
		(mid 179.999894 -6.838696)
		(end 179.438554 -7.400036)
		(stroke
			(width 0.2)
			(type default)
		)
		(layer "In1.Cu")
	)
	(gr_line
		(start 180.561234 -5.200142)
		(end 180.561234 -3.800094)
		(stroke
			(width 0.2)
			(type default)
		)
		(layer "In1.Cu")
	)
	(gr_arc
		(start 180.561234 -3.800094)
		(mid 179.999894 -3.238754)
		(end 179.438554 -3.800094)
		(stroke
			(width 0.2)
			(type default)
		)
		(layer "In1.Cu")
	)
	(gr_line
		(start 180.819552 -24.485346)
		(end 180.819552 -23.596346)
		(stroke
			(width 0.2)
			(type default)
		)
		(layer "In1.Cu")
	)
	(gr_arc
		(start 180.819552 -23.596346)
		(mid 180.436012 -23.212806)
		(end 180.052472 -23.596346)
		(stroke
			(width 0.2)
			(type default)
		)
		(layer "In1.Cu")
	)
	(gr_arc
		(start 181.238652 -11.199876)
		(mid 181.799865 -11.76147)
		(end 182.361332 -11.20013)
		(stroke
			(width 0.2)
			(type default)
		)
		(layer "In1.Cu")
	)
	(gr_line
		(start 181.238652 -9.800082)
		(end 181.238652 -11.199876)
		(stroke
			(width 0.2)
			(type default)
		)
		(layer "In1.Cu")
	)
	(gr_arc
		(start 181.238652 -3.999738)
		(mid 181.799865 -4.561332)
		(end 182.361332 -3.999992)
		(stroke
			(width 0.2)
			(type default)
		)
		(layer "In1.Cu")
	)
	(gr_line
		(start 181.238652 -2.600198)
		(end 181.238652 -3.999738)
		(stroke
			(width 0.2)
			(type default)
		)
		(layer "In1.Cu")
	)
	(gr_line
		(start 182.361332 -11.20013)
		(end 182.361332 -9.800082)
		(stroke
			(width 0.2)
			(type default)
		)
		(layer "In1.Cu")
	)
	(gr_arc
		(start 182.361332 -9.800082)
		(mid 181.799992 -9.238742)
		(end 181.238652 -9.800082)
		(stroke
			(width 0.2)
			(type default)
		)
		(layer "In1.Cu")
	)
	(gr_line
		(start 182.361332 -3.999992)
		(end 182.361332 -2.600198)
		(stroke
			(width 0.2)
			(type default)
		)
		(layer "In1.Cu")
	)
	(gr_arc
		(start 182.361332 -2.600198)
		(mid 181.799992 -2.038858)
		(end 181.238652 -2.600198)
		(stroke
			(width 0.2)
			(type default)
		)
		(layer "In1.Cu")
	)
	(gr_arc
		(start 183.038496 -12.399772)
		(mid 183.599709 -12.961366)
		(end 184.161176 -12.400026)
		(stroke
			(width 0.2)
			(type default)
		)
		(layer "In1.Cu")
	)
	(gr_line
		(start 183.038496 -10.999978)
		(end 183.038496 -12.399772)
		(stroke
			(width 0.2)
			(type default)
		)
		(layer "In1.Cu")
	)
	(gr_arc
		(start 183.038496 -5.199888)
		(mid 183.599709 -5.761482)
		(end 184.161176 -5.200142)
		(stroke
			(width 0.2)
			(type default)
		)
		(layer "In1.Cu")
	)
	(gr_line
		(start 183.038496 -3.800094)
		(end 183.038496 -5.199888)
		(stroke
			(width 0.2)
			(type default)
		)
		(layer "In1.Cu")
	)
	(gr_line
		(start 184.161176 -12.400026)
		(end 184.161176 -10.999978)
		(stroke
			(width 0.2)
			(type default)
		)
		(layer "In1.Cu")
	)
	(gr_arc
		(start 184.161176 -10.999978)
		(mid 183.599836 -10.438638)
		(end 183.038496 -10.999978)
		(stroke
			(width 0.2)
			(type default)
		)
		(layer "In1.Cu")
	)
	(gr_line
		(start 184.161176 -5.200142)
		(end 184.161176 -3.800094)
		(stroke
			(width 0.2)
			(type default)
		)
		(layer "In1.Cu")
	)
	(gr_arc
		(start 184.161176 -3.800094)
		(mid 183.599836 -3.238754)
		(end 183.038496 -3.800094)
		(stroke
			(width 0.2)
			(type default)
		)
		(layer "In1.Cu")
	)
	(gr_arc
		(start 184.838594 -11.199876)
		(mid 185.399807 -11.76147)
		(end 185.961274 -11.20013)
		(stroke
			(width 0.2)
			(type default)
		)
		(layer "In1.Cu")
	)
	(gr_line
		(start 184.838594 -9.800082)
		(end 184.838594 -11.199876)
		(stroke
			(width 0.2)
			(type default)
		)
		(layer "In1.Cu")
	)
	(gr_arc
		(start 184.838594 -3.999738)
		(mid 185.399807 -4.561332)
		(end 185.961274 -3.999992)
		(stroke
			(width 0.2)
			(type default)
		)
		(layer "In1.Cu")
	)
	(gr_line
		(start 184.838594 -2.600198)
		(end 184.838594 -3.999738)
		(stroke
			(width 0.2)
			(type default)
		)
		(layer "In1.Cu")
	)
	(gr_line
		(start 185.961274 -11.20013)
		(end 185.961274 -9.800082)
		(stroke
			(width 0.2)
			(type default)
		)
		(layer "In1.Cu")
	)
	(gr_arc
		(start 185.961274 -9.800082)
		(mid 185.399934 -9.238742)
		(end 184.838594 -9.800082)
		(stroke
			(width 0.2)
			(type default)
		)
		(layer "In1.Cu")
	)
	(gr_line
		(start 185.961274 -3.999992)
		(end 185.961274 -2.600198)
		(stroke
			(width 0.2)
			(type default)
		)
		(layer "In1.Cu")
	)
	(gr_arc
		(start 185.961274 -2.600198)
		(mid 185.399934 -2.038858)
		(end 184.838594 -2.600198)
		(stroke
			(width 0.2)
			(type default)
		)
		(layer "In1.Cu")
	)
	(gr_arc
		(start 186.638438 -12.399772)
		(mid 187.199651 -12.961366)
		(end 187.761118 -12.400026)
		(stroke
			(width 0.2)
			(type default)
		)
		(layer "In1.Cu")
	)
	(gr_line
		(start 186.638438 -10.999978)
		(end 186.638438 -12.399772)
		(stroke
			(width 0.2)
			(type default)
		)
		(layer "In1.Cu")
	)
	(gr_arc
		(start 186.638438 -5.199888)
		(mid 187.199651 -5.761482)
		(end 187.761118 -5.200142)
		(stroke
			(width 0.2)
			(type default)
		)
		(layer "In1.Cu")
	)
	(gr_line
		(start 186.638438 -3.800094)
		(end 186.638438 -5.199888)
		(stroke
			(width 0.2)
			(type default)
		)
		(layer "In1.Cu")
	)
	(gr_line
		(start 187.761118 -12.400026)
		(end 187.761118 -10.999978)
		(stroke
			(width 0.2)
			(type default)
		)
		(layer "In1.Cu")
	)
	(gr_arc
		(start 187.761118 -10.999978)
		(mid 187.199778 -10.438638)
		(end 186.638438 -10.999978)
		(stroke
			(width 0.2)
			(type default)
		)
		(layer "In1.Cu")
	)
	(gr_line
		(start 187.761118 -5.200142)
		(end 187.761118 -3.800094)
		(stroke
			(width 0.2)
			(type default)
		)
		(layer "In1.Cu")
	)
	(gr_arc
		(start 187.761118 -3.800094)
		(mid 187.199778 -3.238754)
		(end 186.638438 -3.800094)
		(stroke
			(width 0.2)
			(type default)
		)
		(layer "In1.Cu")
	)
	(gr_arc
		(start 188.438536 -11.199876)
		(mid 188.999749 -11.76147)
		(end 189.561216 -11.20013)
		(stroke
			(width 0.2)
			(type default)
		)
		(layer "In1.Cu")
	)
	(gr_line
		(start 188.438536 -9.800082)
		(end 188.438536 -11.199876)
		(stroke
			(width 0.2)
			(type default)
		)
		(layer "In1.Cu")
	)
	(gr_arc
		(start 188.438536 -3.999738)
		(mid 188.999749 -4.561332)
		(end 189.561216 -3.999992)
		(stroke
			(width 0.2)
			(type default)
		)
		(layer "In1.Cu")
	)
	(gr_line
		(start 188.438536 -2.600198)
		(end 188.438536 -3.999738)
		(stroke
			(width 0.2)
			(type default)
		)
		(layer "In1.Cu")
	)
	(gr_line
		(start 189.561216 -11.20013)
		(end 189.561216 -9.800082)
		(stroke
			(width 0.2)
			(type default)
		)
		(layer "In1.Cu")
	)
	(gr_arc
		(start 189.561216 -9.800082)
		(mid 188.999876 -9.238742)
		(end 188.438536 -9.800082)
		(stroke
			(width 0.2)
			(type default)
		)
		(layer "In1.Cu")
	)
	(gr_line
		(start 189.561216 -3.999992)
		(end 189.561216 -2.600198)
		(stroke
			(width 0.2)
			(type default)
		)
		(layer "In1.Cu")
	)
	(gr_arc
		(start 189.561216 -2.600198)
		(mid 188.999876 -2.038858)
		(end 188.438536 -2.600198)
		(stroke
			(width 0.2)
			(type default)
		)
		(layer "In1.Cu")
	)
	(gr_arc
		(start 190.238634 -12.399772)
		(mid 190.799847 -12.961366)
		(end 191.361314 -12.400026)
		(stroke
			(width 0.2)
			(type default)
		)
		(layer "In1.Cu")
	)
	(gr_line
		(start 190.238634 -10.999978)
		(end 190.238634 -12.399772)
		(stroke
			(width 0.2)
			(type default)
		)
		(layer "In1.Cu")
	)
	(gr_arc
		(start 190.238634 -5.199888)
		(mid 190.799847 -5.761482)
		(end 191.361314 -5.200142)
		(stroke
			(width 0.2)
			(type default)
		)
		(layer "In1.Cu")
	)
	(gr_line
		(start 190.238634 -3.800094)
		(end 190.238634 -5.199888)
		(stroke
			(width 0.2)
			(type default)
		)
		(layer "In1.Cu")
	)
	(gr_line
		(start 191.361314 -12.400026)
		(end 191.361314 -10.999978)
		(stroke
			(width 0.2)
			(type default)
		)
		(layer "In1.Cu")
	)
	(gr_arc
		(start 191.361314 -10.999978)
		(mid 190.799974 -10.438638)
		(end 190.238634 -10.999978)
		(stroke
			(width 0.2)
			(type default)
		)
		(layer "In1.Cu")
	)
	(gr_line
		(start 191.361314 -5.200142)
		(end 191.361314 -3.800094)
		(stroke
			(width 0.2)
			(type default)
		)
		(layer "In1.Cu")
	)
	(gr_arc
		(start 191.361314 -3.800094)
		(mid 190.799974 -3.238754)
		(end 190.238634 -3.800094)
		(stroke
			(width 0.2)
			(type default)
		)
		(layer "In1.Cu")
	)
	(gr_arc
		(start 192.038478 -11.199876)
		(mid 192.599691 -11.76147)
		(end 193.161158 -11.20013)
		(stroke
			(width 0.2)
			(type default)
		)
		(layer "In1.Cu")
	)
	(gr_line
		(start 192.038478 -9.800082)
		(end 192.038478 -11.199876)
		(stroke
			(width 0.2)
			(type default)
		)
		(layer "In1.Cu")
	)
	(gr_arc
		(start 192.038478 -3.999738)
		(mid 192.599691 -4.561332)
		(end 193.161158 -3.999992)
		(stroke
			(width 0.2)
			(type default)
		)
		(layer "In1.Cu")
	)
	(gr_line
		(start 192.038478 -2.600198)
		(end 192.038478 -3.999738)
		(stroke
			(width 0.2)
			(type default)
		)
		(layer "In1.Cu")
	)
	(gr_line
		(start 193.161158 -11.20013)
		(end 193.161158 -9.800082)
		(stroke
			(width 0.2)
			(type default)
		)
		(layer "In1.Cu")
	)
	(gr_arc
		(start 193.161158 -9.800082)
		(mid 192.599818 -9.238742)
		(end 192.038478 -9.800082)
		(stroke
			(width 0.2)
			(type default)
		)
		(layer "In1.Cu")
	)
	(gr_line
		(start 193.161158 -3.999992)
		(end 193.161158 -2.600198)
		(stroke
			(width 0.2)
			(type default)
		)
		(layer "In1.Cu")
	)
	(gr_arc
		(start 193.161158 -2.600198)
		(mid 192.599818 -2.038858)
		(end 192.038478 -2.600198)
		(stroke
			(width 0.2)
			(type default)
		)
		(layer "In1.Cu")
	)
	(gr_line
		(start 208.000092 -144.999964)
		(end 127.00254 -144.999964)
		(stroke
			(width 1.524)
			(type default)
		)
		(layer "In1.Cu")
	)
	(gr_arc
		(start 208.000092 -144.999964)
		(mid 209.414297 -144.41418)
		(end 210.000088 -142.999968)
		(stroke
			(width 1.524)
			(type default)
		)
		(layer "In1.Cu")
	)
	(gr_arc
		(start 210.000088 -1.999996)
		(mid 209.414301 -0.585791)
		(end 208.000092 0)
		(stroke
			(width 1.524)
			(type default)
		)
		(layer "In1.Cu")
	)
	(gr_line
		(start 210.000088 -1.999996)
		(end 210.000088 -142.999968)
		(stroke
			(width 1.524)
			(type default)
		)
		(layer "In1.Cu")
	)
	(gr_line
		(start 124.682758 -46.716696)
		(end 124.682758 -47.001938)
		(stroke
			(width 0.0508)
			(type default)
		)
		(layer "In2.Cu")
	)
	(gr_arc
		(start 124.682758 -46.143926)
		(mid 124.692986 -46.195346)
		(end 124.722128 -46.238922)
		(stroke
			(width 0.0508)
			(type default)
		)
		(layer "In2.Cu")
	)
	(gr_line
		(start 124.682758 -45.858938)
		(end 124.682758 -46.143926)
		(stroke
			(width 0.0508)
			(type default)
		)
		(layer "In2.Cu")
	)
	(gr_arc
		(start 124.722128 -46.622208)
		(mid 124.693028 -46.66553)
		(end 124.682758 -46.716696)
		(stroke
			(width 0.0508)
			(type default)
		)
		(layer "In2.Cu")
	)
	(gr_line
		(start 124.722128 -46.622208)
		(end 124.731526 -46.61281)
		(stroke
			(width 0.0508)
			(type default)
		)
		(layer "In2.Cu")
	)
	(gr_arc
		(start 124.722128 -46.238922)
		(mid 124.765479 -46.267889)
		(end 124.816616 -46.278038)
		(stroke
			(width 0.0508)
			(type default)
		)
		(layer "In2.Cu")
	)
	(gr_arc
		(start 124.803408 -46.582838)
		(mid 124.764483 -46.590657)
		(end 124.731526 -46.61281)
		(stroke
			(width 0.0508)
			(type default)
		)
		(layer "In2.Cu")
	)
	(gr_line
		(start 126.000002 -60.000134)
		(end 126.315724 -60.000134)
		(stroke
			(width 0.04445)
			(type default)
		)
		(layer "In2.Cu")
	)
	(gr_line
		(start 126.000002 -59.000136)
		(end 126.315724 -59.000136)
		(stroke
			(width 0.04445)
			(type default)
		)
		(layer "In2.Cu")
	)
	(gr_line
		(start 126.000002 -58.000138)
		(end 126.315724 -58.000138)
		(stroke
			(width 0.04445)
			(type default)
		)
		(layer "In2.Cu")
	)
	(gr_line
		(start 126.000002 -57.00014)
		(end 126.315724 -57.00014)
		(stroke
			(width 0.04445)
			(type default)
		)
		(layer "In2.Cu")
	)
	(gr_line
		(start 126.000002 -56.000142)
		(end 126.315724 -56.000142)
		(stroke
			(width 0.04445)
			(type default)
		)
		(layer "In2.Cu")
	)
	(gr_line
		(start 126.000002 -55.000144)
		(end 126.315724 -55.000144)
		(stroke
			(width 0.04445)
			(type default)
		)
		(layer "In2.Cu")
	)
	(gr_line
		(start 126.000002 -54.000146)
		(end 126.315724 -54.000146)
		(stroke
			(width 0.04445)
			(type default)
		)
		(layer "In2.Cu")
	)
	(gr_arc
		(start 126.315724 -60.000134)
		(mid 126.378586 -59.974096)
		(end 126.404624 -59.911234)
		(stroke
			(width 0.04445)
			(type default)
		)
		(layer "In2.Cu")
	)
	(gr_arc
		(start 126.315724 -59.000136)
		(mid 126.378586 -58.974098)
		(end 126.404624 -58.911236)
		(stroke
			(width 0.04445)
			(type default)
		)
		(layer "In2.Cu")
	)
	(gr_arc
		(start 126.315724 -58.000138)
		(mid 126.378586 -57.9741)
		(end 126.404624 -57.911238)
		(stroke
			(width 0.04445)
			(type default)
		)
		(layer "In2.Cu")
	)
	(gr_arc
		(start 126.315724 -57.00014)
		(mid 126.378586 -56.974102)
		(end 126.404624 -56.91124)
		(stroke
			(width 0.04445)
			(type default)
		)
		(layer "In2.Cu")
	)
	(gr_arc
		(start 126.315724 -56.000142)
		(mid 126.378585 -55.974098)
		(end 126.404624 -55.911242)
		(stroke
			(width 0.04445)
			(type default)
		)
		(layer "In2.Cu")
	)
	(gr_arc
		(start 126.315724 -55.000144)
		(mid 126.378586 -54.9741)
		(end 126.404624 -54.911244)
		(stroke
			(width 0.04445)
			(type default)
		)
		(layer "In2.Cu")
	)
	(gr_arc
		(start 126.315724 -54.000146)
		(mid 126.378586 -53.974108)
		(end 126.404624 -53.911246)
		(stroke
			(width 0.04445)
			(type default)
		)
		(layer "In2.Cu")
	)
	(gr_arc
		(start 126.595124 -59.911234)
		(mid 126.621176 -59.974065)
		(end 126.684024 -60.000134)
		(stroke
			(width 0.04445)
			(type default)
		)
		(layer "In2.Cu")
	)
	(gr_arc
		(start 126.595124 -58.911236)
		(mid 126.621176 -58.974066)
		(end 126.684024 -59.000136)
		(stroke
			(width 0.04445)
			(type default)
		)
		(layer "In2.Cu")
	)
	(gr_arc
		(start 126.595124 -57.911238)
		(mid 126.621177 -57.974067)
		(end 126.684024 -58.000138)
		(stroke
			(width 0.04445)
			(type default)
		)
		(layer "In2.Cu")
	)
	(gr_arc
		(start 126.595124 -56.91124)
		(mid 126.621178 -56.974067)
		(end 126.684024 -57.00014)
		(stroke
			(width 0.04445)
			(type default)
		)
		(layer "In2.Cu")
	)
	(gr_arc
		(start 126.595124 -55.911242)
		(mid 126.621162 -55.974104)
		(end 126.684024 -56.000142)
		(stroke
			(width 0.04445)
			(type default)
		)
		(layer "In2.Cu")
	)
	(gr_arc
		(start 126.595124 -54.911244)
		(mid 126.621162 -54.974106)
		(end 126.684024 -55.000144)
		(stroke
			(width 0.04445)
			(type default)
		)
		(layer "In2.Cu")
	)
	(gr_arc
		(start 126.595124 -53.911246)
		(mid 126.62118 -53.97407)
		(end 126.684024 -54.000146)
		(stroke
			(width 0.04445)
			(type default)
		)
		(layer "In2.Cu")
	)
	(gr_line
		(start 126.684024 -60.000134)
		(end 127 -60.000134)
		(stroke
			(width 0.04445)
			(type default)
		)
		(layer "In2.Cu")
	)
	(gr_line
		(start 126.684024 -59.000136)
		(end 127 -59.000136)
		(stroke
			(width 0.04445)
			(type default)
		)
		(layer "In2.Cu")
	)
	(gr_line
		(start 126.684024 -58.000138)
		(end 127 -58.000138)
		(stroke
			(width 0.04445)
			(type default)
		)
		(layer "In2.Cu")
	)
	(gr_line
		(start 126.684024 -57.00014)
		(end 127 -57.00014)
		(stroke
			(width 0.04445)
			(type default)
		)
		(layer "In2.Cu")
	)
	(gr_line
		(start 126.684024 -56.000142)
		(end 127 -56.000142)
		(stroke
			(width 0.04445)
			(type default)
		)
		(layer "In2.Cu")
	)
	(gr_line
		(start 126.684024 -55.000144)
		(end 127 -55.000144)
		(stroke
			(width 0.04445)
			(type default)
		)
		(layer "In2.Cu")
	)
	(gr_line
		(start 126.684024 -54.000146)
		(end 127 -54.000146)
		(stroke
			(width 0.04445)
			(type default)
		)
		(layer "In2.Cu")
	)
	(gr_line
		(start 126.953518 -49.412906)
		(end 127.003556 -49.462944)
		(stroke
			(width 0.0508)
			(type default)
		)
		(layer "In2.Cu")
	)
	(gr_line
		(start 126.955042 -48.979836)
		(end 127.221234 -48.979836)
		(stroke
			(width 0.0508)
			(type default)
		)
		(layer "In2.Cu")
	)
	(gr_line
		(start 127 -53.000148)
		(end 127.315722 -53.000148)
		(stroke
			(width 0.04445)
			(type default)
		)
		(layer "In2.Cu")
	)
	(gr_line
		(start 127.076708 -46.701964)
		(end 127.076708 -46.987206)
		(stroke
			(width 0.0508)
			(type default)
		)
		(layer "In2.Cu")
	)
	(gr_arc
		(start 127.076708 -46.129194)
		(mid 127.086959 -46.180601)
		(end 127.116078 -46.22419)
		(stroke
			(width 0.0508)
			(type default)
		)
		(layer "In2.Cu")
	)
	(gr_line
		(start 127.076708 -45.844206)
		(end 127.076708 -46.129194)
		(stroke
			(width 0.0508)
			(type default)
		)
		(layer "In2.Cu")
	)
	(gr_arc
		(start 127.116078 -46.607476)
		(mid 127.087029 -46.650812)
		(end 127.076708 -46.701964)
		(stroke
			(width 0.0508)
			(type default)
		)
		(layer "In2.Cu")
	)
	(gr_line
		(start 127.116078 -46.607476)
		(end 127.125476 -46.598078)
		(stroke
			(width 0.0508)
			(type default)
		)
		(layer "In2.Cu")
	)
	(gr_arc
		(start 127.116078 -46.22419)
		(mid 127.159433 -46.253146)
		(end 127.210566 -46.263306)
		(stroke
			(width 0.0508)
			(type default)
		)
		(layer "In2.Cu")
	)
	(gr_arc
		(start 127.197358 -46.568106)
		(mid 127.158448 -46.575957)
		(end 127.125476 -46.598078)
		(stroke
			(width 0.0508)
			(type default)
		)
		(layer "In2.Cu")
	)
	(gr_line
		(start 127.221234 -48.979836)
		(end 127.436626 -49.195482)
		(stroke
			(width 0.0508)
			(type default)
		)
		(layer "In2.Cu")
	)
	(gr_arc
		(start 127.315722 -53.000148)
		(mid 127.378587 -52.974105)
		(end 127.404622 -52.911248)
		(stroke
			(width 0.04445)
			(type default)
		)
		(layer "In2.Cu")
	)
	(gr_line
		(start 127.347472 -50.737516)
		(end 127.363474 -50.753518)
		(stroke
			(width 0.04445)
			(type default)
		)
		(layer "In2.Cu")
	)
	(gr_line
		(start 127.347472 -50.715418)
		(end 127.347472 -50.737516)
		(stroke
			(width 0.04445)
			(type default)
		)
		(layer "In2.Cu")
	)
	(gr_line
		(start 127.365252 -50.755296)
		(end 127.404622 -50.794666)
		(stroke
			(width 0.04445)
			(type default)
		)
		(layer "In2.Cu")
	)
	(gr_line
		(start 127.436626 -49.195482)
		(end 127.436626 -49.46142)
		(stroke
			(width 0.0508)
			(type default)
		)
		(layer "In2.Cu")
	)
	(gr_arc
		(start 127.595122 -52.911248)
		(mid 127.62116 -52.97411)
		(end 127.684022 -53.000148)
		(stroke
			(width 0.04445)
			(type default)
		)
		(layer "In2.Cu")
	)
	(gr_line
		(start 127.595122 -50.794666)
		(end 127.634492 -50.755296)
		(stroke
			(width 0.04445)
			(type default)
		)
		(layer "In2.Cu")
	)
	(gr_line
		(start 127.63627 -50.753518)
		(end 127.652272 -50.737516)
		(stroke
			(width 0.04445)
			(type default)
		)
		(layer "In2.Cu")
	)
	(gr_line
		(start 127.652272 -50.715418)
		(end 127.652272 -50.737516)
		(stroke
			(width 0.04445)
			(type default)
		)
		(layer "In2.Cu")
	)
	(gr_line
		(start 127.684022 -53.000148)
		(end 127.999998 -53.000148)
		(stroke
			(width 0.04445)
			(type default)
		)
		(layer "In2.Cu")
	)
	(gr_line
		(start 128.35001 -50.612548)
		(end 128.366012 -50.62855)
		(stroke
			(width 0.04445)
			(type default)
		)
		(layer "In2.Cu")
	)
	(gr_line
		(start 128.35001 -50.59045)
		(end 128.35001 -50.612548)
		(stroke
			(width 0.04445)
			(type default)
		)
		(layer "In2.Cu")
	)
	(gr_line
		(start 128.35001 -47.999396)
		(end 128.35001 -48.070516)
		(stroke
			(width 0.0508)
			(type default)
		)
		(layer "In2.Cu")
	)
	(gr_line
		(start 128.36779 -50.630328)
		(end 128.40716 -50.669698)
		(stroke
			(width 0.04445)
			(type default)
		)
		(layer "In2.Cu")
	)
	(gr_line
		(start 128.59766 -50.669698)
		(end 128.63703 -50.630328)
		(stroke
			(width 0.04445)
			(type default)
		)
		(layer "In2.Cu")
	)
	(gr_line
		(start 128.638808 -50.62855)
		(end 128.65481 -50.612548)
		(stroke
			(width 0.04445)
			(type default)
		)
		(layer "In2.Cu")
	)
	(gr_line
		(start 128.65481 -50.59045)
		(end 128.65481 -50.612548)
		(stroke
			(width 0.04445)
			(type default)
		)
		(layer "In2.Cu")
	)
	(gr_line
		(start 128.65735 -48.375316)
		(end 128.84531 -48.187356)
		(stroke
			(width 0.0508)
			(type default)
		)
		(layer "In2.Cu")
	)
	(gr_line
		(start 128.65735 -47.694596)
		(end 128.84531 -47.882556)
		(stroke
			(width 0.0508)
			(type default)
		)
		(layer "In2.Cu")
	)
	(gr_line
		(start 128.84531 -47.882556)
		(end 128.84531 -48.187356)
		(stroke
			(width 0.0508)
			(type default)
		)
		(layer "In2.Cu")
	)
	(gr_line
		(start 129.219452 -56.593994)
		(end 129.258822 -56.633364)
		(stroke
			(width 0.04445)
			(type default)
		)
		(layer "In2.Cu")
	)
	(gr_line
		(start 129.219452 -56.403494)
		(end 129.258822 -56.364124)
		(stroke
			(width 0.04445)
			(type default)
		)
		(layer "In2.Cu")
	)
	(gr_line
		(start 129.2606 -56.635142)
		(end 129.276602 -56.651144)
		(stroke
			(width 0.04445)
			(type default)
		)
		(layer "In2.Cu")
	)
	(gr_line
		(start 129.2606 -56.362346)
		(end 129.276602 -56.346344)
		(stroke
			(width 0.04445)
			(type default)
		)
		(layer "In2.Cu")
	)
	(gr_line
		(start 129.276602 -56.651144)
		(end 129.2987 -56.651144)
		(stroke
			(width 0.04445)
			(type default)
		)
		(layer "In2.Cu")
	)
	(gr_line
		(start 129.276602 -56.346344)
		(end 129.2987 -56.346344)
		(stroke
			(width 0.04445)
			(type default)
		)
		(layer "In2.Cu")
	)
	(gr_line
		(start 129.3495 -50.748692)
		(end 129.365502 -50.764694)
		(stroke
			(width 0.04445)
			(type default)
		)
		(layer "In2.Cu")
	)
	(gr_line
		(start 129.3495 -50.726594)
		(end 129.3495 -50.748692)
		(stroke
			(width 0.04445)
			(type default)
		)
		(layer "In2.Cu")
	)
	(gr_line
		(start 129.36728 -50.766472)
		(end 129.40665 -50.805842)
		(stroke
			(width 0.04445)
			(type default)
		)
		(layer "In2.Cu")
	)
	(gr_line
		(start 129.583434 -59.595512)
		(end 129.622804 -59.634882)
		(stroke
			(width 0.04445)
			(type default)
		)
		(layer "In2.Cu")
	)
	(gr_line
		(start 129.583434 -59.405012)
		(end 129.622804 -59.365642)
		(stroke
			(width 0.04445)
			(type default)
		)
		(layer "In2.Cu")
	)
	(gr_line
		(start 129.59715 -50.805842)
		(end 129.63652 -50.766472)
		(stroke
			(width 0.04445)
			(type default)
		)
		(layer "In2.Cu")
	)
	(gr_line
		(start 129.624582 -59.63666)
		(end 129.640584 -59.652662)
		(stroke
			(width 0.04445)
			(type default)
		)
		(layer "In2.Cu")
	)
	(gr_line
		(start 129.624582 -59.363864)
		(end 129.640584 -59.347862)
		(stroke
			(width 0.04445)
			(type default)
		)
		(layer "In2.Cu")
	)
	(gr_line
		(start 129.638298 -50.764694)
		(end 129.6543 -50.748692)
		(stroke
			(width 0.04445)
			(type default)
		)
		(layer "In2.Cu")
	)
	(gr_line
		(start 129.640584 -59.652662)
		(end 129.662682 -59.652662)
		(stroke
			(width 0.04445)
			(type default)
		)
		(layer "In2.Cu")
	)
	(gr_line
		(start 129.640584 -59.347862)
		(end 129.662682 -59.347862)
		(stroke
			(width 0.04445)
			(type default)
		)
		(layer "In2.Cu")
	)
	(gr_line
		(start 129.648458 -46.687232)
		(end 129.648458 -46.972474)
		(stroke
			(width 0.0508)
			(type default)
		)
		(layer "In2.Cu")
	)
	(gr_arc
		(start 129.648458 -46.114462)
		(mid 129.658686 -46.165882)
		(end 129.687828 -46.209458)
		(stroke
			(width 0.0508)
			(type default)
		)
		(layer "In2.Cu")
	)
	(gr_line
		(start 129.648458 -45.829474)
		(end 129.648458 -46.114462)
		(stroke
			(width 0.0508)
			(type default)
		)
		(layer "In2.Cu")
	)
	(gr_line
		(start 129.6543 -50.726594)
		(end 129.6543 -50.748692)
		(stroke
			(width 0.04445)
			(type default)
		)
		(layer "In2.Cu")
	)
	(gr_arc
		(start 129.687828 -46.592744)
		(mid 129.65874 -46.636068)
		(end 129.648458 -46.687232)
		(stroke
			(width 0.0508)
			(type default)
		)
		(layer "In2.Cu")
	)
	(gr_line
		(start 129.687828 -46.592744)
		(end 129.697226 -46.583346)
		(stroke
			(width 0.0508)
			(type default)
		)
		(layer "In2.Cu")
	)
	(gr_arc
		(start 129.687828 -46.209458)
		(mid 129.731179 -46.238425)
		(end 129.782316 -46.248574)
		(stroke
			(width 0.0508)
			(type default)
		)
		(layer "In2.Cu")
	)
	(gr_arc
		(start 129.769108 -46.553374)
		(mid 129.730179 -46.561189)
		(end 129.697226 -46.583346)
		(stroke
			(width 0.0508)
			(type default)
		)
		(layer "In2.Cu")
	)
	(gr_line
		(start 130.342132 -47.61738)
		(end 130.342132 -47.6885)
		(stroke
			(width 0.0508)
			(type default)
		)
		(layer "In2.Cu")
	)
	(gr_line
		(start 130.4544 -53.82895)
		(end 130.470402 -53.844952)
		(stroke
			(width 0.04445)
			(type default)
		)
		(layer "In2.Cu")
	)
	(gr_line
		(start 130.4544 -53.806852)
		(end 130.4544 -53.82895)
		(stroke
			(width 0.04445)
			(type default)
		)
		(layer "In2.Cu")
	)
	(gr_line
		(start 130.47218 -53.84673)
		(end 130.51155 -53.8861)
		(stroke
			(width 0.04445)
			(type default)
		)
		(layer "In2.Cu")
	)
	(gr_line
		(start 130.649472 -47.9933)
		(end 130.837432 -47.80534)
		(stroke
			(width 0.0508)
			(type default)
		)
		(layer "In2.Cu")
	)
	(gr_line
		(start 130.649472 -47.31258)
		(end 130.837432 -47.50054)
		(stroke
			(width 0.0508)
			(type default)
		)
		(layer "In2.Cu")
	)
	(gr_line
		(start 130.70205 -53.8861)
		(end 130.74142 -53.84673)
		(stroke
			(width 0.04445)
			(type default)
		)
		(layer "In2.Cu")
	)
	(gr_line
		(start 130.743198 -53.844952)
		(end 130.7592 -53.82895)
		(stroke
			(width 0.04445)
			(type default)
		)
		(layer "In2.Cu")
	)
	(gr_line
		(start 130.7592 -53.806852)
		(end 130.7592 -53.82895)
		(stroke
			(width 0.04445)
			(type default)
		)
		(layer "In2.Cu")
	)
	(gr_line
		(start 130.837432 -47.50054)
		(end 130.837432 -47.80534)
		(stroke
			(width 0.0508)
			(type default)
		)
		(layer "In2.Cu")
	)
	(gr_line
		(start 131.61264 -58.997596)
		(end 131.65201 -59.036966)
		(stroke
			(width 0.04445)
			(type default)
		)
		(layer "In2.Cu")
	)
	(gr_line
		(start 131.61264 -58.807096)
		(end 131.65201 -58.767726)
		(stroke
			(width 0.04445)
			(type default)
		)
		(layer "In2.Cu")
	)
	(gr_line
		(start 131.616704 -58.185812)
		(end 131.656074 -58.225182)
		(stroke
			(width 0.04445)
			(type default)
		)
		(layer "In2.Cu")
	)
	(gr_line
		(start 131.616704 -57.995312)
		(end 131.656074 -57.955942)
		(stroke
			(width 0.04445)
			(type default)
		)
		(layer "In2.Cu")
	)
	(gr_line
		(start 131.653788 -59.038744)
		(end 131.66979 -59.054746)
		(stroke
			(width 0.04445)
			(type default)
		)
		(layer "In2.Cu")
	)
	(gr_line
		(start 131.653788 -58.765948)
		(end 131.66979 -58.749946)
		(stroke
			(width 0.04445)
			(type default)
		)
		(layer "In2.Cu")
	)
	(gr_line
		(start 131.657852 -58.22696)
		(end 131.673854 -58.242962)
		(stroke
			(width 0.04445)
			(type default)
		)
		(layer "In2.Cu")
	)
	(gr_line
		(start 131.657852 -57.954164)
		(end 131.673854 -57.938162)
		(stroke
			(width 0.04445)
			(type default)
		)
		(layer "In2.Cu")
	)
	(gr_line
		(start 131.66979 -59.054746)
		(end 131.691888 -59.054746)
		(stroke
			(width 0.04445)
			(type default)
		)
		(layer "In2.Cu")
	)
	(gr_line
		(start 131.66979 -58.749946)
		(end 131.691888 -58.749946)
		(stroke
			(width 0.04445)
			(type default)
		)
		(layer "In2.Cu")
	)
	(gr_line
		(start 131.673854 -58.242962)
		(end 131.695952 -58.242962)
		(stroke
			(width 0.04445)
			(type default)
		)
		(layer "In2.Cu")
	)
	(gr_line
		(start 131.673854 -57.938162)
		(end 131.695952 -57.938162)
		(stroke
			(width 0.04445)
			(type default)
		)
		(layer "In2.Cu")
	)
	(gr_line
		(start 132.220208 -46.6725)
		(end 132.220208 -46.957742)
		(stroke
			(width 0.0508)
			(type default)
		)
		(layer "In2.Cu")
	)
	(gr_arc
		(start 132.220208 -46.09973)
		(mid 132.230436 -46.15115)
		(end 132.259578 -46.194726)
		(stroke
			(width 0.0508)
			(type default)
		)
		(layer "In2.Cu")
	)
	(gr_line
		(start 132.220208 -45.814742)
		(end 132.220208 -46.09973)
		(stroke
			(width 0.0508)
			(type default)
		)
		(layer "In2.Cu")
	)
	(gr_arc
		(start 132.259578 -46.578012)
		(mid 132.230469 -46.621331)
		(end 132.220208 -46.6725)
		(stroke
			(width 0.0508)
			(type default)
		)
		(layer "In2.Cu")
	)
	(gr_line
		(start 132.259578 -46.578012)
		(end 132.268976 -46.568614)
		(stroke
			(width 0.0508)
			(type default)
		)
		(layer "In2.Cu")
	)
	(gr_arc
		(start 132.259578 -46.194726)
		(mid 132.302929 -46.223693)
		(end 132.354066 -46.233842)
		(stroke
			(width 0.0508)
			(type default)
		)
		(layer "In2.Cu")
	)
	(gr_arc
		(start 132.340858 -46.538642)
		(mid 132.301923 -46.546444)
		(end 132.268976 -46.568614)
		(stroke
			(width 0.0508)
			(type default)
		)
		(layer "In2.Cu")
	)
	(gr_line
		(start 132.703062 -48.77308)
		(end 132.7531 -48.723042)
		(stroke
			(width 0.0508)
			(type default)
		)
		(layer "In2.Cu")
	)
	(gr_line
		(start 132.704586 -49.20615)
		(end 132.970778 -49.20615)
		(stroke
			(width 0.0508)
			(type default)
		)
		(layer "In2.Cu")
	)
	(gr_line
		(start 132.970778 -49.20615)
		(end 133.18617 -48.990504)
		(stroke
			(width 0.0508)
			(type default)
		)
		(layer "In2.Cu")
	)
	(gr_line
		(start 133.18617 -48.724566)
		(end 133.18617 -48.990504)
		(stroke
			(width 0.0508)
			(type default)
		)
		(layer "In2.Cu")
	)
	(gr_line
		(start 135.23087 -61.991748)
		(end 135.446516 -62.20714)
		(stroke
			(width 0.0508)
			(type default)
		)
		(layer "In2.Cu")
	)
	(gr_line
		(start 135.23087 -61.725556)
		(end 135.23087 -61.991748)
		(stroke
			(width 0.0508)
			(type default)
		)
		(layer "In2.Cu")
	)
	(gr_line
		(start 135.268716 -63.918846)
		(end 135.484362 -64.134238)
		(stroke
			(width 0.0508)
			(type default)
		)
		(layer "In2.Cu")
	)
	(gr_line
		(start 135.268716 -63.652654)
		(end 135.268716 -63.918846)
		(stroke
			(width 0.0508)
			(type default)
		)
		(layer "In2.Cu")
	)
	(gr_line
		(start 135.419592 -60.068714)
		(end 135.635238 -60.284106)
		(stroke
			(width 0.0508)
			(type default)
		)
		(layer "In2.Cu")
	)
	(gr_line
		(start 135.419592 -59.802522)
		(end 135.419592 -60.068714)
		(stroke
			(width 0.0508)
			(type default)
		)
		(layer "In2.Cu")
	)
	(gr_line
		(start 135.446516 -62.20714)
		(end 135.712454 -62.20714)
		(stroke
			(width 0.0508)
			(type default)
		)
		(layer "In2.Cu")
	)
	(gr_line
		(start 135.484362 -64.134238)
		(end 135.7503 -64.134238)
		(stroke
			(width 0.0508)
			(type default)
		)
		(layer "In2.Cu")
	)
	(gr_line
		(start 135.635238 -60.284106)
		(end 135.901176 -60.284106)
		(stroke
			(width 0.0508)
			(type default)
		)
		(layer "In2.Cu")
	)
	(gr_line
		(start 135.66394 -61.724032)
		(end 135.713978 -61.77407)
		(stroke
			(width 0.0508)
			(type default)
		)
		(layer "In2.Cu")
	)
	(gr_line
		(start 135.701786 -63.65113)
		(end 135.751824 -63.701168)
		(stroke
			(width 0.0508)
			(type default)
		)
		(layer "In2.Cu")
	)
	(gr_line
		(start 135.852662 -59.800998)
		(end 135.9027 -59.851036)
		(stroke
			(width 0.0508)
			(type default)
		)
		(layer "In2.Cu")
	)
	(gr_line
		(start 136.587484 -58.28284)
		(end 136.775444 -58.4708)
		(stroke
			(width 0.0508)
			(type default)
		)
		(layer "In2.Cu")
	)
	(gr_line
		(start 136.775444 -58.4708)
		(end 137.080244 -58.4708)
		(stroke
			(width 0.0508)
			(type default)
		)
		(layer "In2.Cu")
	)
	(gr_line
		(start 136.892284 -57.9755)
		(end 136.963404 -57.9755)
		(stroke
			(width 0.0508)
			(type default)
		)
		(layer "In2.Cu")
	)
	(gr_line
		(start 137.080244 -58.4708)
		(end 137.268204 -58.28284)
		(stroke
			(width 0.0508)
			(type default)
		)
		(layer "In2.Cu")
	)
	(gr_line
		(start 138.739118 -64.972184)
		(end 138.973814 -64.972184)
		(stroke
			(width 0.0508)
			(type default)
		)
		(layer "In2.Cu")
	)
	(gr_line
		(start 138.80465 -63.045086)
		(end 139.039346 -63.045086)
		(stroke
			(width 0.0508)
			(type default)
		)
		(layer "In2.Cu")
	)
	(gr_arc
		(start 138.973814 -64.972184)
		(mid 139.044467 -64.958287)
		(end 139.10437 -64.918336)
		(stroke
			(width 0.0508)
			(type default)
		)
		(layer "In2.Cu")
	)
	(gr_line
		(start 139.03071 -61.122052)
		(end 139.265406 -61.122052)
		(stroke
			(width 0.0508)
			(type default)
		)
		(layer "In2.Cu")
	)
	(gr_arc
		(start 139.039346 -63.045086)
		(mid 139.109993 -63.031179)
		(end 139.169902 -62.991238)
		(stroke
			(width 0.0508)
			(type default)
		)
		(layer "In2.Cu")
	)
	(gr_line
		(start 139.10437 -64.918336)
		(end 139.104624 -64.918082)
		(stroke
			(width 0.0508)
			(type default)
		)
		(layer "In2.Cu")
	)
	(gr_arc
		(start 139.104624 -64.918082)
		(mid 139.144286 -64.858363)
		(end 139.158218 -64.788034)
		(stroke
			(width 0.0508)
			(type default)
		)
		(layer "In2.Cu")
	)
	(gr_line
		(start 139.169902 -62.991238)
		(end 139.170156 -62.990984)
		(stroke
			(width 0.0508)
			(type default)
		)
		(layer "In2.Cu")
	)
	(gr_arc
		(start 139.170156 -62.990984)
		(mid 139.209812 -62.931263)
		(end 139.22375 -62.860936)
		(stroke
			(width 0.0508)
			(type default)
		)
		(layer "In2.Cu")
	)
	(gr_arc
		(start 139.265406 -61.122052)
		(mid 139.336044 -61.108129)
		(end 139.395962 -61.068204)
		(stroke
			(width 0.0508)
			(type default)
		)
		(layer "In2.Cu")
	)
	(gr_line
		(start 139.395962 -61.068204)
		(end 139.396216 -61.06795)
		(stroke
			(width 0.0508)
			(type default)
		)
		(layer "In2.Cu")
	)
	(gr_arc
		(start 139.396216 -61.06795)
		(mid 139.435902 -61.008235)
		(end 139.44981 -60.937902)
		(stroke
			(width 0.0508)
			(type default)
		)
		(layer "In2.Cu")
	)
	(gr_line
		(start 139.446 -58.9026)
		(end 139.680696 -58.9026)
		(stroke
			(width 0.0508)
			(type default)
		)
		(layer "In2.Cu")
	)
	(gr_arc
		(start 139.463018 -64.80429)
		(mid 139.475833 -64.868623)
		(end 139.512294 -64.923162)
		(stroke
			(width 0.0508)
			(type default)
		)
		(layer "In2.Cu")
	)
	(gr_arc
		(start 139.512294 -64.923162)
		(mid 139.5666 -64.959448)
		(end 139.630658 -64.972184)
		(stroke
			(width 0.0508)
			(type default)
		)
		(layer "In2.Cu")
	)
	(gr_arc
		(start 139.52855 -62.877192)
		(mid 139.541365 -62.941525)
		(end 139.577826 -62.996064)
		(stroke
			(width 0.0508)
			(type default)
		)
		(layer "In2.Cu")
	)
	(gr_arc
		(start 139.577826 -62.996064)
		(mid 139.632132 -63.03235)
		(end 139.69619 -63.045086)
		(stroke
			(width 0.0508)
			(type default)
		)
		(layer "In2.Cu")
	)
	(gr_line
		(start 139.630658 -64.972184)
		(end 139.882118 -64.972184)
		(stroke
			(width 0.0508)
			(type default)
		)
		(layer "In2.Cu")
	)
	(gr_arc
		(start 139.680696 -58.9026)
		(mid 139.751333 -58.888677)
		(end 139.811252 -58.848752)
		(stroke
			(width 0.0508)
			(type default)
		)
		(layer "In2.Cu")
	)
	(gr_line
		(start 139.69619 -63.045086)
		(end 139.94765 -63.045086)
		(stroke
			(width 0.0508)
			(type default)
		)
		(layer "In2.Cu")
	)
	(gr_arc
		(start 139.75461 -60.954158)
		(mid 139.767425 -61.018491)
		(end 139.803886 -61.07303)
		(stroke
			(width 0.0508)
			(type default)
		)
		(layer "In2.Cu")
	)
	(gr_arc
		(start 139.803886 -61.07303)
		(mid 139.858192 -61.109316)
		(end 139.92225 -61.122052)
		(stroke
			(width 0.0508)
			(type default)
		)
		(layer "In2.Cu")
	)
	(gr_line
		(start 139.811252 -58.848752)
		(end 139.811506 -58.848498)
		(stroke
			(width 0.0508)
			(type default)
		)
		(layer "In2.Cu")
	)
	(gr_arc
		(start 139.811506 -58.848498)
		(mid 139.851177 -58.788781)
		(end 139.8651 -58.71845)
		(stroke
			(width 0.0508)
			(type default)
		)
		(layer "In2.Cu")
	)
	(gr_line
		(start 139.92225 -61.122052)
		(end 140.17371 -61.122052)
		(stroke
			(width 0.0508)
			(type default)
		)
		(layer "In2.Cu")
	)
	(gr_arc
		(start 140.1699 -58.734706)
		(mid 140.182715 -58.799039)
		(end 140.219176 -58.853578)
		(stroke
			(width 0.0508)
			(type default)
		)
		(layer "In2.Cu")
	)
	(gr_arc
		(start 140.219176 -58.853578)
		(mid 140.273482 -58.889864)
		(end 140.33754 -58.9026)
		(stroke
			(width 0.0508)
			(type default)
		)
		(layer "In2.Cu")
	)
	(gr_line
		(start 140.33754 -58.9026)
		(end 140.589 -58.9026)
		(stroke
			(width 0.0508)
			(type default)
		)
		(layer "In2.Cu")
	)
	(gr_line
		(start 146.286728 -33.472882)
		(end 146.34591 -33.193736)
		(stroke
			(width 0.0508)
			(type default)
		)
		(layer "In2.Cu")
	)
	(gr_arc
		(start 146.404076 -33.109662)
		(mid 146.366663 -33.14594)
		(end 146.34591 -33.193736)
		(stroke
			(width 0.0508)
			(type default)
		)
		(layer "In2.Cu")
	)
	(gr_line
		(start 146.404076 -33.109662)
		(end 146.415252 -33.102296)
		(stroke
			(width 0.0508)
			(type default)
		)
		(layer "In2.Cu")
	)
	(gr_arc
		(start 146.46529 -32.633666)
		(mid 146.464644 -32.68608)
		(end 146.484086 -32.734758)
		(stroke
			(width 0.0508)
			(type default)
		)
		(layer "In2.Cu")
	)
	(gr_line
		(start 146.46529 -32.633666)
		(end 146.524472 -32.354774)
		(stroke
			(width 0.0508)
			(type default)
		)
		(layer "In2.Cu")
	)
	(gr_arc
		(start 146.484086 -32.734758)
		(mid 146.520341 -32.772111)
		(end 146.56816 -32.79267)
		(stroke
			(width 0.0508)
			(type default)
		)
		(layer "In2.Cu")
	)
	(gr_arc
		(start 146.49196 -33.088072)
		(mid 146.452195 -33.087564)
		(end 146.415252 -33.102296)
		(stroke
			(width 0.0508)
			(type default)
		)
		(layer "In2.Cu")
	)
	(gr_line
		(start 146.502374 -33.090358)
		(end 146.561556 -33.102804)
		(stroke
			(width 0.0508)
			(type default)
		)
		(layer "In2.Cu")
	)
	(gr_line
		(start 146.56816 -32.79267)
		(end 146.624802 -32.804608)
		(stroke
			(width 0.0508)
			(type default)
		)
		(layer "In2.Cu")
	)
	(gr_line
		(start 147.307046 -47.564294)
		(end 147.366228 -47.285148)
		(stroke
			(width 0.0508)
			(type default)
		)
		(layer "In2.Cu")
	)
	(gr_arc
		(start 147.424394 -47.201074)
		(mid 147.387005 -47.237364)
		(end 147.366228 -47.285148)
		(stroke
			(width 0.0508)
			(type default)
		)
		(layer "In2.Cu")
	)
	(gr_line
		(start 147.424394 -47.201074)
		(end 147.43557 -47.193708)
		(stroke
			(width 0.0508)
			(type default)
		)
		(layer "In2.Cu")
	)
	(gr_arc
		(start 147.485608 -46.725078)
		(mid 147.48492 -46.777504)
		(end 147.504404 -46.82617)
		(stroke
			(width 0.0508)
			(type default)
		)
		(layer "In2.Cu")
	)
	(gr_line
		(start 147.485608 -46.725078)
		(end 147.54479 -46.446186)
		(stroke
			(width 0.0508)
			(type default)
		)
		(layer "In2.Cu")
	)
	(gr_arc
		(start 147.512278 -47.179484)
		(mid 147.47251 -47.178969)
		(end 147.43557 -47.193708)
		(stroke
			(width 0.0508)
			(type default)
		)
		(layer "In2.Cu")
	)
	(gr_arc
		(start 147.512278 -47.179484)
		(mid 147.518618 -47.180928)
		(end 147.524978 -47.182278)
		(stroke
			(width 0.0508)
			(type default)
		)
		(layer "In2.Cu")
	)
	(gr_line
		(start 148.354796 -51.53279)
		(end 148.413978 -51.253644)
		(stroke
			(width 0.0508)
			(type default)
		)
		(layer "In2.Cu")
	)
	(gr_arc
		(start 148.472144 -51.16957)
		(mid 148.434741 -51.205853)
		(end 148.413978 -51.253644)
		(stroke
			(width 0.0508)
			(type default)
		)
		(layer "In2.Cu")
	)
	(gr_line
		(start 148.472144 -51.16957)
		(end 148.48332 -51.162204)
		(stroke
			(width 0.0508)
			(type default)
		)
		(layer "In2.Cu")
	)
	(gr_arc
		(start 148.533358 -50.693574)
		(mid 148.532715 -50.745988)
		(end 148.552154 -50.794666)
		(stroke
			(width 0.0508)
			(type default)
		)
		(layer "In2.Cu")
	)
	(gr_line
		(start 148.533358 -50.693574)
		(end 148.59254 -50.414682)
		(stroke
			(width 0.0508)
			(type default)
		)
		(layer "In2.Cu")
	)
	(gr_arc
		(start 148.552154 -50.794666)
		(mid 148.58703 -50.83103)
		(end 148.632926 -50.851816)
		(stroke
			(width 0.0508)
			(type default)
		)
		(layer "In2.Cu")
	)
	(gr_arc
		(start 148.560028 -51.14798)
		(mid 148.520253 -51.147447)
		(end 148.48332 -51.162204)
		(stroke
			(width 0.0508)
			(type default)
		)
		(layer "In2.Cu")
	)
	(gr_line
		(start 148.62683 -41.353486)
		(end 148.686012 -41.07434)
		(stroke
			(width 0.0508)
			(type default)
		)
		(layer "In2.Cu")
	)
	(gr_arc
		(start 148.744178 -40.990266)
		(mid 148.706766 -41.026545)
		(end 148.686012 -41.07434)
		(stroke
			(width 0.0508)
			(type default)
		)
		(layer "In2.Cu")
	)
	(gr_line
		(start 148.744178 -40.990266)
		(end 148.755354 -40.9829)
		(stroke
			(width 0.0508)
			(type default)
		)
		(layer "In2.Cu")
	)
	(gr_line
		(start 148.783548 -51.195478)
		(end 148.79701 -51.198272)
		(stroke
			(width 0.0508)
			(type default)
		)
		(layer "In2.Cu")
	)
	(gr_line
		(start 148.79701 -51.198272)
		(end 148.810472 -51.196494)
		(stroke
			(width 0.0508)
			(type default)
		)
		(layer "In2.Cu")
	)
	(gr_arc
		(start 148.805392 -40.51427)
		(mid 148.804747 -40.566684)
		(end 148.824188 -40.615362)
		(stroke
			(width 0.0508)
			(type default)
		)
		(layer "In2.Cu")
	)
	(gr_line
		(start 148.805392 -40.51427)
		(end 148.864574 -40.235378)
		(stroke
			(width 0.0508)
			(type default)
		)
		(layer "In2.Cu")
	)
	(gr_arc
		(start 148.832062 -40.968676)
		(mid 148.792296 -40.968167)
		(end 148.755354 -40.9829)
		(stroke
			(width 0.0508)
			(type default)
		)
		(layer "In2.Cu")
	)
	(gr_arc
		(start 148.832062 -40.968676)
		(mid 148.838402 -40.97012)
		(end 148.844762 -40.97147)
		(stroke
			(width 0.0508)
			(type default)
		)
		(layer "In2.Cu")
	)
	(gr_line
		(start 149.132036 -36.225988)
		(end 149.191218 -35.946842)
		(stroke
			(width 0.0508)
			(type default)
		)
		(layer "In2.Cu")
	)
	(gr_arc
		(start 149.249384 -35.862768)
		(mid 149.21193 -35.899022)
		(end 149.191218 -35.946842)
		(stroke
			(width 0.0508)
			(type default)
		)
		(layer "In2.Cu")
	)
	(gr_line
		(start 149.249384 -35.862768)
		(end 149.26056 -35.855402)
		(stroke
			(width 0.0508)
			(type default)
		)
		(layer "In2.Cu")
	)
	(gr_line
		(start 149.252686 -47.549816)
		(end 149.281388 -47.555912)
		(stroke
			(width 0.0508)
			(type default)
		)
		(layer "In2.Cu")
	)
	(gr_line
		(start 149.26056 -35.855402)
		(end 149.329648 -35.841686)
		(stroke
			(width 0.0508)
			(type default)
		)
		(layer "In2.Cu")
	)
	(gr_line
		(start 149.281388 -47.555912)
		(end 149.309582 -47.549308)
		(stroke
			(width 0.0508)
			(type default)
		)
		(layer "In2.Cu")
	)
	(gr_line
		(start 149.295358 -33.683956)
		(end 149.321012 -33.68929)
		(stroke
			(width 0.0508)
			(type default)
		)
		(layer "In2.Cu")
	)
	(gr_arc
		(start 149.310598 -35.386772)
		(mid 149.309954 -35.439185)
		(end 149.329394 -35.487864)
		(stroke
			(width 0.0508)
			(type default)
		)
		(layer "In2.Cu")
	)
	(gr_line
		(start 149.310598 -35.386772)
		(end 149.36978 -35.10788)
		(stroke
			(width 0.0508)
			(type default)
		)
		(layer "In2.Cu")
	)
	(gr_line
		(start 149.321012 -33.68929)
		(end 149.346158 -33.683956)
		(stroke
			(width 0.0508)
			(type default)
		)
		(layer "In2.Cu")
	)
	(gr_line
		(start 149.402546 -55.501286)
		(end 149.461728 -55.22214)
		(stroke
			(width 0.0508)
			(type default)
		)
		(layer "In2.Cu")
	)
	(gr_arc
		(start 149.519894 -55.138066)
		(mid 149.48244 -55.17432)
		(end 149.461728 -55.22214)
		(stroke
			(width 0.0508)
			(type default)
		)
		(layer "In2.Cu")
	)
	(gr_line
		(start 149.519894 -55.138066)
		(end 149.53107 -55.1307)
		(stroke
			(width 0.0508)
			(type default)
		)
		(layer "In2.Cu")
	)
	(gr_line
		(start 149.54758 -45.321982)
		(end 149.606762 -45.042836)
		(stroke
			(width 0.0508)
			(type default)
		)
		(layer "In2.Cu")
	)
	(gr_arc
		(start 149.581108 -54.66207)
		(mid 149.580463 -54.714484)
		(end 149.599904 -54.763162)
		(stroke
			(width 0.0508)
			(type default)
		)
		(layer "In2.Cu")
	)
	(gr_line
		(start 149.581108 -54.66207)
		(end 149.64029 -54.383178)
		(stroke
			(width 0.0508)
			(type default)
		)
		(layer "In2.Cu")
	)
	(gr_arc
		(start 149.599904 -54.763162)
		(mid 149.634318 -54.798977)
		(end 149.679406 -54.819804)
		(stroke
			(width 0.0508)
			(type default)
		)
		(layer "In2.Cu")
	)
	(gr_arc
		(start 149.607778 -55.116476)
		(mid 149.567992 -55.1159)
		(end 149.53107 -55.1307)
		(stroke
			(width 0.0508)
			(type default)
		)
		(layer "In2.Cu")
	)
	(gr_arc
		(start 149.664928 -44.958762)
		(mid 149.627474 -44.995016)
		(end 149.606762 -45.042836)
		(stroke
			(width 0.0508)
			(type default)
		)
		(layer "In2.Cu")
	)
	(gr_line
		(start 149.664928 -44.958762)
		(end 149.676104 -44.951396)
		(stroke
			(width 0.0508)
			(type default)
		)
		(layer "In2.Cu")
	)
	(gr_arc
		(start 149.726142 -44.482766)
		(mid 149.725496 -44.535181)
		(end 149.744938 -44.583858)
		(stroke
			(width 0.0508)
			(type default)
		)
		(layer "In2.Cu")
	)
	(gr_line
		(start 149.726142 -44.482766)
		(end 149.785324 -44.203874)
		(stroke
			(width 0.0508)
			(type default)
		)
		(layer "In2.Cu")
	)
	(gr_arc
		(start 149.752812 -44.937172)
		(mid 149.713026 -44.936596)
		(end 149.676104 -44.951396)
		(stroke
			(width 0.0508)
			(type default)
		)
		(layer "In2.Cu")
	)
	(gr_line
		(start 150.142956 -55.230014)
		(end 150.206456 -55.243476)
		(stroke
			(width 0.0508)
			(type default)
		)
		(layer "In2.Cu")
	)
	(gr_line
		(start 150.206456 -55.243476)
		(end 150.264876 -55.215282)
		(stroke
			(width 0.0508)
			(type default)
		)
		(layer "In2.Cu")
	)
	(gr_line
		(start 150.42007 -36.04006)
		(end 150.442422 -36.044124)
		(stroke
			(width 0.0508)
			(type default)
		)
		(layer "In2.Cu")
	)
	(gr_line
		(start 150.442422 -36.044124)
		(end 150.463504 -36.039552)
		(stroke
			(width 0.0508)
			(type default)
		)
		(layer "In2.Cu")
	)
	(gr_line
		(start 150.470362 -41.316402)
		(end 150.50643 -41.324022)
		(stroke
			(width 0.0508)
			(type default)
		)
		(layer "In2.Cu")
	)
	(gr_line
		(start 150.50643 -41.324022)
		(end 150.541482 -41.313862)
		(stroke
			(width 0.0508)
			(type default)
		)
		(layer "In2.Cu")
	)
	(gr_line
		(start 150.636224 -45.125132)
		(end 150.683976 -45.135292)
		(stroke
			(width 0.0508)
			(type default)
		)
		(layer "In2.Cu")
	)
	(gr_line
		(start 150.671784 -50.9524)
		(end 150.772368 -50.939192)
		(stroke
			(width 0.0508)
			(type default)
		)
		(layer "In2.Cu")
	)
	(gr_line
		(start 150.683976 -45.135038)
		(end 150.683976 -45.135292)
		(stroke
			(width 0.0508)
			(type default)
		)
		(layer "In2.Cu")
	)
	(gr_line
		(start 150.683976 -45.135038)
		(end 150.727664 -45.119036)
		(stroke
			(width 0.0508)
			(type default)
		)
		(layer "In2.Cu")
	)
	(gr_line
		(start 150.772368 -50.939192)
		(end 150.827486 -50.854356)
		(stroke
			(width 0.0508)
			(type default)
		)
		(layer "In2.Cu")
	)
	(gr_line
		(start 150.876762 -47.178722)
		(end 150.890224 -47.17542)
		(stroke
			(width 0.0508)
			(type default)
		)
		(layer "In2.Cu")
	)
	(gr_line
		(start 150.890224 -47.17542)
		(end 150.901654 -47.168054)
		(stroke
			(width 0.0508)
			(type default)
		)
		(layer "In2.Cu")
	)
	(gr_line
		(start 150.994364 -39.111174)
		(end 151.053546 -38.832028)
		(stroke
			(width 0.0508)
			(type default)
		)
		(layer "In2.Cu")
	)
	(gr_arc
		(start 151.111712 -38.747954)
		(mid 151.074258 -38.784208)
		(end 151.053546 -38.832028)
		(stroke
			(width 0.0508)
			(type default)
		)
		(layer "In2.Cu")
	)
	(gr_line
		(start 151.111712 -38.747954)
		(end 151.122888 -38.740588)
		(stroke
			(width 0.0508)
			(type default)
		)
		(layer "In2.Cu")
	)
	(gr_line
		(start 151.114252 -32.996632)
		(end 151.70785 -32.870394)
		(stroke
			(width 0.0508)
			(type default)
		)
		(layer "In2.Cu")
	)
	(gr_line
		(start 151.141684 -33.304734)
		(end 151.364696 -33.449768)
		(stroke
			(width 0.0508)
			(type default)
		)
		(layer "In2.Cu")
	)
	(gr_arc
		(start 151.172926 -38.271958)
		(mid 151.172276 -38.324373)
		(end 151.191722 -38.37305)
		(stroke
			(width 0.0508)
			(type default)
		)
		(layer "In2.Cu")
	)
	(gr_line
		(start 151.172926 -38.271958)
		(end 151.232108 -37.993066)
		(stroke
			(width 0.0508)
			(type default)
		)
		(layer "In2.Cu")
	)
	(gr_arc
		(start 151.199596 -38.726364)
		(mid 151.15981 -38.725788)
		(end 151.122888 -38.740588)
		(stroke
			(width 0.0508)
			(type default)
		)
		(layer "In2.Cu")
	)
	(gr_line
		(start 151.364696 -33.449768)
		(end 151.662638 -33.386268)
		(stroke
			(width 0.0508)
			(type default)
		)
		(layer "In2.Cu")
	)
	(gr_line
		(start 151.510746 -49.802796)
		(end 151.520398 -49.78781)
		(stroke
			(width 0.0508)
			(type default)
		)
		(layer "In2.Cu")
	)
	(gr_line
		(start 151.520398 -49.78781)
		(end 151.524208 -49.770284)
		(stroke
			(width 0.0508)
			(type default)
		)
		(layer "In2.Cu")
	)
	(gr_line
		(start 151.538432 -54.603904)
		(end 151.580088 -54.583838)
		(stroke
			(width 0.0508)
			(type default)
		)
		(layer "In2.Cu")
	)
	(gr_line
		(start 151.566372 -48.103536)
		(end 151.570182 -48.08601)
		(stroke
			(width 0.0508)
			(type default)
		)
		(layer "In2.Cu")
	)
	(gr_line
		(start 151.570182 -48.08601)
		(end 151.579834 -48.071024)
		(stroke
			(width 0.0508)
			(type default)
		)
		(layer "In2.Cu")
	)
	(gr_line
		(start 151.580088 -54.583838)
		(end 151.604726 -54.545484)
		(stroke
			(width 0.0508)
			(type default)
		)
		(layer "In2.Cu")
	)
	(gr_line
		(start 151.657558 -40.997124)
		(end 151.6634 -40.9956)
		(stroke
			(width 0.0508)
			(type default)
		)
		(layer "In2.Cu")
	)
	(gr_line
		(start 151.662638 -33.386268)
		(end 151.807672 -33.163256)
		(stroke
			(width 0.0508)
			(type default)
		)
		(layer "In2.Cu")
	)
	(gr_line
		(start 151.6634 -40.9956)
		(end 151.668226 -40.992298)
		(stroke
			(width 0.0508)
			(type default)
		)
		(layer "In2.Cu")
	)
	(gr_line
		(start 151.688292 -46.657514)
		(end 151.710644 -46.643036)
		(stroke
			(width 0.0508)
			(type default)
		)
		(layer "In2.Cu")
	)
	(gr_line
		(start 151.710644 -46.643036)
		(end 151.725122 -46.620684)
		(stroke
			(width 0.0508)
			(type default)
		)
		(layer "In2.Cu")
	)
	(gr_line
		(start 151.882602 -44.61129)
		(end 151.904954 -44.596812)
		(stroke
			(width 0.0508)
			(type default)
		)
		(layer "In2.Cu")
	)
	(gr_line
		(start 151.904954 -44.596812)
		(end 151.919432 -44.57446)
		(stroke
			(width 0.0508)
			(type default)
		)
		(layer "In2.Cu")
	)
	(gr_line
		(start 152.048464 -40.379142)
		(end 152.103836 -40.119046)
		(stroke
			(width 0.0508)
			(type default)
		)
		(layer "In2.Cu")
	)
	(gr_line
		(start 152.083262 -32.790638)
		(end 152.67686 -32.6644)
		(stroke
			(width 0.0508)
			(type default)
		)
		(layer "In2.Cu")
	)
	(gr_line
		(start 152.100026 -38.91788)
		(end 152.130252 -38.92423)
		(stroke
			(width 0.0508)
			(type default)
		)
		(layer "In2.Cu")
	)
	(gr_line
		(start 152.103836 -40.119046)
		(end 152.359614 -39.953184)
		(stroke
			(width 0.0508)
			(type default)
		)
		(layer "In2.Cu")
	)
	(gr_line
		(start 152.110694 -33.098994)
		(end 152.333452 -33.243774)
		(stroke
			(width 0.0508)
			(type default)
		)
		(layer "In2.Cu")
	)
	(gr_line
		(start 152.130252 -38.92423)
		(end 152.159462 -38.917118)
		(stroke
			(width 0.0508)
			(type default)
		)
		(layer "In2.Cu")
	)
	(gr_line
		(start 152.24633 -40.61714)
		(end 152.757124 -40.28567)
		(stroke
			(width 0.0508)
			(type default)
		)
		(layer "In2.Cu")
	)
	(gr_line
		(start 152.271222 -52.308252)
		(end 152.334722 -52.010056)
		(stroke
			(width 0.0508)
			(type default)
		)
		(layer "In2.Cu")
	)
	(gr_line
		(start 152.271222 -52.308252)
		(end 152.416256 -52.531264)
		(stroke
			(width 0.0508)
			(type default)
		)
		(layer "In2.Cu")
	)
	(gr_line
		(start 152.333452 -33.243774)
		(end 152.631648 -33.180274)
		(stroke
			(width 0.0508)
			(type default)
		)
		(layer "In2.Cu")
	)
	(gr_line
		(start 152.334722 -52.010056)
		(end 152.557734 -51.865276)
		(stroke
			(width 0.0508)
			(type default)
		)
		(layer "In2.Cu")
	)
	(gr_line
		(start 152.359614 -39.953184)
		(end 152.61971 -40.008302)
		(stroke
			(width 0.0508)
			(type default)
		)
		(layer "In2.Cu")
	)
	(gr_line
		(start 152.630886 -52.966874)
		(end 152.641046 -52.951126)
		(stroke
			(width 0.0508)
			(type default)
		)
		(layer "In2.Cu")
	)
	(gr_line
		(start 152.631648 -33.180274)
		(end 152.776682 -32.957262)
		(stroke
			(width 0.0508)
			(type default)
		)
		(layer "In2.Cu")
	)
	(gr_line
		(start 152.641046 -52.951126)
		(end 152.644602 -52.9336)
		(stroke
			(width 0.0508)
			(type default)
		)
		(layer "In2.Cu")
	)
	(gr_line
		(start 152.724358 -52.560474)
		(end 152.851358 -51.96332)
		(stroke
			(width 0.0508)
			(type default)
		)
		(layer "In2.Cu")
	)
	(gr_line
		(start 153.008584 -38.71214)
		(end 153.022808 -38.708584)
		(stroke
			(width 0.0508)
			(type default)
		)
		(layer "In2.Cu")
	)
	(gr_line
		(start 153.022808 -38.708584)
		(end 153.034746 -38.70071)
		(stroke
			(width 0.0508)
			(type default)
		)
		(layer "In2.Cu")
	)
	(gr_line
		(start 153.052272 -32.584644)
		(end 153.64587 -32.458406)
		(stroke
			(width 0.0508)
			(type default)
		)
		(layer "In2.Cu")
	)
	(gr_line
		(start 153.079704 -32.893)
		(end 153.302462 -33.03778)
		(stroke
			(width 0.0508)
			(type default)
		)
		(layer "In2.Cu")
	)
	(gr_line
		(start 153.196544 -35.458908)
		(end 153.21407 -35.455098)
		(stroke
			(width 0.0508)
			(type default)
		)
		(layer "In2.Cu")
	)
	(gr_line
		(start 153.21407 -35.455098)
		(end 153.229056 -35.445446)
		(stroke
			(width 0.0508)
			(type default)
		)
		(layer "In2.Cu")
	)
	(gr_line
		(start 153.302462 -33.03778)
		(end 153.600658 -32.97428)
		(stroke
			(width 0.0508)
			(type default)
		)
		(layer "In2.Cu")
	)
	(gr_line
		(start 153.488644 -47.500794)
		(end 153.492454 -47.483268)
		(stroke
			(width 0.0508)
			(type default)
		)
		(layer "In2.Cu")
	)
	(gr_line
		(start 153.492454 -47.483268)
		(end 153.502106 -47.468282)
		(stroke
			(width 0.0508)
			(type default)
		)
		(layer "In2.Cu")
	)
	(gr_line
		(start 153.530808 -38.378892)
		(end 153.55316 -38.364414)
		(stroke
			(width 0.0508)
			(type default)
		)
		(layer "In2.Cu")
	)
	(gr_line
		(start 153.55316 -38.364414)
		(end 153.566876 -38.342824)
		(stroke
			(width 0.0508)
			(type default)
		)
		(layer "In2.Cu")
	)
	(gr_line
		(start 153.600658 -32.97428)
		(end 153.745692 -32.751268)
		(stroke
			(width 0.0508)
			(type default)
		)
		(layer "In2.Cu")
	)
	(gr_line
		(start 153.984198 -39.489126)
		(end 154.00655 -39.474648)
		(stroke
			(width 0.0508)
			(type default)
		)
		(layer "In2.Cu")
	)
	(gr_line
		(start 154.00655 -39.474648)
		(end 154.021282 -39.452042)
		(stroke
			(width 0.0508)
			(type default)
		)
		(layer "In2.Cu")
	)
	(gr_line
		(start 154.526234 -36.305998)
		(end 154.540712 -36.283646)
		(stroke
			(width 0.0508)
			(type default)
		)
		(layer "In2.Cu")
	)
	(gr_line
		(start 154.540712 -36.283646)
		(end 154.563318 -36.268914)
		(stroke
			(width 0.0508)
			(type default)
		)
		(layer "In2.Cu")
	)
	(gr_line
		(start 154.801316 -43.110912)
		(end 155.133548 -42.599356)
		(stroke
			(width 0.0508)
			(type default)
		)
		(layer "In2.Cu")
	)
	(gr_line
		(start 154.883104 -36.061142)
		(end 155.394406 -35.729164)
		(stroke
			(width 0.0508)
			(type default)
		)
		(layer "In2.Cu")
	)
	(gr_line
		(start 155.02001 -36.338764)
		(end 155.28036 -36.394136)
		(stroke
			(width 0.0508)
			(type default)
		)
		(layer "In2.Cu")
	)
	(gr_line
		(start 155.040076 -43.307762)
		(end 155.300172 -43.252644)
		(stroke
			(width 0.0508)
			(type default)
		)
		(layer "In2.Cu")
	)
	(gr_line
		(start 155.090114 -37.24656)
		(end 155.10383 -37.22497)
		(stroke
			(width 0.0508)
			(type default)
		)
		(layer "In2.Cu")
	)
	(gr_line
		(start 155.10383 -37.22497)
		(end 155.126436 -37.210238)
		(stroke
			(width 0.0508)
			(type default)
		)
		(layer "In2.Cu")
	)
	(gr_line
		(start 155.28036 -36.394136)
		(end 155.535884 -36.22802)
		(stroke
			(width 0.0508)
			(type default)
		)
		(layer "In2.Cu")
	)
	(gr_line
		(start 155.300172 -43.252644)
		(end 155.466288 -42.996866)
		(stroke
			(width 0.0508)
			(type default)
		)
		(layer "In2.Cu")
	)
	(gr_line
		(start 155.340558 -42.280586)
		(end 155.673552 -41.768014)
		(stroke
			(width 0.0508)
			(type default)
		)
		(layer "In2.Cu")
	)
	(gr_line
		(start 155.410916 -42.73677)
		(end 155.466288 -42.996866)
		(stroke
			(width 0.0508)
			(type default)
		)
		(layer "In2.Cu")
	)
	(gr_line
		(start 155.535884 -36.22802)
		(end 155.591256 -35.96767)
		(stroke
			(width 0.0508)
			(type default)
		)
		(layer "In2.Cu")
	)
	(gr_line
		(start 155.579572 -42.477182)
		(end 155.839668 -42.42181)
		(stroke
			(width 0.0508)
			(type default)
		)
		(layer "In2.Cu")
	)
	(gr_line
		(start 155.71343 -35.5219)
		(end 156.225748 -35.189414)
		(stroke
			(width 0.0508)
			(type default)
		)
		(layer "In2.Cu")
	)
	(gr_line
		(start 155.750514 -32.32277)
		(end 155.76804 -32.31896)
		(stroke
			(width 0.0508)
			(type default)
		)
		(layer "In2.Cu")
	)
	(gr_line
		(start 155.76804 -32.31896)
		(end 155.783026 -32.309308)
		(stroke
			(width 0.0508)
			(type default)
		)
		(layer "In2.Cu")
	)
	(gr_line
		(start 155.839668 -42.42181)
		(end 156.005784 -42.166286)
		(stroke
			(width 0.0508)
			(type default)
		)
		(layer "In2.Cu")
	)
	(gr_line
		(start 155.850844 -35.799268)
		(end 156.111194 -35.85464)
		(stroke
			(width 0.0508)
			(type default)
		)
		(layer "In2.Cu")
	)
	(gr_line
		(start 155.881324 -41.448482)
		(end 156.212794 -40.937942)
		(stroke
			(width 0.0508)
			(type default)
		)
		(layer "In2.Cu")
	)
	(gr_line
		(start 155.950666 -41.905936)
		(end 156.005784 -42.166286)
		(stroke
			(width 0.0508)
			(type default)
		)
		(layer "In2.Cu")
	)
	(gr_line
		(start 155.985464 -37.751004)
		(end 155.999942 -37.728652)
		(stroke
			(width 0.0508)
			(type default)
		)
		(layer "In2.Cu")
	)
	(gr_line
		(start 155.999942 -37.728652)
		(end 156.022548 -37.71392)
		(stroke
			(width 0.0508)
			(type default)
		)
		(layer "In2.Cu")
	)
	(gr_line
		(start 156.111194 -35.85464)
		(end 156.366718 -35.688524)
		(stroke
			(width 0.0508)
			(type default)
		)
		(layer "In2.Cu")
	)
	(gr_line
		(start 156.119068 -41.646348)
		(end 156.379418 -41.590976)
		(stroke
			(width 0.0508)
			(type default)
		)
		(layer "In2.Cu")
	)
	(gr_line
		(start 156.328872 -38.970204)
		(end 156.342588 -38.948614)
		(stroke
			(width 0.0508)
			(type default)
		)
		(layer "In2.Cu")
	)
	(gr_line
		(start 156.342588 -38.948614)
		(end 156.365194 -38.933882)
		(stroke
			(width 0.0508)
			(type default)
		)
		(layer "In2.Cu")
	)
	(gr_line
		(start 156.34335 -37.50564)
		(end 156.853636 -37.17417)
		(stroke
			(width 0.0508)
			(type default)
		)
		(layer "In2.Cu")
	)
	(gr_line
		(start 156.366718 -35.688524)
		(end 156.42209 -35.428428)
		(stroke
			(width 0.0508)
			(type default)
		)
		(layer "In2.Cu")
	)
	(gr_line
		(start 156.379418 -41.590976)
		(end 156.54528 -41.335452)
		(stroke
			(width 0.0508)
			(type default)
		)
		(layer "In2.Cu")
	)
	(gr_line
		(start 156.430472 -40.602662)
		(end 156.445204 -40.580056)
		(stroke
			(width 0.0508)
			(type default)
		)
		(layer "In2.Cu")
	)
	(gr_line
		(start 156.445204 -40.580056)
		(end 156.466794 -40.56634)
		(stroke
			(width 0.0508)
			(type default)
		)
		(layer "In2.Cu")
	)
	(gr_line
		(start 156.47924 -37.78377)
		(end 156.73959 -37.839142)
		(stroke
			(width 0.0508)
			(type default)
		)
		(layer "In2.Cu")
	)
	(gr_line
		(start 156.490162 -41.075102)
		(end 156.54528 -41.335452)
		(stroke
			(width 0.0508)
			(type default)
		)
		(layer "In2.Cu")
	)
	(gr_line
		(start 156.543756 -34.982658)
		(end 157.057344 -34.649156)
		(stroke
			(width 0.0508)
			(type default)
		)
		(layer "In2.Cu")
	)
	(gr_line
		(start 156.681678 -35.259772)
		(end 156.942028 -35.315144)
		(stroke
			(width 0.0508)
			(type default)
		)
		(layer "In2.Cu")
	)
	(gr_line
		(start 156.73959 -37.839142)
		(end 156.995114 -37.673026)
		(stroke
			(width 0.0508)
			(type default)
		)
		(layer "In2.Cu")
	)
	(gr_line
		(start 156.942028 -35.315144)
		(end 157.197552 -35.149028)
		(stroke
			(width 0.0508)
			(type default)
		)
		(layer "In2.Cu")
	)
	(gr_line
		(start 156.995114 -37.673026)
		(end 157.050486 -37.412676)
		(stroke
			(width 0.0508)
			(type default)
		)
		(layer "In2.Cu")
	)
	(gr_line
		(start 157.173168 -36.966652)
		(end 157.68447 -36.634674)
		(stroke
			(width 0.0508)
			(type default)
		)
		(layer "In2.Cu")
	)
	(gr_line
		(start 157.197552 -35.149028)
		(end 157.252924 -34.888932)
		(stroke
			(width 0.0508)
			(type default)
		)
		(layer "In2.Cu")
	)
	(gr_line
		(start 157.310074 -37.244274)
		(end 157.570424 -37.299646)
		(stroke
			(width 0.0508)
			(type default)
		)
		(layer "In2.Cu")
	)
	(gr_line
		(start 157.385258 -41.48582)
		(end 157.399736 -41.463468)
		(stroke
			(width 0.0508)
			(type default)
		)
		(layer "In2.Cu")
	)
	(gr_line
		(start 157.399736 -41.463468)
		(end 157.422088 -41.44899)
		(stroke
			(width 0.0508)
			(type default)
		)
		(layer "In2.Cu")
	)
	(gr_line
		(start 157.570424 -37.299646)
		(end 157.825948 -37.133784)
		(stroke
			(width 0.0508)
			(type default)
		)
		(layer "In2.Cu")
	)
	(gr_line
		(start 157.825948 -37.133784)
		(end 157.88132 -36.87318)
		(stroke
			(width 0.0508)
			(type default)
		)
		(layer "In2.Cu")
	)
	(gr_line
		(start 158.004002 -36.427156)
		(end 158.515304 -36.095178)
		(stroke
			(width 0.0508)
			(type default)
		)
		(layer "In2.Cu")
	)
	(gr_line
		(start 158.140908 -36.704778)
		(end 158.401258 -36.76015)
		(stroke
			(width 0.0508)
			(type default)
		)
		(layer "In2.Cu")
	)
	(gr_line
		(start 158.245556 -33.877758)
		(end 158.757874 -33.545272)
		(stroke
			(width 0.0508)
			(type default)
		)
		(layer "In2.Cu")
	)
	(gr_line
		(start 158.38297 -34.155126)
		(end 158.64332 -34.210498)
		(stroke
			(width 0.0508)
			(type default)
		)
		(layer "In2.Cu")
	)
	(gr_line
		(start 158.401258 -36.76015)
		(end 158.656782 -36.594034)
		(stroke
			(width 0.0508)
			(type default)
		)
		(layer "In2.Cu")
	)
	(gr_line
		(start 158.523432 -30.165802)
		(end 158.538418 -30.15615)
		(stroke
			(width 0.0508)
			(type default)
		)
		(layer "In2.Cu")
	)
	(gr_line
		(start 158.538418 -30.15615)
		(end 158.555944 -30.15234)
		(stroke
			(width 0.0508)
			(type default)
		)
		(layer "In2.Cu")
	)
	(gr_line
		(start 158.64332 -34.210498)
		(end 158.898844 -34.044382)
		(stroke
			(width 0.0508)
			(type default)
		)
		(layer "In2.Cu")
	)
	(gr_line
		(start 158.656782 -36.594034)
		(end 158.712154 -36.333684)
		(stroke
			(width 0.0508)
			(type default)
		)
		(layer "In2.Cu")
	)
	(gr_line
		(start 158.782004 -31.474918)
		(end 158.79699 -31.465266)
		(stroke
			(width 0.0508)
			(type default)
		)
		(layer "In2.Cu")
	)
	(gr_line
		(start 158.79699 -31.465266)
		(end 158.814516 -31.461456)
		(stroke
			(width 0.0508)
			(type default)
		)
		(layer "In2.Cu")
	)
	(gr_line
		(start 158.835852 -35.887152)
		(end 159.34563 -35.55619)
		(stroke
			(width 0.0508)
			(type default)
		)
		(layer "In2.Cu")
	)
	(gr_line
		(start 158.898844 -34.044382)
		(end 158.954216 -33.784032)
		(stroke
			(width 0.0508)
			(type default)
		)
		(layer "In2.Cu")
	)
	(gr_line
		(start 158.971742 -36.165282)
		(end 159.232092 -36.220654)
		(stroke
			(width 0.0508)
			(type default)
		)
		(layer "In2.Cu")
	)
	(gr_line
		(start 159.077914 -33.3375)
		(end 159.587946 -33.006284)
		(stroke
			(width 0.0508)
			(type default)
		)
		(layer "In2.Cu")
	)
	(gr_line
		(start 159.213804 -33.61563)
		(end 159.474154 -33.671002)
		(stroke
			(width 0.0508)
			(type default)
		)
		(layer "In2.Cu")
	)
	(gr_line
		(start 159.232092 -36.220654)
		(end 159.487616 -36.054538)
		(stroke
			(width 0.0508)
			(type default)
		)
		(layer "In2.Cu")
	)
	(gr_line
		(start 159.474154 -33.671002)
		(end 159.729678 -33.504886)
		(stroke
			(width 0.0508)
			(type default)
		)
		(layer "In2.Cu")
	)
	(gr_line
		(start 159.487616 -36.054538)
		(end 159.542988 -35.794188)
		(stroke
			(width 0.0508)
			(type default)
		)
		(layer "In2.Cu")
	)
	(gr_line
		(start 159.729678 -33.504886)
		(end 159.78505 -33.244536)
		(stroke
			(width 0.0508)
			(type default)
		)
		(layer "In2.Cu")
	)
	(gr_line
		(start 159.90824 -32.798258)
		(end 160.419034 -32.466534)
		(stroke
			(width 0.0508)
			(type default)
		)
		(layer "In2.Cu")
	)
	(gr_line
		(start 160.044638 -33.076134)
		(end 160.304988 -33.131506)
		(stroke
			(width 0.0508)
			(type default)
		)
		(layer "In2.Cu")
	)
	(gr_line
		(start 160.304988 -33.131506)
		(end 160.560512 -32.96539)
		(stroke
			(width 0.0508)
			(type default)
		)
		(layer "In2.Cu")
	)
	(gr_line
		(start 160.323276 -29.776674)
		(end 160.918652 -29.650182)
		(stroke
			(width 0.0508)
			(type default)
		)
		(layer "In2.Cu")
	)
	(gr_line
		(start 160.351978 -30.08503)
		(end 160.57499 -30.22981)
		(stroke
			(width 0.0508)
			(type default)
		)
		(layer "In2.Cu")
	)
	(gr_line
		(start 160.418526 -37.999924)
		(end 160.928304 -37.668962)
		(stroke
			(width 0.0508)
			(type default)
		)
		(layer "In2.Cu")
	)
	(gr_line
		(start 160.55467 -38.278054)
		(end 160.814766 -38.333426)
		(stroke
			(width 0.0508)
			(type default)
		)
		(layer "In2.Cu")
	)
	(gr_line
		(start 160.560512 -32.96539)
		(end 160.615884 -32.70504)
		(stroke
			(width 0.0508)
			(type default)
		)
		(layer "In2.Cu")
	)
	(gr_line
		(start 160.57499 -30.22981)
		(end 160.873186 -30.16631)
		(stroke
			(width 0.0508)
			(type default)
		)
		(layer "In2.Cu")
	)
	(gr_line
		(start 160.738566 -32.259016)
		(end 160.781746 -32.231076)
		(stroke
			(width 0.0508)
			(type default)
		)
		(layer "In2.Cu")
	)
	(gr_line
		(start 160.801812 -36.048188)
		(end 160.85693 -35.787838)
		(stroke
			(width 0.0508)
			(type default)
		)
		(layer "In2.Cu")
	)
	(gr_line
		(start 160.814766 -38.333426)
		(end 161.07029 -38.16731)
		(stroke
			(width 0.0508)
			(type default)
		)
		(layer "In2.Cu")
	)
	(gr_line
		(start 160.85693 -35.787838)
		(end 161.123122 -35.614864)
		(stroke
			(width 0.0508)
			(type default)
		)
		(layer "In2.Cu")
	)
	(gr_line
		(start 160.873186 -30.16631)
		(end 161.017966 -29.943298)
		(stroke
			(width 0.0508)
			(type default)
		)
		(layer "In2.Cu")
	)
	(gr_line
		(start 160.908746 -34.540952)
		(end 160.923732 -34.5313)
		(stroke
			(width 0.0508)
			(type default)
		)
		(layer "In2.Cu")
	)
	(gr_line
		(start 160.923732 -34.5313)
		(end 160.941258 -34.52749)
		(stroke
			(width 0.0508)
			(type default)
		)
		(layer "In2.Cu")
	)
	(gr_line
		(start 160.999678 -36.286186)
		(end 161.520886 -35.94735)
		(stroke
			(width 0.0508)
			(type default)
		)
		(layer "In2.Cu")
	)
	(gr_line
		(start 161.07029 -38.16731)
		(end 161.125662 -37.907214)
		(stroke
			(width 0.0508)
			(type default)
		)
		(layer "In2.Cu")
	)
	(gr_line
		(start 161.123122 -35.614864)
		(end 161.383472 -35.669982)
		(stroke
			(width 0.0508)
			(type default)
		)
		(layer "In2.Cu")
	)
	(gr_line
		(start 161.2265 -33.248854)
		(end 161.241486 -33.239202)
		(stroke
			(width 0.0508)
			(type default)
		)
		(layer "In2.Cu")
	)
	(gr_line
		(start 161.241486 -33.239202)
		(end 161.259012 -33.235392)
		(stroke
			(width 0.0508)
			(type default)
		)
		(layer "In2.Cu")
	)
	(gr_line
		(start 161.248852 -37.460682)
		(end 161.760154 -37.128704)
		(stroke
			(width 0.0508)
			(type default)
		)
		(layer "In2.Cu")
	)
	(gr_line
		(start 161.292286 -29.57068)
		(end 161.887662 -29.444188)
		(stroke
			(width 0.0508)
			(type default)
		)
		(layer "In2.Cu")
	)
	(gr_line
		(start 161.320988 -29.879036)
		(end 161.544 -30.023816)
		(stroke
			(width 0.0508)
			(type default)
		)
		(layer "In2.Cu")
	)
	(gr_line
		(start 161.38525 -37.738558)
		(end 161.6456 -37.79393)
		(stroke
			(width 0.0508)
			(type default)
		)
		(layer "In2.Cu")
	)
	(gr_line
		(start 161.544 -30.023816)
		(end 161.842196 -29.960316)
		(stroke
			(width 0.0508)
			(type default)
		)
		(layer "In2.Cu")
	)
	(gr_line
		(start 161.637218 -35.50793)
		(end 161.652966 -35.49777)
		(stroke
			(width 0.0508)
			(type default)
		)
		(layer "In2.Cu")
	)
	(gr_line
		(start 161.6456 -37.79393)
		(end 161.901124 -37.627814)
		(stroke
			(width 0.0508)
			(type default)
		)
		(layer "In2.Cu")
	)
	(gr_line
		(start 161.652966 -35.49777)
		(end 161.671 -35.49396)
		(stroke
			(width 0.0508)
			(type default)
		)
		(layer "In2.Cu")
	)
	(gr_line
		(start 161.842196 -29.960316)
		(end 161.986976 -29.737304)
		(stroke
			(width 0.0508)
			(type default)
		)
		(layer "In2.Cu")
	)
	(gr_line
		(start 161.901124 -37.627814)
		(end 161.956496 -37.367464)
		(stroke
			(width 0.0508)
			(type default)
		)
		(layer "In2.Cu")
	)
	(gr_line
		(start 161.907474 -34.322258)
		(end 162.504882 -34.195512)
		(stroke
			(width 0.0508)
			(type default)
		)
		(layer "In2.Cu")
	)
	(gr_line
		(start 161.936684 -34.63036)
		(end 162.15995 -34.775394)
		(stroke
			(width 0.0508)
			(type default)
		)
		(layer "In2.Cu")
	)
	(gr_line
		(start 162.079178 -36.92144)
		(end 162.094164 -36.911788)
		(stroke
			(width 0.0508)
			(type default)
		)
		(layer "In2.Cu")
	)
	(gr_line
		(start 162.094164 -36.911788)
		(end 162.11169 -36.907978)
		(stroke
			(width 0.0508)
			(type default)
		)
		(layer "In2.Cu")
	)
	(gr_line
		(start 162.15995 -34.775394)
		(end 162.457892 -34.712148)
		(stroke
			(width 0.0508)
			(type default)
		)
		(layer "In2.Cu")
	)
	(gr_line
		(start 162.457892 -34.712148)
		(end 162.602926 -34.489136)
		(stroke
			(width 0.0508)
			(type default)
		)
		(layer "In2.Cu")
	)
	(gr_line
		(start 162.884104 -37.902642)
		(end 162.89909 -37.89299)
		(stroke
			(width 0.0508)
			(type default)
		)
		(layer "In2.Cu")
	)
	(gr_line
		(start 162.89909 -37.89299)
		(end 162.916616 -37.88918)
		(stroke
			(width 0.0508)
			(type default)
		)
		(layer "In2.Cu")
	)
	(gr_line
		(start 163.684712 -34.383218)
		(end 163.70681 -34.383218)
		(stroke
			(width 0.04445)
			(type default)
		)
		(layer "In2.Cu")
	)
	(gr_line
		(start 163.684712 -34.078418)
		(end 163.70681 -34.078418)
		(stroke
			(width 0.04445)
			(type default)
		)
		(layer "In2.Cu")
	)
	(gr_line
		(start 163.70681 -34.383218)
		(end 163.722812 -34.367216)
		(stroke
			(width 0.04445)
			(type default)
		)
		(layer "In2.Cu")
	)
	(gr_line
		(start 163.70681 -34.078418)
		(end 163.722812 -34.09442)
		(stroke
			(width 0.04445)
			(type default)
		)
		(layer "In2.Cu")
	)
	(gr_line
		(start 163.72459 -34.365438)
		(end 163.76396 -34.326068)
		(stroke
			(width 0.04445)
			(type default)
		)
		(layer "In2.Cu")
	)
	(gr_line
		(start 163.72459 -34.096198)
		(end 163.76396 -34.135568)
		(stroke
			(width 0.04445)
			(type default)
		)
		(layer "In2.Cu")
	)
	(gr_line
		(start 163.796218 -33.47847)
		(end 163.818316 -33.47847)
		(stroke
			(width 0.04445)
			(type default)
		)
		(layer "In2.Cu")
	)
	(gr_line
		(start 163.796218 -33.17367)
		(end 163.818316 -33.17367)
		(stroke
			(width 0.04445)
			(type default)
		)
		(layer "In2.Cu")
	)
	(gr_line
		(start 163.818316 -33.47847)
		(end 163.834318 -33.462468)
		(stroke
			(width 0.04445)
			(type default)
		)
		(layer "In2.Cu")
	)
	(gr_line
		(start 163.818316 -33.17367)
		(end 163.834318 -33.189672)
		(stroke
			(width 0.04445)
			(type default)
		)
		(layer "In2.Cu")
	)
	(gr_line
		(start 163.836096 -33.46069)
		(end 163.875466 -33.42132)
		(stroke
			(width 0.04445)
			(type default)
		)
		(layer "In2.Cu")
	)
	(gr_line
		(start 163.836096 -33.19145)
		(end 163.875466 -33.23082)
		(stroke
			(width 0.04445)
			(type default)
		)
		(layer "In2.Cu")
	)
	(gr_line
		(start 164.969698 -36.495228)
		(end 165.132512 -36.495228)
		(stroke
			(width 0.04445)
			(type default)
		)
		(layer "In2.Cu")
	)
	(gr_line
		(start 165.132512 -36.495228)
		(end 165.227762 -36.399978)
		(stroke
			(width 0.04445)
			(type default)
		)
		(layer "In2.Cu")
	)
	(gr_line
		(start 165.17112 -34.271204)
		(end 165.299898 -34.399982)
		(stroke
			(width 0.04445)
			(type default)
		)
		(layer "In2.Cu")
	)
	(gr_line
		(start 165.172898 -33.999932)
		(end 165.79977 -33.999932)
		(stroke
			(width 0.04445)
			(type default)
		)
		(layer "In2.Cu")
	)
	(gr_line
		(start 165.227762 -36.399978)
		(end 165.79977 -36.399978)
		(stroke
			(width 0.04445)
			(type default)
		)
		(layer "In2.Cu")
	)
	(gr_line
		(start 165.232588 -31.997396)
		(end 165.254686 -31.997396)
		(stroke
			(width 0.04445)
			(type default)
		)
		(layer "In2.Cu")
	)
	(gr_line
		(start 165.232588 -31.692596)
		(end 165.254686 -31.692596)
		(stroke
			(width 0.04445)
			(type default)
		)
		(layer "In2.Cu")
	)
	(gr_line
		(start 165.254686 -31.997396)
		(end 165.270688 -31.981394)
		(stroke
			(width 0.04445)
			(type default)
		)
		(layer "In2.Cu")
	)
	(gr_line
		(start 165.254686 -31.692596)
		(end 165.270688 -31.708598)
		(stroke
			(width 0.04445)
			(type default)
		)
		(layer "In2.Cu")
	)
	(gr_line
		(start 165.272466 -31.979616)
		(end 165.311836 -31.940246)
		(stroke
			(width 0.04445)
			(type default)
		)
		(layer "In2.Cu")
	)
	(gr_line
		(start 165.272466 -31.710376)
		(end 165.311836 -31.749746)
		(stroke
			(width 0.04445)
			(type default)
		)
		(layer "In2.Cu")
	)
	(gr_line
		(start 165.277038 -36.800028)
		(end 165.399974 -36.800028)
		(stroke
			(width 0.0508)
			(type default)
		)
		(layer "In2.Cu")
	)
	(gr_line
		(start 165.299898 -34.399982)
		(end 165.399974 -34.399982)
		(stroke
			(width 0.04445)
			(type default)
		)
		(layer "In2.Cu")
	)
	(gr_line
		(start 165.346634 -29.44749)
		(end 165.368732 -29.44749)
		(stroke
			(width 0.04445)
			(type default)
		)
		(layer "In2.Cu")
	)
	(gr_line
		(start 165.346634 -29.14269)
		(end 165.368732 -29.14269)
		(stroke
			(width 0.04445)
			(type default)
		)
		(layer "In2.Cu")
	)
	(gr_line
		(start 165.368732 -29.44749)
		(end 165.384734 -29.431488)
		(stroke
			(width 0.04445)
			(type default)
		)
		(layer "In2.Cu")
	)
	(gr_line
		(start 165.368732 -29.14269)
		(end 165.384734 -29.158692)
		(stroke
			(width 0.04445)
			(type default)
		)
		(layer "In2.Cu")
	)
	(gr_line
		(start 165.386512 -29.42971)
		(end 165.425882 -29.39034)
		(stroke
			(width 0.04445)
			(type default)
		)
		(layer "In2.Cu")
	)
	(gr_line
		(start 165.386512 -29.16047)
		(end 165.425882 -29.19984)
		(stroke
			(width 0.04445)
			(type default)
		)
		(layer "In2.Cu")
	)
	(gr_line
		(start 165.79977 -36.399978)
		(end 166.19982 -36.800028)
		(stroke
			(width 0.04445)
			(type default)
		)
		(layer "In2.Cu")
	)
	(gr_line
		(start 165.79977 -33.999932)
		(end 166.19982 -34.399982)
		(stroke
			(width 0.04445)
			(type default)
		)
		(layer "In2.Cu")
	)
	(gr_line
		(start 165.828472 -31.747206)
		(end 165.975792 -31.599886)
		(stroke
			(width 0.04445)
			(type default)
		)
		(layer "In2.Cu")
	)
	(gr_arc
		(start 165.952932 -33.104582)
		(mid 166.127485 -33.032259)
		(end 166.19982 -32.857694)
		(stroke
			(width 0.04445)
			(type default)
		)
		(layer "In2.Cu")
	)
	(gr_line
		(start 165.975792 -31.599886)
		(end 166.59987 -31.599886)
		(stroke
			(width 0.04445)
			(type default)
		)
		(layer "In2.Cu")
	)
	(gr_line
		(start 165.99281 -29.39288)
		(end 166.19982 -29.59989)
		(stroke
			(width 0.04445)
			(type default)
		)
		(layer "In2.Cu")
	)
	(gr_line
		(start 166.018972 -31.940246)
		(end 166.140384 -31.940246)
		(stroke
			(width 0.04445)
			(type default)
		)
		(layer "In2.Cu")
	)
	(gr_arc
		(start 166.111936 -37.853366)
		(mid 166.178952 -37.822893)
		(end 166.19982 -37.752274)
		(stroke
			(width 0.0508)
			(type default)
		)
		(layer "In2.Cu")
	)
	(gr_arc
		(start 166.111936 -35.45332)
		(mid 166.178869 -35.422796)
		(end 166.19982 -35.352228)
		(stroke
			(width 0.0508)
			(type default)
		)
		(layer "In2.Cu")
	)
	(gr_arc
		(start 166.111936 -30.653228)
		(mid 166.178979 -30.622756)
		(end 166.19982 -30.552136)
		(stroke
			(width 0.0508)
			(type default)
		)
		(layer "In2.Cu")
	)
	(gr_line
		(start 166.140384 -31.940246)
		(end 166.200074 -31.999936)
		(stroke
			(width 0.04445)
			(type default)
		)
		(layer "In2.Cu")
	)
	(gr_arc
		(start 166.163752 -38.19398)
		(mid 166.124144 -38.167451)
		(end 166.077392 -38.158166)
		(stroke
			(width 0.0508)
			(type default)
		)
		(layer "In2.Cu")
	)
	(gr_arc
		(start 166.163752 -35.793934)
		(mid 166.124134 -35.767442)
		(end 166.077392 -35.75812)
		(stroke
			(width 0.0508)
			(type default)
		)
		(layer "In2.Cu")
	)
	(gr_arc
		(start 166.163752 -30.993842)
		(mid 166.124144 -30.967313)
		(end 166.077392 -30.958028)
		(stroke
			(width 0.0508)
			(type default)
		)
		(layer "In2.Cu")
	)
	(gr_line
		(start 166.18331 -29.19984)
		(end 166.599362 -29.19984)
		(stroke
			(width 0.04445)
			(type default)
		)
		(layer "In2.Cu")
	)
	(gr_arc
		(start 166.19982 -38.280848)
		(mid 166.190447 -38.233817)
		(end 166.163752 -38.19398)
		(stroke
			(width 0.0508)
			(type default)
		)
		(layer "In2.Cu")
	)
	(gr_line
		(start 166.19982 -38.280848)
		(end 166.19982 -38.399974)
		(stroke
			(width 0.0508)
			(type default)
		)
		(layer "In2.Cu")
	)
	(gr_line
		(start 166.19982 -37.599874)
		(end 166.19982 -37.752274)
		(stroke
			(width 0.0508)
			(type default)
		)
		(layer "In2.Cu")
	)
	(gr_arc
		(start 166.19982 -35.880802)
		(mid 166.19045 -35.833768)
		(end 166.163752 -35.793934)
		(stroke
			(width 0.0508)
			(type default)
		)
		(layer "In2.Cu")
	)
	(gr_line
		(start 166.19982 -35.880802)
		(end 166.19982 -35.999928)
		(stroke
			(width 0.0508)
			(type default)
		)
		(layer "In2.Cu")
	)
	(gr_line
		(start 166.19982 -35.199828)
		(end 166.19982 -35.352228)
		(stroke
			(width 0.0508)
			(type default)
		)
		(layer "In2.Cu")
	)
	(gr_arc
		(start 166.19982 -33.54197)
		(mid 166.1275 -33.367402)
		(end 165.952932 -33.295082)
		(stroke
			(width 0.04445)
			(type default)
		)
		(layer "In2.Cu")
	)
	(gr_line
		(start 166.19982 -33.54197)
		(end 166.19982 -33.599882)
		(stroke
			(width 0.04445)
			(type default)
		)
		(layer "In2.Cu")
	)
	(gr_line
		(start 166.19982 -32.800036)
		(end 166.19982 -32.857694)
		(stroke
			(width 0.04445)
			(type default)
		)
		(layer "In2.Cu")
	)
	(gr_arc
		(start 166.19982 -31.08071)
		(mid 166.190447 -31.033679)
		(end 166.163752 -30.993842)
		(stroke
			(width 0.0508)
			(type default)
		)
		(layer "In2.Cu")
	)
	(gr_line
		(start 166.19982 -31.08071)
		(end 166.19982 -31.199836)
		(stroke
			(width 0.0508)
			(type default)
		)
		(layer "In2.Cu")
	)
	(gr_line
		(start 166.19982 -30.39999)
		(end 166.19982 -30.552136)
		(stroke
			(width 0.0508)
			(type default)
		)
		(layer "In2.Cu")
	)
	(gr_line
		(start 166.599362 -29.19984)
		(end 166.999666 -29.600144)
		(stroke
			(width 0.04445)
			(type default)
		)
		(layer "In2.Cu")
	)
	(gr_line
		(start 166.59987 -31.599886)
		(end 166.99992 -31.999936)
		(stroke
			(width 0.04445)
			(type default)
		)
		(layer "In2.Cu")
	)
	(gr_line
		(start 0 -142.999968)
		(end 0 -1.999996)
		(stroke
			(width 2.54)
			(type default)
		)
		(layer "In3.Cu")
	)
	(gr_arc
		(start 0 -142.999968)
		(mid 0.585785 -144.414179)
		(end 1.999996 -144.999964)
		(stroke
			(width 2.54)
			(type default)
		)
		(layer "In3.Cu")
	)
	(gr_arc
		(start 1.999996 0)
		(mid 0.585785 -0.585785)
		(end 0 -1.999996)
		(stroke
			(width 2.54)
			(type default)
		)
		(layer "In3.Cu")
	)
	(gr_line
		(start 1.999996 0)
		(end 208.000092 0)
		(stroke
			(width 2.54)
			(type default)
		)
		(layer "In3.Cu")
	)
	(gr_line
		(start 31.545276 -83.6676)
		(end 35.761676 -87.884)
		(stroke
			(width 0.381)
			(type default)
		)
		(layer "In3.Cu")
	)
	(gr_line
		(start 31.545276 -62.511432)
		(end 31.545276 -83.6676)
		(stroke
			(width 0.381)
			(type default)
		)
		(layer "In3.Cu")
	)
	(gr_line
		(start 33.159446 -36.414964)
		(end 33.796478 -35.777932)
		(stroke
			(width 0.381)
			(type default)
		)
		(layer "In3.Cu")
	)
	(gr_line
		(start 33.159446 -36.414964)
		(end 33.796732 -37.05225)
		(stroke
			(width 0.381)
			(type default)
		)
		(layer "In3.Cu")
	)
	(gr_line
		(start 33.796478 -60.26023)
		(end 31.545276 -62.511432)
		(stroke
			(width 0.381)
			(type default)
		)
		(layer "In3.Cu")
	)
	(gr_line
		(start 33.796478 -36.414964)
		(end 0.006096 -36.414964)
		(stroke
			(width 0.381)
			(type default)
		)
		(layer "In3.Cu")
	)
	(gr_line
		(start 33.796478 -36.414964)
		(end 33.796478 -60.26023)
		(stroke
			(width 0.381)
			(type default)
		)
		(layer "In3.Cu")
	)
	(gr_line
		(start 33.796478 -28.099004)
		(end 33.796478 -36.414964)
		(stroke
			(width 0.381)
			(type default)
		)
		(layer "In3.Cu")
	)
	(gr_line
		(start 35.761676 -87.884)
		(end 50.7492 -87.884)
		(stroke
			(width 0.381)
			(type default)
		)
		(layer "In3.Cu")
	)
	(gr_line
		(start 38.52418 -1.67132)
		(end 37.887148 -1.034288)
		(stroke
			(width 0.381)
			(type default)
		)
		(layer "In3.Cu")
	)
	(gr_line
		(start 38.52418 -1.67132)
		(end 39.161466 -1.034034)
		(stroke
			(width 0.381)
			(type default)
		)
		(layer "In3.Cu")
	)
	(gr_line
		(start 38.528752 -23.36673)
		(end 33.796478 -28.099004)
		(stroke
			(width 0.381)
			(type default)
		)
		(layer "In3.Cu")
	)
	(gr_line
		(start 38.528752 -0.032004)
		(end 38.528752 -23.36673)
		(stroke
			(width 0.381)
			(type default)
		)
		(layer "In3.Cu")
	)
	(gr_line
		(start 50.5206 -87.884)
		(end 50.5714 -87.884)
		(stroke
			(width 0.381)
			(type default)
		)
		(layer "In3.Cu")
	)
	(gr_line
		(start 50.5714 -87.884)
		(end 50.8 -87.6554)
		(stroke
			(width 0.381)
			(type default)
		)
		(layer "In3.Cu")
	)
	(gr_line
		(start 50.8 -94.85376)
		(end 51.4096 -95.46336)
		(stroke
			(width 0.381)
			(type default)
		)
		(layer "In3.Cu")
	)
	(gr_line
		(start 50.8 -88.1634)
		(end 50.5206 -87.884)
		(stroke
			(width 0.381)
			(type default)
		)
		(layer "In3.Cu")
	)
	(gr_line
		(start 50.8 -55.153814)
		(end 50.8 -94.85376)
		(stroke
			(width 0.381)
			(type default)
		)
		(layer "In3.Cu")
	)
	(gr_arc
		(start 50.807366 -55.136034)
		(mid 50.801969 -55.144206)
		(end 50.8 -55.153814)
		(stroke
			(width 0.381)
			(type default)
		)
		(layer "In3.Cu")
	)
	(gr_line
		(start 51.4096 -95.46336)
		(end 70.19036 -95.46336)
		(stroke
			(width 0.381)
			(type default)
		)
		(layer "In3.Cu")
	)
	(gr_line
		(start 59.3598 -46.5836)
		(end 50.807366 -55.136034)
		(stroke
			(width 0.381)
			(type default)
		)
		(layer "In3.Cu")
	)
	(gr_line
		(start 59.3598 -34.163)
		(end 59.3598 -46.5836)
		(stroke
			(width 0.381)
			(type default)
		)
		(layer "In3.Cu")
	)
	(gr_line
		(start 59.8424 -33.6804)
		(end 59.3598 -34.163)
		(stroke
			(width 0.381)
			(type default)
		)
		(layer "In3.Cu")
	)
	(gr_line
		(start 72.3646 -60.5536)
		(end 73.8632 -62.0522)
		(stroke
			(width 0.381)
			(type default)
		)
		(layer "In3.Cu")
	)
	(gr_line
		(start 72.3646 -34.24936)
		(end 71.93153 -33.81629)
		(stroke
			(width 0.381)
			(type default)
		)
		(layer "In3.Cu")
	)
	(gr_line
		(start 72.3646 -33.7566)
		(end 72.3646 -60.5536)
		(stroke
			(width 0.381)
			(type default)
		)
		(layer "In3.Cu")
	)
	(gr_line
		(start 72.79767 -33.81629)
		(end 72.3646 -34.24936)
		(stroke
			(width 0.381)
			(type default)
		)
		(layer "In3.Cu")
	)
	(gr_line
		(start 73.8632 -62.0522)
		(end 97.77222 -62.0522)
		(stroke
			(width 0.381)
			(type default)
		)
		(layer "In3.Cu")
	)
	(gr_line
		(start 83.002374 -144.999964)
		(end 1.999996 -144.999964)
		(stroke
			(width 2.54)
			(type default)
		)
		(layer "In3.Cu")
	)
	(gr_arc
		(start 83.002374 -144.999964)
		(mid 84.41672 -144.414257)
		(end 85.002624 -142.999968)
		(stroke
			(width 2.54)
			(type default)
		)
		(layer "In3.Cu")
	)
	(gr_line
		(start 85.002624 -132.26288)
		(end 85.002624 -142.999968)
		(stroke
			(width 2.54)
			(type default)
		)
		(layer "In3.Cu")
	)
	(gr_line
		(start 85.1408 -33.6804)
		(end 59.8424 -33.6804)
		(stroke
			(width 0.381)
			(type default)
		)
		(layer "In3.Cu")
	)
	(gr_arc
		(start 85.438742 -12.399772)
		(mid 85.999955 -12.961366)
		(end 86.561422 -12.400026)
		(stroke
			(width 0.2)
			(type default)
		)
		(layer "In3.Cu")
	)
	(gr_line
		(start 85.438742 -10.999978)
		(end 85.438742 -12.399772)
		(stroke
			(width 0.2)
			(type default)
		)
		(layer "In3.Cu")
	)
	(gr_arc
		(start 85.438742 -5.199888)
		(mid 85.999955 -5.761482)
		(end 86.561422 -5.200142)
		(stroke
			(width 0.2)
			(type default)
		)
		(layer "In3.Cu")
	)
	(gr_line
		(start 85.438742 -3.800094)
		(end 85.438742 -5.199888)
		(stroke
			(width 0.2)
			(type default)
		)
		(layer "In3.Cu")
	)
	(gr_line
		(start 86.561422 -12.400026)
		(end 86.561422 -10.999978)
		(stroke
			(width 0.2)
			(type default)
		)
		(layer "In3.Cu")
	)
	(gr_arc
		(start 86.561422 -10.999978)
		(mid 86.000082 -10.438638)
		(end 85.438742 -10.999978)
		(stroke
			(width 0.2)
			(type default)
		)
		(layer "In3.Cu")
	)
	(gr_line
		(start 86.561422 -5.200142)
		(end 86.561422 -3.800094)
		(stroke
			(width 0.2)
			(type default)
		)
		(layer "In3.Cu")
	)
	(gr_arc
		(start 86.561422 -3.800094)
		(mid 86.000082 -3.238754)
		(end 85.438742 -3.800094)
		(stroke
			(width 0.2)
			(type default)
		)
		(layer "In3.Cu")
	)
	(gr_arc
		(start 87.23884 -11.199876)
		(mid 87.800053 -11.76147)
		(end 88.36152 -11.20013)
		(stroke
			(width 0.2)
			(type default)
		)
		(layer "In3.Cu")
	)
	(gr_line
		(start 87.23884 -9.800082)
		(end 87.23884 -11.199876)
		(stroke
			(width 0.2)
			(type default)
		)
		(layer "In3.Cu")
	)
	(gr_arc
		(start 87.23884 -3.999738)
		(mid 87.800053 -4.561332)
		(end 88.36152 -3.999992)
		(stroke
			(width 0.2)
			(type default)
		)
		(layer "In3.Cu")
	)
	(gr_line
		(start 87.23884 -2.600198)
		(end 87.23884 -3.999738)
		(stroke
			(width 0.2)
			(type default)
		)
		(layer "In3.Cu")
	)
	(gr_line
		(start 88.36152 -11.20013)
		(end 88.36152 -9.800082)
		(stroke
			(width 0.2)
			(type default)
		)
		(layer "In3.Cu")
	)
	(gr_arc
		(start 88.36152 -9.800082)
		(mid 87.80018 -9.238742)
		(end 87.23884 -9.800082)
		(stroke
			(width 0.2)
			(type default)
		)
		(layer "In3.Cu")
	)
	(gr_line
		(start 88.36152 -3.999992)
		(end 88.36152 -2.600198)
		(stroke
			(width 0.2)
			(type default)
		)
		(layer "In3.Cu")
	)
	(gr_arc
		(start 88.36152 -2.600198)
		(mid 87.80018 -2.038858)
		(end 87.23884 -2.600198)
		(stroke
			(width 0.2)
			(type default)
		)
		(layer "In3.Cu")
	)
	(gr_line
		(start 88.5952 -30.226)
		(end 85.1408 -33.6804)
		(stroke
			(width 0.381)
			(type default)
		)
		(layer "In3.Cu")
	)
	(gr_arc
		(start 89.038684 -12.399772)
		(mid 89.599897 -12.961366)
		(end 90.161364 -12.400026)
		(stroke
			(width 0.2)
			(type default)
		)
		(layer "In3.Cu")
	)
	(gr_line
		(start 89.038684 -10.999978)
		(end 89.038684 -12.399772)
		(stroke
			(width 0.2)
			(type default)
		)
		(layer "In3.Cu")
	)
	(gr_arc
		(start 89.038684 -5.199888)
		(mid 89.599897 -5.761482)
		(end 90.161364 -5.200142)
		(stroke
			(width 0.2)
			(type default)
		)
		(layer "In3.Cu")
	)
	(gr_line
		(start 89.038684 -3.800094)
		(end 89.038684 -5.199888)
		(stroke
			(width 0.2)
			(type default)
		)
		(layer "In3.Cu")
	)
	(gr_arc
		(start 89.212674 -127.325628)
		(mid 86.197998 -129.018598)
		(end 85.002624 -132.26288)
		(stroke
			(width 2.54)
			(type default)
		)
		(layer "In3.Cu")
	)
	(gr_line
		(start 90.161364 -12.400026)
		(end 90.161364 -10.999978)
		(stroke
			(width 0.2)
			(type default)
		)
		(layer "In3.Cu")
	)
	(gr_arc
		(start 90.161364 -10.999978)
		(mid 89.600024 -10.438638)
		(end 89.038684 -10.999978)
		(stroke
			(width 0.2)
			(type default)
		)
		(layer "In3.Cu")
	)
	(gr_line
		(start 90.161364 -5.200142)
		(end 90.161364 -3.800094)
		(stroke
			(width 0.2)
			(type default)
		)
		(layer "In3.Cu")
	)
	(gr_arc
		(start 90.161364 -3.800094)
		(mid 89.600024 -3.238754)
		(end 89.038684 -3.800094)
		(stroke
			(width 0.2)
			(type default)
		)
		(layer "In3.Cu")
	)
	(gr_arc
		(start 90.838782 -11.199876)
		(mid 91.399995 -11.76147)
		(end 91.961462 -11.20013)
		(stroke
			(width 0.2)
			(type default)
		)
		(layer "In3.Cu")
	)
	(gr_line
		(start 90.838782 -9.800082)
		(end 90.838782 -11.199876)
		(stroke
			(width 0.2)
			(type default)
		)
		(layer "In3.Cu")
	)
	(gr_arc
		(start 90.838782 -3.999738)
		(mid 91.399995 -4.561332)
		(end 91.961462 -3.999992)
		(stroke
			(width 0.2)
			(type default)
		)
		(layer "In3.Cu")
	)
	(gr_line
		(start 90.838782 -2.600198)
		(end 90.838782 -3.999738)
		(stroke
			(width 0.2)
			(type default)
		)
		(layer "In3.Cu")
	)
	(gr_line
		(start 91.961462 -11.20013)
		(end 91.961462 -9.800082)
		(stroke
			(width 0.2)
			(type default)
		)
		(layer "In3.Cu")
	)
	(gr_arc
		(start 91.961462 -9.800082)
		(mid 91.400122 -9.238742)
		(end 90.838782 -9.800082)
		(stroke
			(width 0.2)
			(type default)
		)
		(layer "In3.Cu")
	)
	(gr_line
		(start 91.961462 -3.999992)
		(end 91.961462 -2.600198)
		(stroke
			(width 0.2)
			(type default)
		)
		(layer "In3.Cu")
	)
	(gr_arc
		(start 91.961462 -2.600198)
		(mid 91.400122 -2.038858)
		(end 90.838782 -2.600198)
		(stroke
			(width 0.2)
			(type default)
		)
		(layer "In3.Cu")
	)
	(gr_arc
		(start 92.638626 -12.399772)
		(mid 93.199839 -12.961366)
		(end 93.761306 -12.400026)
		(stroke
			(width 0.2)
			(type default)
		)
		(layer "In3.Cu")
	)
	(gr_line
		(start 92.638626 -10.999978)
		(end 92.638626 -12.399772)
		(stroke
			(width 0.2)
			(type default)
		)
		(layer "In3.Cu")
	)
	(gr_arc
		(start 92.638626 -5.199888)
		(mid 93.199839 -5.761482)
		(end 93.761306 -5.200142)
		(stroke
			(width 0.2)
			(type default)
		)
		(layer "In3.Cu")
	)
	(gr_line
		(start 92.638626 -3.800094)
		(end 92.638626 -5.199888)
		(stroke
			(width 0.2)
			(type default)
		)
		(layer "In3.Cu")
	)
	(gr_line
		(start 93.761306 -12.400026)
		(end 93.761306 -10.999978)
		(stroke
			(width 0.2)
			(type default)
		)
		(layer "In3.Cu")
	)
	(gr_arc
		(start 93.761306 -10.999978)
		(mid 93.199966 -10.438638)
		(end 92.638626 -10.999978)
		(stroke
			(width 0.2)
			(type default)
		)
		(layer "In3.Cu")
	)
	(gr_line
		(start 93.761306 -5.200142)
		(end 93.761306 -3.800094)
		(stroke
			(width 0.2)
			(type default)
		)
		(layer "In3.Cu")
	)
	(gr_arc
		(start 93.761306 -3.800094)
		(mid 93.199966 -3.238754)
		(end 92.638626 -3.800094)
		(stroke
			(width 0.2)
			(type default)
		)
		(layer "In3.Cu")
	)
	(gr_arc
		(start 94.438724 -11.199876)
		(mid 94.999937 -11.76147)
		(end 95.561404 -11.20013)
		(stroke
			(width 0.2)
			(type default)
		)
		(layer "In3.Cu")
	)
	(gr_line
		(start 94.438724 -9.800082)
		(end 94.438724 -11.199876)
		(stroke
			(width 0.2)
			(type default)
		)
		(layer "In3.Cu")
	)
	(gr_arc
		(start 94.438724 -3.999738)
		(mid 94.999937 -4.561332)
		(end 95.561404 -3.999992)
		(stroke
			(width 0.2)
			(type default)
		)
		(layer "In3.Cu")
	)
	(gr_line
		(start 94.438724 -2.600198)
		(end 94.438724 -3.999738)
		(stroke
			(width 0.2)
			(type default)
		)
		(layer "In3.Cu")
	)
	(gr_line
		(start 95.561404 -11.20013)
		(end 95.561404 -9.800082)
		(stroke
			(width 0.2)
			(type default)
		)
		(layer "In3.Cu")
	)
	(gr_arc
		(start 95.561404 -9.800082)
		(mid 95.000064 -9.238742)
		(end 94.438724 -9.800082)
		(stroke
			(width 0.2)
			(type default)
		)
		(layer "In3.Cu")
	)
	(gr_line
		(start 95.561404 -3.999992)
		(end 95.561404 -2.600198)
		(stroke
			(width 0.2)
			(type default)
		)
		(layer "In3.Cu")
	)
	(gr_arc
		(start 95.561404 -2.600198)
		(mid 95.000064 -2.038858)
		(end 94.438724 -2.600198)
		(stroke
			(width 0.2)
			(type default)
		)
		(layer "In3.Cu")
	)
	(gr_arc
		(start 96.238822 -12.399772)
		(mid 96.800035 -12.961366)
		(end 97.361502 -12.400026)
		(stroke
			(width 0.2)
			(type default)
		)
		(layer "In3.Cu")
	)
	(gr_line
		(start 96.238822 -10.999978)
		(end 96.238822 -12.399772)
		(stroke
			(width 0.2)
			(type default)
		)
		(layer "In3.Cu")
	)
	(gr_arc
		(start 96.238822 -5.199888)
		(mid 96.800035 -5.761482)
		(end 97.361502 -5.200142)
		(stroke
			(width 0.2)
			(type default)
		)
		(layer "In3.Cu")
	)
	(gr_line
		(start 96.238822 -3.800094)
		(end 96.238822 -5.199888)
		(stroke
			(width 0.2)
			(type default)
		)
		(layer "In3.Cu")
	)
	(gr_line
		(start 97.361502 -12.400026)
		(end 97.361502 -10.999978)
		(stroke
			(width 0.2)
			(type default)
		)
		(layer "In3.Cu")
	)
	(gr_arc
		(start 97.361502 -10.999978)
		(mid 96.800162 -10.438638)
		(end 96.238822 -10.999978)
		(stroke
			(width 0.2)
			(type default)
		)
		(layer "In3.Cu")
	)
	(gr_line
		(start 97.361502 -5.200142)
		(end 97.361502 -3.800094)
		(stroke
			(width 0.2)
			(type default)
		)
		(layer "In3.Cu")
	)
	(gr_arc
		(start 97.361502 -3.800094)
		(mid 96.800162 -3.238754)
		(end 96.238822 -3.800094)
		(stroke
			(width 0.2)
			(type default)
		)
		(layer "In3.Cu")
	)
	(gr_line
		(start 97.499932 -126.000002)
		(end 89.212674 -127.325628)
		(stroke
			(width 2.54)
			(type default)
		)
		(layer "In3.Cu")
	)
	(gr_line
		(start 97.77222 -62.0522)
		(end 98.206306 -62.486286)
		(stroke
			(width 0.381)
			(type default)
		)
		(layer "In3.Cu")
	)
	(gr_arc
		(start 98.038666 -11.199876)
		(mid 98.599879 -11.76147)
		(end 99.161346 -11.20013)
		(stroke
			(width 0.2)
			(type default)
		)
		(layer "In3.Cu")
	)
	(gr_line
		(start 98.038666 -9.800082)
		(end 98.038666 -11.199876)
		(stroke
			(width 0.2)
			(type default)
		)
		(layer "In3.Cu")
	)
	(gr_arc
		(start 98.038666 -3.999738)
		(mid 98.599879 -4.561332)
		(end 99.161346 -3.999992)
		(stroke
			(width 0.2)
			(type default)
		)
		(layer "In3.Cu")
	)
	(gr_line
		(start 98.038666 -2.600198)
		(end 98.038666 -3.999738)
		(stroke
			(width 0.2)
			(type default)
		)
		(layer "In3.Cu")
	)
	(gr_line
		(start 98.206306 -62.486286)
		(end 121.10593 -62.486286)
		(stroke
			(width 0.381)
			(type default)
		)
		(layer "In3.Cu")
	)
	(gr_arc
		(start 98.641916 -54.99989)
		(mid 98.999929 -55.358284)
		(end 99.358196 -55.000144)
		(stroke
			(width 0.2)
			(type default)
		)
		(layer "In3.Cu")
	)
	(gr_line
		(start 98.641916 -54.000146)
		(end 98.641916 -54.99989)
		(stroke
			(width 0.2)
			(type default)
		)
		(layer "In3.Cu")
	)
	(gr_line
		(start 99.161346 -11.20013)
		(end 99.161346 -9.800082)
		(stroke
			(width 0.2)
			(type default)
		)
		(layer "In3.Cu")
	)
	(gr_arc
		(start 99.161346 -9.800082)
		(mid 98.600006 -9.238742)
		(end 98.038666 -9.800082)
		(stroke
			(width 0.2)
			(type default)
		)
		(layer "In3.Cu")
	)
	(gr_line
		(start 99.161346 -3.999992)
		(end 99.161346 -2.600198)
		(stroke
			(width 0.2)
			(type default)
		)
		(layer "In3.Cu")
	)
	(gr_arc
		(start 99.161346 -2.600198)
		(mid 98.600006 -2.038858)
		(end 98.038666 -2.600198)
		(stroke
			(width 0.2)
			(type default)
		)
		(layer "In3.Cu")
	)
	(gr_line
		(start 99.358196 -55.000144)
		(end 99.358196 -54.000146)
		(stroke
			(width 0.2)
			(type default)
		)
		(layer "In3.Cu")
	)
	(gr_arc
		(start 99.358196 -54.000146)
		(mid 99.000056 -53.642006)
		(end 98.641916 -54.000146)
		(stroke
			(width 0.2)
			(type default)
		)
		(layer "In3.Cu")
	)
	(gr_arc
		(start 99.641914 -51.999896)
		(mid 99.999927 -52.35829)
		(end 100.358194 -52.00015)
		(stroke
			(width 0.2)
			(type default)
		)
		(layer "In3.Cu")
	)
	(gr_line
		(start 99.641914 -51.000152)
		(end 99.641914 -51.999896)
		(stroke
			(width 0.2)
			(type default)
		)
		(layer "In3.Cu")
	)
	(gr_arc
		(start 99.838764 -12.399772)
		(mid 100.399977 -12.961366)
		(end 100.961444 -12.400026)
		(stroke
			(width 0.2)
			(type default)
		)
		(layer "In3.Cu")
	)
	(gr_line
		(start 99.838764 -10.999978)
		(end 99.838764 -12.399772)
		(stroke
			(width 0.2)
			(type default)
		)
		(layer "In3.Cu")
	)
	(gr_arc
		(start 99.838764 -5.199888)
		(mid 100.399977 -5.761482)
		(end 100.961444 -5.200142)
		(stroke
			(width 0.2)
			(type default)
		)
		(layer "In3.Cu")
	)
	(gr_line
		(start 99.838764 -3.800094)
		(end 99.838764 -5.199888)
		(stroke
			(width 0.2)
			(type default)
		)
		(layer "In3.Cu")
	)
	(gr_line
		(start 100.358194 -52.00015)
		(end 100.358194 -51.000152)
		(stroke
			(width 0.2)
			(type default)
		)
		(layer "In3.Cu")
	)
	(gr_arc
		(start 100.358194 -51.000152)
		(mid 100.000054 -50.642012)
		(end 99.641914 -51.000152)
		(stroke
			(width 0.2)
			(type default)
		)
		(layer "In3.Cu")
	)
	(gr_arc
		(start 100.641912 -55.999888)
		(mid 100.999925 -56.358282)
		(end 101.358192 -56.000142)
		(stroke
			(width 0.2)
			(type default)
		)
		(layer "In3.Cu")
	)
	(gr_line
		(start 100.641912 -55.000144)
		(end 100.641912 -55.999888)
		(stroke
			(width 0.2)
			(type default)
		)
		(layer "In3.Cu")
	)
	(gr_arc
		(start 100.641912 -52.999894)
		(mid 100.999925 -53.358288)
		(end 101.358192 -53.000148)
		(stroke
			(width 0.2)
			(type default)
		)
		(layer "In3.Cu")
	)
	(gr_line
		(start 100.641912 -52.00015)
		(end 100.641912 -52.999894)
		(stroke
			(width 0.2)
			(type default)
		)
		(layer "In3.Cu")
	)
	(gr_line
		(start 100.961444 -12.400026)
		(end 100.961444 -10.999978)
		(stroke
			(width 0.2)
			(type default)
		)
		(layer "In3.Cu")
	)
	(gr_arc
		(start 100.961444 -10.999978)
		(mid 100.400104 -10.438638)
		(end 99.838764 -10.999978)
		(stroke
			(width 0.2)
			(type default)
		)
		(layer "In3.Cu")
	)
	(gr_line
		(start 100.961444 -5.200142)
		(end 100.961444 -3.800094)
		(stroke
			(width 0.2)
			(type default)
		)
		(layer "In3.Cu")
	)
	(gr_arc
		(start 100.961444 -3.800094)
		(mid 100.400104 -3.238754)
		(end 99.838764 -3.800094)
		(stroke
			(width 0.2)
			(type default)
		)
		(layer "In3.Cu")
	)
	(gr_line
		(start 101.358192 -56.000142)
		(end 101.358192 -55.000144)
		(stroke
			(width 0.2)
			(type default)
		)
		(layer "In3.Cu")
	)
	(gr_arc
		(start 101.358192 -55.000144)
		(mid 101.000052 -54.642004)
		(end 100.641912 -55.000144)
		(stroke
			(width 0.2)
			(type default)
		)
		(layer "In3.Cu")
	)
	(gr_line
		(start 101.358192 -53.000148)
		(end 101.358192 -52.00015)
		(stroke
			(width 0.2)
			(type default)
		)
		(layer "In3.Cu")
	)
	(gr_arc
		(start 101.358192 -52.00015)
		(mid 101.000052 -51.64201)
		(end 100.641912 -52.00015)
		(stroke
			(width 0.2)
			(type default)
		)
		(layer "In3.Cu")
	)
	(gr_arc
		(start 101.638862 -11.199876)
		(mid 102.200075 -11.76147)
		(end 102.761542 -11.20013)
		(stroke
			(width 0.2)
			(type default)
		)
		(layer "In3.Cu")
	)
	(gr_line
		(start 101.638862 -9.800082)
		(end 101.638862 -11.199876)
		(stroke
			(width 0.2)
			(type default)
		)
		(layer "In3.Cu")
	)
	(gr_arc
		(start 101.638862 -3.999738)
		(mid 102.200075 -4.561332)
		(end 102.761542 -3.999992)
		(stroke
			(width 0.2)
			(type default)
		)
		(layer "In3.Cu")
	)
	(gr_line
		(start 101.638862 -2.600198)
		(end 101.638862 -3.999738)
		(stroke
			(width 0.2)
			(type default)
		)
		(layer "In3.Cu")
	)
	(gr_arc
		(start 101.64191 -55.999888)
		(mid 101.999923 -56.358282)
		(end 102.35819 -56.000142)
		(stroke
			(width 0.2)
			(type default)
		)
		(layer "In3.Cu")
	)
	(gr_line
		(start 101.64191 -55.000144)
		(end 101.64191 -55.999888)
		(stroke
			(width 0.2)
			(type default)
		)
		(layer "In3.Cu")
	)
	(gr_arc
		(start 101.64191 -51.999896)
		(mid 101.999923 -52.35829)
		(end 102.35819 -52.00015)
		(stroke
			(width 0.2)
			(type default)
		)
		(layer "In3.Cu")
	)
	(gr_line
		(start 101.64191 -51.000152)
		(end 101.64191 -51.999896)
		(stroke
			(width 0.2)
			(type default)
		)
		(layer "In3.Cu")
	)
	(gr_arc
		(start 102.266496 -115.990878)
		(mid 102.491032 -116.733574)
		(end 103.233728 -116.509038)
		(stroke
			(width 0.2)
			(type default)
		)
		(layer "In3.Cu")
	)
	(gr_line
		(start 102.266496 -115.990624)
		(end 102.266496 -115.990878)
		(stroke
			(width 0.2)
			(type default)
		)
		(layer "In3.Cu")
	)
	(gr_arc
		(start 102.266496 -112.191038)
		(mid 102.491032 -112.933734)
		(end 103.233728 -112.709198)
		(stroke
			(width 0.2)
			(type default)
		)
		(layer "In3.Cu")
	)
	(gr_line
		(start 102.266496 -112.190784)
		(end 102.266496 -112.191038)
		(stroke
			(width 0.2)
			(type default)
		)
		(layer "In3.Cu")
	)
	(gr_line
		(start 102.311454 -108.415074)
		(end 102.311962 -108.415328)
		(stroke
			(width 0.2)
			(type default)
		)
		(layer "In3.Cu")
	)
	(gr_line
		(start 102.311454 -108.41482)
		(end 102.311454 -108.415074)
		(stroke
			(width 0.2)
			(type default)
		)
		(layer "In3.Cu")
	)
	(gr_line
		(start 102.311454 -104.61498)
		(end 102.311962 -104.615234)
		(stroke
			(width 0.2)
			(type default)
		)
		(layer "In3.Cu")
	)
	(gr_line
		(start 102.311454 -104.614726)
		(end 102.311454 -104.61498)
		(stroke
			(width 0.2)
			(type default)
		)
		(layer "In3.Cu")
	)
	(gr_arc
		(start 102.311962 -108.415328)
		(mid 102.515416 -109.088174)
		(end 103.188262 -108.88472)
		(stroke
			(width 0.2)
			(type default)
		)
		(layer "In3.Cu")
	)
	(gr_arc
		(start 102.311962 -104.615234)
		(mid 102.515416 -105.28808)
		(end 103.188262 -105.084626)
		(stroke
			(width 0.2)
			(type default)
		)
		(layer "In3.Cu")
	)
	(gr_line
		(start 102.35819 -56.000142)
		(end 102.35819 -55.000144)
		(stroke
			(width 0.2)
			(type default)
		)
		(layer "In3.Cu")
	)
	(gr_arc
		(start 102.35819 -55.000144)
		(mid 102.00005 -54.642004)
		(end 101.64191 -55.000144)
		(stroke
			(width 0.2)
			(type default)
		)
		(layer "In3.Cu")
	)
	(gr_line
		(start 102.35819 -52.00015)
		(end 102.35819 -51.000152)
		(stroke
			(width 0.2)
			(type default)
		)
		(layer "In3.Cu")
	)
	(gr_arc
		(start 102.35819 -51.000152)
		(mid 102.00005 -50.642012)
		(end 101.64191 -51.000152)
		(stroke
			(width 0.2)
			(type default)
		)
		(layer "In3.Cu")
	)
	(gr_arc
		(start 102.641908 -55.999888)
		(mid 102.999921 -56.358282)
		(end 103.358188 -56.000142)
		(stroke
			(width 0.2)
			(type default)
		)
		(layer "In3.Cu")
	)
	(gr_line
		(start 102.641908 -55.000144)
		(end 102.641908 -55.999888)
		(stroke
			(width 0.2)
			(type default)
		)
		(layer "In3.Cu")
	)
	(gr_arc
		(start 102.641908 -52.999894)
		(mid 102.999921 -53.358288)
		(end 103.358188 -53.000148)
		(stroke
			(width 0.2)
			(type default)
		)
		(layer "In3.Cu")
	)
	(gr_line
		(start 102.641908 -52.00015)
		(end 102.641908 -52.999894)
		(stroke
			(width 0.2)
			(type default)
		)
		(layer "In3.Cu")
	)
	(gr_line
		(start 102.761542 -11.20013)
		(end 102.761542 -9.800082)
		(stroke
			(width 0.2)
			(type default)
		)
		(layer "In3.Cu")
	)
	(gr_arc
		(start 102.761542 -9.800082)
		(mid 102.200202 -9.238742)
		(end 101.638862 -9.800082)
		(stroke
			(width 0.2)
			(type default)
		)
		(layer "In3.Cu")
	)
	(gr_line
		(start 102.761542 -3.999992)
		(end 102.761542 -2.600198)
		(stroke
			(width 0.2)
			(type default)
		)
		(layer "In3.Cu")
	)
	(gr_arc
		(start 102.761542 -2.600198)
		(mid 102.200202 -2.038858)
		(end 101.638862 -2.600198)
		(stroke
			(width 0.2)
			(type default)
		)
		(layer "In3.Cu")
	)
	(gr_line
		(start 103.016304 -114.59083)
		(end 102.266496 -115.990624)
		(stroke
			(width 0.2)
			(type default)
		)
		(layer "In3.Cu")
	)
	(gr_line
		(start 103.016304 -110.79099)
		(end 102.266496 -112.190784)
		(stroke
			(width 0.2)
			(type default)
		)
		(layer "In3.Cu")
	)
	(gr_line
		(start 103.061008 -107.015026)
		(end 102.311454 -108.41482)
		(stroke
			(width 0.2)
			(type default)
		)
		(layer "In3.Cu")
	)
	(gr_line
		(start 103.061008 -103.215186)
		(end 102.311454 -104.614726)
		(stroke
			(width 0.2)
			(type default)
		)
		(layer "In3.Cu")
	)
	(gr_line
		(start 103.06177 -107.01528)
		(end 103.061008 -107.015026)
		(stroke
			(width 0.2)
			(type default)
		)
		(layer "In3.Cu")
	)
	(gr_line
		(start 103.06177 -103.21544)
		(end 103.061008 -103.215186)
		(stroke
			(width 0.2)
			(type default)
		)
		(layer "In3.Cu")
	)
	(gr_line
		(start 103.188262 -108.88472)
		(end 103.189024 -108.884974)
		(stroke
			(width 0.2)
			(type default)
		)
		(layer "In3.Cu")
	)
	(gr_line
		(start 103.188262 -105.084626)
		(end 103.189024 -105.08488)
		(stroke
			(width 0.2)
			(type default)
		)
		(layer "In3.Cu")
	)
	(gr_line
		(start 103.189024 -108.884974)
		(end 103.938832 -107.484926)
		(stroke
			(width 0.2)
			(type default)
		)
		(layer "In3.Cu")
	)
	(gr_line
		(start 103.189024 -105.08488)
		(end 103.938832 -103.685086)
		(stroke
			(width 0.2)
			(type default)
		)
		(layer "In3.Cu")
	)
	(gr_line
		(start 103.233728 -116.509038)
		(end 103.983536 -115.10899)
		(stroke
			(width 0.2)
			(type default)
		)
		(layer "In3.Cu")
	)
	(gr_line
		(start 103.233728 -112.709198)
		(end 103.983536 -111.30915)
		(stroke
			(width 0.2)
			(type default)
		)
		(layer "In3.Cu")
	)
	(gr_line
		(start 103.358188 -56.000142)
		(end 103.358188 -55.000144)
		(stroke
			(width 0.2)
			(type default)
		)
		(layer "In3.Cu")
	)
	(gr_arc
		(start 103.358188 -55.000144)
		(mid 103.000048 -54.642004)
		(end 102.641908 -55.000144)
		(stroke
			(width 0.2)
			(type default)
		)
		(layer "In3.Cu")
	)
	(gr_line
		(start 103.358188 -53.000148)
		(end 103.358188 -52.00015)
		(stroke
			(width 0.2)
			(type default)
		)
		(layer "In3.Cu")
	)
	(gr_arc
		(start 103.358188 -52.00015)
		(mid 103.000048 -51.64201)
		(end 102.641908 -52.00015)
		(stroke
			(width 0.2)
			(type default)
		)
		(layer "In3.Cu")
	)
	(gr_arc
		(start 103.438706 -12.399772)
		(mid 103.999919 -12.961366)
		(end 104.561386 -12.400026)
		(stroke
			(width 0.2)
			(type default)
		)
		(layer "In3.Cu")
	)
	(gr_line
		(start 103.438706 -10.999978)
		(end 103.438706 -12.399772)
		(stroke
			(width 0.2)
			(type default)
		)
		(layer "In3.Cu")
	)
	(gr_arc
		(start 103.438706 -5.199888)
		(mid 103.999919 -5.761482)
		(end 104.561386 -5.200142)
		(stroke
			(width 0.2)
			(type default)
		)
		(layer "In3.Cu")
	)
	(gr_line
		(start 103.438706 -3.800094)
		(end 103.438706 -5.199888)
		(stroke
			(width 0.2)
			(type default)
		)
		(layer "In3.Cu")
	)
	(gr_arc
		(start 103.641906 -55.999888)
		(mid 103.999919 -56.358282)
		(end 104.358186 -56.000142)
		(stroke
			(width 0.2)
			(type default)
		)
		(layer "In3.Cu")
	)
	(gr_line
		(start 103.641906 -55.000144)
		(end 103.641906 -55.999888)
		(stroke
			(width 0.2)
			(type default)
		)
		(layer "In3.Cu")
	)
	(gr_arc
		(start 103.641906 -51.999896)
		(mid 103.999919 -52.35829)
		(end 104.358186 -52.00015)
		(stroke
			(width 0.2)
			(type default)
		)
		(layer "In3.Cu")
	)
	(gr_line
		(start 103.641906 -51.000152)
		(end 103.641906 -51.999896)
		(stroke
			(width 0.2)
			(type default)
		)
		(layer "In3.Cu")
	)
	(gr_arc
		(start 103.93807 -107.484672)
		(mid 103.734616 -106.811826)
		(end 103.06177 -107.01528)
		(stroke
			(width 0.2)
			(type default)
		)
		(layer "In3.Cu")
	)
	(gr_arc
		(start 103.93807 -103.684832)
		(mid 103.734616 -103.011986)
		(end 103.06177 -103.21544)
		(stroke
			(width 0.2)
			(type default)
		)
		(layer "In3.Cu")
	)
	(gr_line
		(start 103.938832 -107.484926)
		(end 103.93807 -107.484672)
		(stroke
			(width 0.2)
			(type default)
		)
		(layer "In3.Cu")
	)
	(gr_line
		(start 103.938832 -103.685086)
		(end 103.93807 -103.684832)
		(stroke
			(width 0.2)
			(type default)
		)
		(layer "In3.Cu")
	)
	(gr_arc
		(start 103.983536 -115.10899)
		(mid 103.759 -114.366294)
		(end 103.016304 -114.59083)
		(stroke
			(width 0.2)
			(type default)
		)
		(layer "In3.Cu")
	)
	(gr_arc
		(start 103.983536 -111.30915)
		(mid 103.759 -110.566454)
		(end 103.016304 -110.79099)
		(stroke
			(width 0.2)
			(type default)
		)
		(layer "In3.Cu")
	)
	(gr_line
		(start 104.358186 -56.000142)
		(end 104.358186 -55.000144)
		(stroke
			(width 0.2)
			(type default)
		)
		(layer "In3.Cu")
	)
	(gr_arc
		(start 104.358186 -55.000144)
		(mid 104.000046 -54.642004)
		(end 103.641906 -55.000144)
		(stroke
			(width 0.2)
			(type default)
		)
		(layer "In3.Cu")
	)
	(gr_line
		(start 104.358186 -52.00015)
		(end 104.358186 -51.000152)
		(stroke
			(width 0.2)
			(type default)
		)
		(layer "In3.Cu")
	)
	(gr_arc
		(start 104.358186 -51.000152)
		(mid 104.000046 -50.642012)
		(end 103.641906 -51.000152)
		(stroke
			(width 0.2)
			(type default)
		)
		(layer "In3.Cu")
	)
	(gr_arc
		(start 104.516428 -115.990624)
		(mid 104.740809 -116.733627)
		(end 105.48366 -116.509038)
		(stroke
			(width 0.2)
			(type default)
		)
		(layer "In3.Cu")
	)
	(gr_arc
		(start 104.516428 -112.190784)
		(mid 104.740809 -112.933787)
		(end 105.48366 -112.709198)
		(stroke
			(width 0.2)
			(type default)
		)
		(layer "In3.Cu")
	)
	(gr_line
		(start 104.561386 -108.415074)
		(end 104.561894 -108.415328)
		(stroke
			(width 0.2)
			(type default)
		)
		(layer "In3.Cu")
	)
	(gr_line
		(start 104.561386 -108.41482)
		(end 104.561386 -108.415074)
		(stroke
			(width 0.2)
			(type default)
		)
		(layer "In3.Cu")
	)
	(gr_line
		(start 104.561386 -104.61498)
		(end 104.561894 -104.615234)
		(stroke
			(width 0.2)
			(type default)
		)
		(layer "In3.Cu")
	)
	(gr_line
		(start 104.561386 -104.614472)
		(end 104.561386 -104.61498)
		(stroke
			(width 0.2)
			(type default)
		)
		(layer "In3.Cu")
	)
	(gr_line
		(start 104.561386 -12.400026)
		(end 104.561386 -10.999978)
		(stroke
			(width 0.2)
			(type default)
		)
		(layer "In3.Cu")
	)
	(gr_arc
		(start 104.561386 -10.999978)
		(mid 104.000046 -10.438638)
		(end 103.438706 -10.999978)
		(stroke
			(width 0.2)
			(type default)
		)
		(layer "In3.Cu")
	)
	(gr_line
		(start 104.561386 -5.200142)
		(end 104.561386 -3.800094)
		(stroke
			(width 0.2)
			(type default)
		)
		(layer "In3.Cu")
	)
	(gr_arc
		(start 104.561386 -3.800094)
		(mid 104.000046 -3.238754)
		(end 103.438706 -3.800094)
		(stroke
			(width 0.2)
			(type default)
		)
		(layer "In3.Cu")
	)
	(gr_arc
		(start 104.561894 -108.415328)
		(mid 104.765348 -109.088174)
		(end 105.438194 -108.88472)
		(stroke
			(width 0.2)
			(type default)
		)
		(layer "In3.Cu")
	)
	(gr_arc
		(start 104.561894 -104.615234)
		(mid 104.765348 -105.28808)
		(end 105.438194 -105.084626)
		(stroke
			(width 0.2)
			(type default)
		)
		(layer "In3.Cu")
	)
	(gr_arc
		(start 104.641904 -55.999888)
		(mid 104.999917 -56.358282)
		(end 105.358184 -56.000142)
		(stroke
			(width 0.2)
			(type default)
		)
		(layer "In3.Cu")
	)
	(gr_line
		(start 104.641904 -55.000144)
		(end 104.641904 -55.999888)
		(stroke
			(width 0.2)
			(type default)
		)
		(layer "In3.Cu")
	)
	(gr_arc
		(start 104.641904 -52.999894)
		(mid 104.999917 -53.358288)
		(end 105.358184 -53.000148)
		(stroke
			(width 0.2)
			(type default)
		)
		(layer "In3.Cu")
	)
	(gr_line
		(start 104.641904 -52.00015)
		(end 104.641904 -52.999894)
		(stroke
			(width 0.2)
			(type default)
		)
		(layer "In3.Cu")
	)
	(gr_arc
		(start 105.238804 -11.199876)
		(mid 105.800017 -11.76147)
		(end 106.361484 -11.20013)
		(stroke
			(width 0.2)
			(type default)
		)
		(layer "In3.Cu")
	)
	(gr_line
		(start 105.238804 -9.800082)
		(end 105.238804 -11.199876)
		(stroke
			(width 0.2)
			(type default)
		)
		(layer "In3.Cu")
	)
	(gr_arc
		(start 105.238804 -3.999738)
		(mid 105.800017 -4.561332)
		(end 106.361484 -3.999992)
		(stroke
			(width 0.2)
			(type default)
		)
		(layer "In3.Cu")
	)
	(gr_line
		(start 105.238804 -2.600198)
		(end 105.238804 -3.999738)
		(stroke
			(width 0.2)
			(type default)
		)
		(layer "In3.Cu")
	)
	(gr_line
		(start 105.26649 -114.59083)
		(end 104.516428 -115.990624)
		(stroke
			(width 0.2)
			(type default)
		)
		(layer "In3.Cu")
	)
	(gr_line
		(start 105.26649 -110.79099)
		(end 104.516428 -112.190784)
		(stroke
			(width 0.2)
			(type default)
		)
		(layer "In3.Cu")
	)
	(gr_line
		(start 105.311194 -107.014772)
		(end 104.561386 -108.41482)
		(stroke
			(width 0.2)
			(type default)
		)
		(layer "In3.Cu")
	)
	(gr_line
		(start 105.311194 -103.214932)
		(end 104.561386 -104.614472)
		(stroke
			(width 0.2)
			(type default)
		)
		(layer "In3.Cu")
	)
	(gr_line
		(start 105.311956 -107.01528)
		(end 105.311194 -107.014772)
		(stroke
			(width 0.2)
			(type default)
		)
		(layer "In3.Cu")
	)
	(gr_line
		(start 105.311956 -103.21544)
		(end 105.311194 -103.214932)
		(stroke
			(width 0.2)
			(type default)
		)
		(layer "In3.Cu")
	)
	(gr_line
		(start 105.358184 -56.000142)
		(end 105.358184 -55.000144)
		(stroke
			(width 0.2)
			(type default)
		)
		(layer "In3.Cu")
	)
	(gr_arc
		(start 105.358184 -55.000144)
		(mid 105.000044 -54.642004)
		(end 104.641904 -55.000144)
		(stroke
			(width 0.2)
			(type default)
		)
		(layer "In3.Cu")
	)
	(gr_line
		(start 105.358184 -53.000148)
		(end 105.358184 -52.00015)
		(stroke
			(width 0.2)
			(type default)
		)
		(layer "In3.Cu")
	)
	(gr_arc
		(start 105.358184 -52.00015)
		(mid 105.000044 -51.64201)
		(end 104.641904 -52.00015)
		(stroke
			(width 0.2)
			(type default)
		)
		(layer "In3.Cu")
	)
	(gr_line
		(start 105.438194 -108.88472)
		(end 105.438956 -108.885228)
		(stroke
			(width 0.2)
			(type default)
		)
		(layer "In3.Cu")
	)
	(gr_line
		(start 105.438194 -105.084626)
		(end 105.438956 -105.085134)
		(stroke
			(width 0.2)
			(type default)
		)
		(layer "In3.Cu")
	)
	(gr_line
		(start 105.438956 -108.885228)
		(end 106.189018 -107.48518)
		(stroke
			(width 0.2)
			(type default)
		)
		(layer "In3.Cu")
	)
	(gr_line
		(start 105.438956 -105.085134)
		(end 106.189018 -103.68534)
		(stroke
			(width 0.2)
			(type default)
		)
		(layer "In3.Cu")
	)
	(gr_line
		(start 105.48366 -116.509038)
		(end 106.233722 -115.10899)
		(stroke
			(width 0.2)
			(type default)
		)
		(layer "In3.Cu")
	)
	(gr_line
		(start 105.48366 -112.709198)
		(end 106.233722 -111.30915)
		(stroke
			(width 0.2)
			(type default)
		)
		(layer "In3.Cu")
	)
	(gr_arc
		(start 105.641902 -55.999888)
		(mid 105.999915 -56.358282)
		(end 106.358182 -56.000142)
		(stroke
			(width 0.2)
			(type default)
		)
		(layer "In3.Cu")
	)
	(gr_line
		(start 105.641902 -55.000144)
		(end 105.641902 -55.999888)
		(stroke
			(width 0.2)
			(type default)
		)
		(layer "In3.Cu")
	)
	(gr_arc
		(start 105.641902 -51.999896)
		(mid 105.999915 -52.35829)
		(end 106.358182 -52.00015)
		(stroke
			(width 0.2)
			(type default)
		)
		(layer "In3.Cu")
	)
	(gr_line
		(start 105.641902 -51.000152)
		(end 105.641902 -51.999896)
		(stroke
			(width 0.2)
			(type default)
		)
		(layer "In3.Cu")
	)
	(gr_arc
		(start 106.188256 -107.484672)
		(mid 105.984802 -106.811826)
		(end 105.311956 -107.01528)
		(stroke
			(width 0.2)
			(type default)
		)
		(layer "In3.Cu")
	)
	(gr_arc
		(start 106.188256 -103.684832)
		(mid 105.984802 -103.011986)
		(end 105.311956 -103.21544)
		(stroke
			(width 0.2)
			(type default)
		)
		(layer "In3.Cu")
	)
	(gr_line
		(start 106.189018 -107.48518)
		(end 106.188256 -107.484672)
		(stroke
			(width 0.2)
			(type default)
		)
		(layer "In3.Cu")
	)
	(gr_line
		(start 106.189018 -103.68534)
		(end 106.188256 -103.684832)
		(stroke
			(width 0.2)
			(type default)
		)
		(layer "In3.Cu")
	)
	(gr_arc
		(start 106.233722 -115.10899)
		(mid 106.009186 -114.366294)
		(end 105.26649 -114.59083)
		(stroke
			(width 0.2)
			(type default)
		)
		(layer "In3.Cu")
	)
	(gr_arc
		(start 106.233722 -111.30915)
		(mid 106.009186 -110.566454)
		(end 105.26649 -110.79099)
		(stroke
			(width 0.2)
			(type default)
		)
		(layer "In3.Cu")
	)
	(gr_line
		(start 106.358182 -56.000142)
		(end 106.358182 -55.000144)
		(stroke
			(width 0.2)
			(type default)
		)
		(layer "In3.Cu")
	)
	(gr_arc
		(start 106.358182 -55.000144)
		(mid 106.000042 -54.642004)
		(end 105.641902 -55.000144)
		(stroke
			(width 0.2)
			(type default)
		)
		(layer "In3.Cu")
	)
	(gr_line
		(start 106.358182 -52.00015)
		(end 106.358182 -51.000152)
		(stroke
			(width 0.2)
			(type default)
		)
		(layer "In3.Cu")
	)
	(gr_arc
		(start 106.358182 -51.000152)
		(mid 106.000042 -50.642012)
		(end 105.641902 -51.000152)
		(stroke
			(width 0.2)
			(type default)
		)
		(layer "In3.Cu")
	)
	(gr_line
		(start 106.361484 -11.20013)
		(end 106.361484 -9.800082)
		(stroke
			(width 0.2)
			(type default)
		)
		(layer "In3.Cu")
	)
	(gr_arc
		(start 106.361484 -9.800082)
		(mid 105.800144 -9.238742)
		(end 105.238804 -9.800082)
		(stroke
			(width 0.2)
			(type default)
		)
		(layer "In3.Cu")
	)
	(gr_line
		(start 106.361484 -3.999992)
		(end 106.361484 -2.600198)
		(stroke
			(width 0.2)
			(type default)
		)
		(layer "In3.Cu")
	)
	(gr_arc
		(start 106.361484 -2.600198)
		(mid 105.800144 -2.038858)
		(end 105.238804 -2.600198)
		(stroke
			(width 0.2)
			(type default)
		)
		(layer "In3.Cu")
	)
	(gr_arc
		(start 106.6419 -55.999888)
		(mid 106.999913 -56.358282)
		(end 107.35818 -56.000142)
		(stroke
			(width 0.2)
			(type default)
		)
		(layer "In3.Cu")
	)
	(gr_line
		(start 106.6419 -55.000144)
		(end 106.6419 -55.999888)
		(stroke
			(width 0.2)
			(type default)
		)
		(layer "In3.Cu")
	)
	(gr_arc
		(start 106.6419 -52.999894)
		(mid 106.999913 -53.358288)
		(end 107.35818 -53.000148)
		(stroke
			(width 0.2)
			(type default)
		)
		(layer "In3.Cu")
	)
	(gr_line
		(start 106.6419 -52.00015)
		(end 106.6419 -52.999894)
		(stroke
			(width 0.2)
			(type default)
		)
		(layer "In3.Cu")
	)
	(gr_arc
		(start 107.038648 -12.399772)
		(mid 107.599861 -12.961366)
		(end 108.161328 -12.400026)
		(stroke
			(width 0.2)
			(type default)
		)
		(layer "In3.Cu")
	)
	(gr_line
		(start 107.038648 -10.999978)
		(end 107.038648 -12.399772)
		(stroke
			(width 0.2)
			(type default)
		)
		(layer "In3.Cu")
	)
	(gr_arc
		(start 107.038648 -5.199888)
		(mid 107.599861 -5.761482)
		(end 108.161328 -5.200142)
		(stroke
			(width 0.2)
			(type default)
		)
		(layer "In3.Cu")
	)
	(gr_line
		(start 107.038648 -3.800094)
		(end 107.038648 -5.199888)
		(stroke
			(width 0.2)
			(type default)
		)
		(layer "In3.Cu")
	)
	(gr_line
		(start 107.35818 -56.000142)
		(end 107.35818 -55.000144)
		(stroke
			(width 0.2)
			(type default)
		)
		(layer "In3.Cu")
	)
	(gr_arc
		(start 107.35818 -55.000144)
		(mid 107.00004 -54.642004)
		(end 106.6419 -55.000144)
		(stroke
			(width 0.2)
			(type default)
		)
		(layer "In3.Cu")
	)
	(gr_line
		(start 107.35818 -53.000148)
		(end 107.35818 -52.00015)
		(stroke
			(width 0.2)
			(type default)
		)
		(layer "In3.Cu")
	)
	(gr_arc
		(start 107.35818 -52.00015)
		(mid 107.00004 -51.64201)
		(end 106.6419 -52.00015)
		(stroke
			(width 0.2)
			(type default)
		)
		(layer "In3.Cu")
	)
	(gr_arc
		(start 107.641898 -55.999888)
		(mid 107.999911 -56.358282)
		(end 108.358178 -56.000142)
		(stroke
			(width 0.2)
			(type default)
		)
		(layer "In3.Cu")
	)
	(gr_line
		(start 107.641898 -55.000144)
		(end 107.641898 -55.999888)
		(stroke
			(width 0.2)
			(type default)
		)
		(layer "In3.Cu")
	)
	(gr_arc
		(start 107.641898 -51.999896)
		(mid 107.999911 -52.35829)
		(end 108.358178 -52.00015)
		(stroke
			(width 0.2)
			(type default)
		)
		(layer "In3.Cu")
	)
	(gr_line
		(start 107.641898 -51.000152)
		(end 107.641898 -51.999896)
		(stroke
			(width 0.2)
			(type default)
		)
		(layer "In3.Cu")
	)
	(gr_line
		(start 108.161328 -12.400026)
		(end 108.161328 -10.999978)
		(stroke
			(width 0.2)
			(type default)
		)
		(layer "In3.Cu")
	)
	(gr_arc
		(start 108.161328 -10.999978)
		(mid 107.599988 -10.438638)
		(end 107.038648 -10.999978)
		(stroke
			(width 0.2)
			(type default)
		)
		(layer "In3.Cu")
	)
	(gr_line
		(start 108.161328 -5.200142)
		(end 108.161328 -3.800094)
		(stroke
			(width 0.2)
			(type default)
		)
		(layer "In3.Cu")
	)
	(gr_arc
		(start 108.161328 -3.800094)
		(mid 107.599988 -3.238754)
		(end 107.038648 -3.800094)
		(stroke
			(width 0.2)
			(type default)
		)
		(layer "In3.Cu")
	)
	(gr_line
		(start 108.358178 -56.000142)
		(end 108.358178 -55.000144)
		(stroke
			(width 0.2)
			(type default)
		)
		(layer "In3.Cu")
	)
	(gr_arc
		(start 108.358178 -55.000144)
		(mid 108.000038 -54.642004)
		(end 107.641898 -55.000144)
		(stroke
			(width 0.2)
			(type default)
		)
		(layer "In3.Cu")
	)
	(gr_line
		(start 108.358178 -52.00015)
		(end 108.358178 -51.000152)
		(stroke
			(width 0.2)
			(type default)
		)
		(layer "In3.Cu")
	)
	(gr_arc
		(start 108.358178 -51.000152)
		(mid 108.000038 -50.642012)
		(end 107.641898 -51.000152)
		(stroke
			(width 0.2)
			(type default)
		)
		(layer "In3.Cu")
	)
	(gr_arc
		(start 108.641896 -55.999888)
		(mid 108.999909 -56.358282)
		(end 109.358176 -56.000142)
		(stroke
			(width 0.2)
			(type default)
		)
		(layer "In3.Cu")
	)
	(gr_line
		(start 108.641896 -55.000144)
		(end 108.641896 -55.999888)
		(stroke
			(width 0.2)
			(type default)
		)
		(layer "In3.Cu")
	)
	(gr_arc
		(start 108.641896 -52.999894)
		(mid 108.999909 -53.358288)
		(end 109.358176 -53.000148)
		(stroke
			(width 0.2)
			(type default)
		)
		(layer "In3.Cu")
	)
	(gr_line
		(start 108.641896 -52.00015)
		(end 108.641896 -52.999894)
		(stroke
			(width 0.2)
			(type default)
		)
		(layer "In3.Cu")
	)
	(gr_arc
		(start 108.838746 -11.199876)
		(mid 109.399959 -11.76147)
		(end 109.961426 -11.20013)
		(stroke
			(width 0.2)
			(type default)
		)
		(layer "In3.Cu")
	)
	(gr_line
		(start 108.838746 -9.800082)
		(end 108.838746 -11.199876)
		(stroke
			(width 0.2)
			(type default)
		)
		(layer "In3.Cu")
	)
	(gr_arc
		(start 108.838746 -3.999738)
		(mid 109.399959 -4.561332)
		(end 109.961426 -3.999992)
		(stroke
			(width 0.2)
			(type default)
		)
		(layer "In3.Cu")
	)
	(gr_line
		(start 108.838746 -2.600198)
		(end 108.838746 -3.999738)
		(stroke
			(width 0.2)
			(type default)
		)
		(layer "In3.Cu")
	)
	(gr_line
		(start 109.358176 -56.000142)
		(end 109.358176 -55.000144)
		(stroke
			(width 0.2)
			(type default)
		)
		(layer "In3.Cu")
	)
	(gr_arc
		(start 109.358176 -55.000144)
		(mid 109.000036 -54.642004)
		(end 108.641896 -55.000144)
		(stroke
			(width 0.2)
			(type default)
		)
		(layer "In3.Cu")
	)
	(gr_line
		(start 109.358176 -53.000148)
		(end 109.358176 -52.00015)
		(stroke
			(width 0.2)
			(type default)
		)
		(layer "In3.Cu")
	)
	(gr_arc
		(start 109.358176 -52.00015)
		(mid 109.000036 -51.64201)
		(end 108.641896 -52.00015)
		(stroke
			(width 0.2)
			(type default)
		)
		(layer "In3.Cu")
	)
	(gr_arc
		(start 109.641894 -55.999888)
		(mid 109.999907 -56.358282)
		(end 110.358174 -56.000142)
		(stroke
			(width 0.2)
			(type default)
		)
		(layer "In3.Cu")
	)
	(gr_line
		(start 109.641894 -55.000144)
		(end 109.641894 -55.999888)
		(stroke
			(width 0.2)
			(type default)
		)
		(layer "In3.Cu")
	)
	(gr_arc
		(start 109.641894 -51.999896)
		(mid 109.999907 -52.35829)
		(end 110.358174 -52.00015)
		(stroke
			(width 0.2)
			(type default)
		)
		(layer "In3.Cu")
	)
	(gr_line
		(start 109.641894 -51.000152)
		(end 109.641894 -51.999896)
		(stroke
			(width 0.2)
			(type default)
		)
		(layer "In3.Cu")
	)
	(gr_line
		(start 109.961426 -11.20013)
		(end 109.961426 -9.800082)
		(stroke
			(width 0.2)
			(type default)
		)
		(layer "In3.Cu")
	)
	(gr_arc
		(start 109.961426 -9.800082)
		(mid 109.400086 -9.238742)
		(end 108.838746 -9.800082)
		(stroke
			(width 0.2)
			(type default)
		)
		(layer "In3.Cu")
	)
	(gr_line
		(start 109.961426 -3.999992)
		(end 109.961426 -2.600198)
		(stroke
			(width 0.2)
			(type default)
		)
		(layer "In3.Cu")
	)
	(gr_arc
		(start 109.961426 -2.600198)
		(mid 109.400086 -2.038858)
		(end 108.838746 -2.600198)
		(stroke
			(width 0.2)
			(type default)
		)
		(layer "In3.Cu")
	)
	(gr_line
		(start 110.358174 -56.000142)
		(end 110.358174 -55.000144)
		(stroke
			(width 0.2)
			(type default)
		)
		(layer "In3.Cu")
	)
	(gr_arc
		(start 110.358174 -55.000144)
		(mid 110.000034 -54.642004)
		(end 109.641894 -55.000144)
		(stroke
			(width 0.2)
			(type default)
		)
		(layer "In3.Cu")
	)
	(gr_line
		(start 110.358174 -52.00015)
		(end 110.358174 -51.000152)
		(stroke
			(width 0.2)
			(type default)
		)
		(layer "In3.Cu")
	)
	(gr_arc
		(start 110.358174 -51.000152)
		(mid 110.000034 -50.642012)
		(end 109.641894 -51.000152)
		(stroke
			(width 0.2)
			(type default)
		)
		(layer "In3.Cu")
	)
	(gr_arc
		(start 110.638844 -12.399772)
		(mid 111.200057 -12.961366)
		(end 111.761524 -12.400026)
		(stroke
			(width 0.2)
			(type default)
		)
		(layer "In3.Cu")
	)
	(gr_line
		(start 110.638844 -10.999978)
		(end 110.638844 -12.399772)
		(stroke
			(width 0.2)
			(type default)
		)
		(layer "In3.Cu")
	)
	(gr_arc
		(start 110.638844 -5.199888)
		(mid 111.200057 -5.761482)
		(end 111.761524 -5.200142)
		(stroke
			(width 0.2)
			(type default)
		)
		(layer "In3.Cu")
	)
	(gr_line
		(start 110.638844 -3.800094)
		(end 110.638844 -5.199888)
		(stroke
			(width 0.2)
			(type default)
		)
		(layer "In3.Cu")
	)
	(gr_arc
		(start 110.641892 -55.999888)
		(mid 110.999905 -56.358282)
		(end 111.358172 -56.000142)
		(stroke
			(width 0.2)
			(type default)
		)
		(layer "In3.Cu")
	)
	(gr_line
		(start 110.641892 -55.000144)
		(end 110.641892 -55.999888)
		(stroke
			(width 0.2)
			(type default)
		)
		(layer "In3.Cu")
	)
	(gr_arc
		(start 110.641892 -52.999894)
		(mid 110.999905 -53.358288)
		(end 111.358172 -53.000148)
		(stroke
			(width 0.2)
			(type default)
		)
		(layer "In3.Cu")
	)
	(gr_line
		(start 110.641892 -52.00015)
		(end 110.641892 -52.999894)
		(stroke
			(width 0.2)
			(type default)
		)
		(layer "In3.Cu")
	)
	(gr_line
		(start 111.358172 -56.000142)
		(end 111.358172 -55.000144)
		(stroke
			(width 0.2)
			(type default)
		)
		(layer "In3.Cu")
	)
	(gr_arc
		(start 111.358172 -55.000144)
		(mid 111.000032 -54.642004)
		(end 110.641892 -55.000144)
		(stroke
			(width 0.2)
			(type default)
		)
		(layer "In3.Cu")
	)
	(gr_line
		(start 111.358172 -53.000148)
		(end 111.358172 -52.00015)
		(stroke
			(width 0.2)
			(type default)
		)
		(layer "In3.Cu")
	)
	(gr_arc
		(start 111.358172 -52.00015)
		(mid 111.000032 -51.64201)
		(end 110.641892 -52.00015)
		(stroke
			(width 0.2)
			(type default)
		)
		(layer "In3.Cu")
	)
	(gr_arc
		(start 111.64189 -55.999888)
		(mid 111.999903 -56.358282)
		(end 112.35817 -56.000142)
		(stroke
			(width 0.2)
			(type default)
		)
		(layer "In3.Cu")
	)
	(gr_line
		(start 111.64189 -55.000144)
		(end 111.64189 -55.999888)
		(stroke
			(width 0.2)
			(type default)
		)
		(layer "In3.Cu")
	)
	(gr_arc
		(start 111.64189 -51.999896)
		(mid 111.999903 -52.35829)
		(end 112.35817 -52.00015)
		(stroke
			(width 0.2)
			(type default)
		)
		(layer "In3.Cu")
	)
	(gr_line
		(start 111.64189 -51.000152)
		(end 111.64189 -51.999896)
		(stroke
			(width 0.2)
			(type default)
		)
		(layer "In3.Cu")
	)
	(gr_line
		(start 111.761524 -12.400026)
		(end 111.761524 -10.999978)
		(stroke
			(width 0.2)
			(type default)
		)
		(layer "In3.Cu")
	)
	(gr_arc
		(start 111.761524 -10.999978)
		(mid 111.200184 -10.438638)
		(end 110.638844 -10.999978)
		(stroke
			(width 0.2)
			(type default)
		)
		(layer "In3.Cu")
	)
	(gr_line
		(start 111.761524 -5.200142)
		(end 111.761524 -3.800094)
		(stroke
			(width 0.2)
			(type default)
		)
		(layer "In3.Cu")
	)
	(gr_arc
		(start 111.761524 -3.800094)
		(mid 111.200184 -3.238754)
		(end 110.638844 -3.800094)
		(stroke
			(width 0.2)
			(type default)
		)
		(layer "In3.Cu")
	)
	(gr_line
		(start 112.35817 -56.000142)
		(end 112.35817 -55.000144)
		(stroke
			(width 0.2)
			(type default)
		)
		(layer "In3.Cu")
	)
	(gr_arc
		(start 112.35817 -55.000144)
		(mid 112.00003 -54.642004)
		(end 111.64189 -55.000144)
		(stroke
			(width 0.2)
			(type default)
		)
		(layer "In3.Cu")
	)
	(gr_line
		(start 112.35817 -52.00015)
		(end 112.35817 -51.000152)
		(stroke
			(width 0.2)
			(type default)
		)
		(layer "In3.Cu")
	)
	(gr_arc
		(start 112.35817 -51.000152)
		(mid 112.00003 -50.642012)
		(end 111.64189 -51.000152)
		(stroke
			(width 0.2)
			(type default)
		)
		(layer "In3.Cu")
	)
	(gr_arc
		(start 112.438688 -11.199876)
		(mid 112.999901 -11.76147)
		(end 113.561368 -11.20013)
		(stroke
			(width 0.2)
			(type default)
		)
		(layer "In3.Cu")
	)
	(gr_line
		(start 112.438688 -9.800082)
		(end 112.438688 -11.199876)
		(stroke
			(width 0.2)
			(type default)
		)
		(layer "In3.Cu")
	)
	(gr_arc
		(start 112.438688 -3.999738)
		(mid 112.999901 -4.561332)
		(end 113.561368 -3.999992)
		(stroke
			(width 0.2)
			(type default)
		)
		(layer "In3.Cu")
	)
	(gr_line
		(start 112.438688 -2.600198)
		(end 112.438688 -3.999738)
		(stroke
			(width 0.2)
			(type default)
		)
		(layer "In3.Cu")
	)
	(gr_line
		(start 112.499902 -126.000002)
		(end 97.499932 -126.000002)
		(stroke
			(width 2.54)
			(type default)
		)
		(layer "In3.Cu")
	)
	(gr_arc
		(start 112.641888 -55.999888)
		(mid 112.999901 -56.358282)
		(end 113.358168 -56.000142)
		(stroke
			(width 0.2)
			(type default)
		)
		(layer "In3.Cu")
	)
	(gr_line
		(start 112.641888 -55.000144)
		(end 112.641888 -55.999888)
		(stroke
			(width 0.2)
			(type default)
		)
		(layer "In3.Cu")
	)
	(gr_arc
		(start 112.641888 -52.999894)
		(mid 112.999901 -53.358288)
		(end 113.358168 -53.000148)
		(stroke
			(width 0.2)
			(type default)
		)
		(layer "In3.Cu")
	)
	(gr_line
		(start 112.641888 -52.00015)
		(end 112.641888 -52.999894)
		(stroke
			(width 0.2)
			(type default)
		)
		(layer "In3.Cu")
	)
	(gr_line
		(start 113.358168 -56.000142)
		(end 113.358168 -55.000144)
		(stroke
			(width 0.2)
			(type default)
		)
		(layer "In3.Cu")
	)
	(gr_arc
		(start 113.358168 -55.000144)
		(mid 113.000028 -54.642004)
		(end 112.641888 -55.000144)
		(stroke
			(width 0.2)
			(type default)
		)
		(layer "In3.Cu")
	)
	(gr_line
		(start 113.358168 -53.000148)
		(end 113.358168 -52.00015)
		(stroke
			(width 0.2)
			(type default)
		)
		(layer "In3.Cu")
	)
	(gr_arc
		(start 113.358168 -52.00015)
		(mid 113.000028 -51.64201)
		(end 112.641888 -52.00015)
		(stroke
			(width 0.2)
			(type default)
		)
		(layer "In3.Cu")
	)
	(gr_line
		(start 113.561368 -11.20013)
		(end 113.561368 -9.800082)
		(stroke
			(width 0.2)
			(type default)
		)
		(layer "In3.Cu")
	)
	(gr_arc
		(start 113.561368 -9.800082)
		(mid 113.000028 -9.238742)
		(end 112.438688 -9.800082)
		(stroke
			(width 0.2)
			(type default)
		)
		(layer "In3.Cu")
	)
	(gr_line
		(start 113.561368 -3.999992)
		(end 113.561368 -2.600198)
		(stroke
			(width 0.2)
			(type default)
		)
		(layer "In3.Cu")
	)
	(gr_arc
		(start 113.561368 -2.600198)
		(mid 113.000028 -2.038858)
		(end 112.438688 -2.600198)
		(stroke
			(width 0.2)
			(type default)
		)
		(layer "In3.Cu")
	)
	(gr_arc
		(start 113.641886 -55.999888)
		(mid 113.999899 -56.358282)
		(end 114.358166 -56.000142)
		(stroke
			(width 0.2)
			(type default)
		)
		(layer "In3.Cu")
	)
	(gr_line
		(start 113.641886 -55.000144)
		(end 113.641886 -55.999888)
		(stroke
			(width 0.2)
			(type default)
		)
		(layer "In3.Cu")
	)
	(gr_arc
		(start 113.641886 -51.999896)
		(mid 113.999899 -52.35829)
		(end 114.358166 -52.00015)
		(stroke
			(width 0.2)
			(type default)
		)
		(layer "In3.Cu")
	)
	(gr_line
		(start 113.641886 -51.000152)
		(end 113.641886 -51.999896)
		(stroke
			(width 0.2)
			(type default)
		)
		(layer "In3.Cu")
	)
	(gr_arc
		(start 114.238786 -12.399772)
		(mid 114.799999 -12.961366)
		(end 115.361466 -12.400026)
		(stroke
			(width 0.2)
			(type default)
		)
		(layer "In3.Cu")
	)
	(gr_line
		(start 114.238786 -10.999978)
		(end 114.238786 -12.399772)
		(stroke
			(width 0.2)
			(type default)
		)
		(layer "In3.Cu")
	)
	(gr_arc
		(start 114.238786 -5.199888)
		(mid 114.799999 -5.761482)
		(end 115.361466 -5.200142)
		(stroke
			(width 0.2)
			(type default)
		)
		(layer "In3.Cu")
	)
	(gr_line
		(start 114.238786 -3.800094)
		(end 114.238786 -5.199888)
		(stroke
			(width 0.2)
			(type default)
		)
		(layer "In3.Cu")
	)
	(gr_line
		(start 114.358166 -56.000142)
		(end 114.358166 -55.000144)
		(stroke
			(width 0.2)
			(type default)
		)
		(layer "In3.Cu")
	)
	(gr_arc
		(start 114.358166 -55.000144)
		(mid 114.000026 -54.642004)
		(end 113.641886 -55.000144)
		(stroke
			(width 0.2)
			(type default)
		)
		(layer "In3.Cu")
	)
	(gr_line
		(start 114.358166 -52.00015)
		(end 114.358166 -51.000152)
		(stroke
			(width 0.2)
			(type default)
		)
		(layer "In3.Cu")
	)
	(gr_arc
		(start 114.358166 -51.000152)
		(mid 114.000026 -50.642012)
		(end 113.641886 -51.000152)
		(stroke
			(width 0.2)
			(type default)
		)
		(layer "In3.Cu")
	)
	(gr_line
		(start 115.361466 -12.400026)
		(end 115.361466 -10.999978)
		(stroke
			(width 0.2)
			(type default)
		)
		(layer "In3.Cu")
	)
	(gr_arc
		(start 115.361466 -10.999978)
		(mid 114.800126 -10.438638)
		(end 114.238786 -10.999978)
		(stroke
			(width 0.2)
			(type default)
		)
		(layer "In3.Cu")
	)
	(gr_line
		(start 115.361466 -5.200142)
		(end 115.361466 -3.800094)
		(stroke
			(width 0.2)
			(type default)
		)
		(layer "In3.Cu")
	)
	(gr_arc
		(start 115.361466 -3.800094)
		(mid 114.800126 -3.238754)
		(end 114.238786 -3.800094)
		(stroke
			(width 0.2)
			(type default)
		)
		(layer "In3.Cu")
	)
	(gr_arc
		(start 115.641882 -55.999888)
		(mid 115.999895 -56.358282)
		(end 116.358162 -56.000142)
		(stroke
			(width 0.2)
			(type default)
		)
		(layer "In3.Cu")
	)
	(gr_line
		(start 115.641882 -55.000144)
		(end 115.641882 -55.999888)
		(stroke
			(width 0.2)
			(type default)
		)
		(layer "In3.Cu")
	)
	(gr_arc
		(start 115.641882 -52.999894)
		(mid 115.999895 -53.358288)
		(end 116.358162 -53.000148)
		(stroke
			(width 0.2)
			(type default)
		)
		(layer "In3.Cu")
	)
	(gr_line
		(start 115.641882 -52.00015)
		(end 115.641882 -52.999894)
		(stroke
			(width 0.2)
			(type default)
		)
		(layer "In3.Cu")
	)
	(gr_arc
		(start 116.03863 -11.199876)
		(mid 116.599843 -11.76147)
		(end 117.16131 -11.20013)
		(stroke
			(width 0.2)
			(type default)
		)
		(layer "In3.Cu")
	)
	(gr_line
		(start 116.03863 -9.800082)
		(end 116.03863 -11.199876)
		(stroke
			(width 0.2)
			(type default)
		)
		(layer "In3.Cu")
	)
	(gr_arc
		(start 116.03863 -3.999738)
		(mid 116.599843 -4.561332)
		(end 117.16131 -3.999992)
		(stroke
			(width 0.2)
			(type default)
		)
		(layer "In3.Cu")
	)
	(gr_line
		(start 116.03863 -2.600198)
		(end 116.03863 -3.999738)
		(stroke
			(width 0.2)
			(type default)
		)
		(layer "In3.Cu")
	)
	(gr_line
		(start 116.358162 -56.000142)
		(end 116.358162 -55.000144)
		(stroke
			(width 0.2)
			(type default)
		)
		(layer "In3.Cu")
	)
	(gr_arc
		(start 116.358162 -55.000144)
		(mid 116.000022 -54.642004)
		(end 115.641882 -55.000144)
		(stroke
			(width 0.2)
			(type default)
		)
		(layer "In3.Cu")
	)
	(gr_line
		(start 116.358162 -53.000148)
		(end 116.358162 -52.00015)
		(stroke
			(width 0.2)
			(type default)
		)
		(layer "In3.Cu")
	)
	(gr_arc
		(start 116.358162 -52.00015)
		(mid 116.000022 -51.64201)
		(end 115.641882 -52.00015)
		(stroke
			(width 0.2)
			(type default)
		)
		(layer "In3.Cu")
	)
	(gr_arc
		(start 116.64188 -55.999888)
		(mid 116.999893 -56.358282)
		(end 117.35816 -56.000142)
		(stroke
			(width 0.2)
			(type default)
		)
		(layer "In3.Cu")
	)
	(gr_line
		(start 116.64188 -55.000144)
		(end 116.64188 -55.999888)
		(stroke
			(width 0.2)
			(type default)
		)
		(layer "In3.Cu")
	)
	(gr_arc
		(start 116.64188 -51.999896)
		(mid 116.999893 -52.35829)
		(end 117.35816 -52.00015)
		(stroke
			(width 0.2)
			(type default)
		)
		(layer "In3.Cu")
	)
	(gr_line
		(start 116.64188 -51.000152)
		(end 116.64188 -51.999896)
		(stroke
			(width 0.2)
			(type default)
		)
		(layer "In3.Cu")
	)
	(gr_line
		(start 117.16131 -11.20013)
		(end 117.16131 -9.800082)
		(stroke
			(width 0.2)
			(type default)
		)
		(layer "In3.Cu")
	)
	(gr_arc
		(start 117.16131 -9.800082)
		(mid 116.59997 -9.238742)
		(end 116.03863 -9.800082)
		(stroke
			(width 0.2)
			(type default)
		)
		(layer "In3.Cu")
	)
	(gr_line
		(start 117.16131 -3.999992)
		(end 117.16131 -2.600198)
		(stroke
			(width 0.2)
			(type default)
		)
		(layer "In3.Cu")
	)
	(gr_arc
		(start 117.16131 -2.600198)
		(mid 116.59997 -2.038858)
		(end 116.03863 -2.600198)
		(stroke
			(width 0.2)
			(type default)
		)
		(layer "In3.Cu")
	)
	(gr_line
		(start 117.35816 -56.000142)
		(end 117.35816 -55.000144)
		(stroke
			(width 0.2)
			(type default)
		)
		(layer "In3.Cu")
	)
	(gr_arc
		(start 117.35816 -55.000144)
		(mid 117.00002 -54.642004)
		(end 116.64188 -55.000144)
		(stroke
			(width 0.2)
			(type default)
		)
		(layer "In3.Cu")
	)
	(gr_line
		(start 117.35816 -52.00015)
		(end 117.35816 -51.000152)
		(stroke
			(width 0.2)
			(type default)
		)
		(layer "In3.Cu")
	)
	(gr_arc
		(start 117.35816 -51.000152)
		(mid 117.00002 -50.642012)
		(end 116.64188 -51.000152)
		(stroke
			(width 0.2)
			(type default)
		)
		(layer "In3.Cu")
	)
	(gr_arc
		(start 117.641878 -55.999888)
		(mid 117.999891 -56.358282)
		(end 118.358158 -56.000142)
		(stroke
			(width 0.2)
			(type default)
		)
		(layer "In3.Cu")
	)
	(gr_line
		(start 117.641878 -55.000144)
		(end 117.641878 -55.999888)
		(stroke
			(width 0.2)
			(type default)
		)
		(layer "In3.Cu")
	)
	(gr_arc
		(start 117.641878 -52.999894)
		(mid 117.999891 -53.358288)
		(end 118.358158 -53.000148)
		(stroke
			(width 0.2)
			(type default)
		)
		(layer "In3.Cu")
	)
	(gr_line
		(start 117.641878 -52.00015)
		(end 117.641878 -52.999894)
		(stroke
			(width 0.2)
			(type default)
		)
		(layer "In3.Cu")
	)
	(gr_arc
		(start 117.838728 -12.399772)
		(mid 118.399941 -12.961366)
		(end 118.961408 -12.400026)
		(stroke
			(width 0.2)
			(type default)
		)
		(layer "In3.Cu")
	)
	(gr_line
		(start 117.838728 -10.999978)
		(end 117.838728 -12.399772)
		(stroke
			(width 0.2)
			(type default)
		)
		(layer "In3.Cu")
	)
	(gr_arc
		(start 117.838728 -5.199888)
		(mid 118.399941 -5.761482)
		(end 118.961408 -5.200142)
		(stroke
			(width 0.2)
			(type default)
		)
		(layer "In3.Cu")
	)
	(gr_line
		(start 117.838728 -3.800094)
		(end 117.838728 -5.199888)
		(stroke
			(width 0.2)
			(type default)
		)
		(layer "In3.Cu")
	)
	(gr_line
		(start 118.358158 -56.000142)
		(end 118.358158 -55.000144)
		(stroke
			(width 0.2)
			(type default)
		)
		(layer "In3.Cu")
	)
	(gr_arc
		(start 118.358158 -55.000144)
		(mid 118.000018 -54.642004)
		(end 117.641878 -55.000144)
		(stroke
			(width 0.2)
			(type default)
		)
		(layer "In3.Cu")
	)
	(gr_line
		(start 118.358158 -53.000148)
		(end 118.358158 -52.00015)
		(stroke
			(width 0.2)
			(type default)
		)
		(layer "In3.Cu")
	)
	(gr_arc
		(start 118.358158 -52.00015)
		(mid 118.000018 -51.64201)
		(end 117.641878 -52.00015)
		(stroke
			(width 0.2)
			(type default)
		)
		(layer "In3.Cu")
	)
	(gr_arc
		(start 118.641876 -55.999888)
		(mid 118.999889 -56.358282)
		(end 119.358156 -56.000142)
		(stroke
			(width 0.2)
			(type default)
		)
		(layer "In3.Cu")
	)
	(gr_line
		(start 118.641876 -55.000144)
		(end 118.641876 -55.999888)
		(stroke
			(width 0.2)
			(type default)
		)
		(layer "In3.Cu")
	)
	(gr_arc
		(start 118.641876 -51.999896)
		(mid 118.999889 -52.35829)
		(end 119.358156 -52.00015)
		(stroke
			(width 0.2)
			(type default)
		)
		(layer "In3.Cu")
	)
	(gr_line
		(start 118.641876 -51.000152)
		(end 118.641876 -51.999896)
		(stroke
			(width 0.2)
			(type default)
		)
		(layer "In3.Cu")
	)
	(gr_line
		(start 118.961408 -12.400026)
		(end 118.961408 -10.999978)
		(stroke
			(width 0.2)
			(type default)
		)
		(layer "In3.Cu")
	)
	(gr_arc
		(start 118.961408 -10.999978)
		(mid 118.400068 -10.438638)
		(end 117.838728 -10.999978)
		(stroke
			(width 0.2)
			(type default)
		)
		(layer "In3.Cu")
	)
	(gr_line
		(start 118.961408 -5.200142)
		(end 118.961408 -3.800094)
		(stroke
			(width 0.2)
			(type default)
		)
		(layer "In3.Cu")
	)
	(gr_arc
		(start 118.961408 -3.800094)
		(mid 118.400068 -3.238754)
		(end 117.838728 -3.800094)
		(stroke
			(width 0.2)
			(type default)
		)
		(layer "In3.Cu")
	)
	(gr_line
		(start 119.358156 -56.000142)
		(end 119.358156 -55.000144)
		(stroke
			(width 0.2)
			(type default)
		)
		(layer "In3.Cu")
	)
	(gr_arc
		(start 119.358156 -55.000144)
		(mid 119.000016 -54.642004)
		(end 118.641876 -55.000144)
		(stroke
			(width 0.2)
			(type default)
		)
		(layer "In3.Cu")
	)
	(gr_line
		(start 119.358156 -52.00015)
		(end 119.358156 -51.000152)
		(stroke
			(width 0.2)
			(type default)
		)
		(layer "In3.Cu")
	)
	(gr_arc
		(start 119.358156 -51.000152)
		(mid 119.000016 -50.642012)
		(end 118.641876 -51.000152)
		(stroke
			(width 0.2)
			(type default)
		)
		(layer "In3.Cu")
	)
	(gr_arc
		(start 119.638826 -11.199876)
		(mid 120.200039 -11.76147)
		(end 120.761506 -11.20013)
		(stroke
			(width 0.2)
			(type default)
		)
		(layer "In3.Cu")
	)
	(gr_line
		(start 119.638826 -9.800082)
		(end 119.638826 -11.199876)
		(stroke
			(width 0.2)
			(type default)
		)
		(layer "In3.Cu")
	)
	(gr_arc
		(start 119.638826 -3.999738)
		(mid 120.200039 -4.561332)
		(end 120.761506 -3.999992)
		(stroke
			(width 0.2)
			(type default)
		)
		(layer "In3.Cu")
	)
	(gr_line
		(start 119.638826 -2.600198)
		(end 119.638826 -3.999738)
		(stroke
			(width 0.2)
			(type default)
		)
		(layer "In3.Cu")
	)
	(gr_arc
		(start 119.641874 -55.999888)
		(mid 119.999887 -56.358282)
		(end 120.358154 -56.000142)
		(stroke
			(width 0.2)
			(type default)
		)
		(layer "In3.Cu")
	)
	(gr_line
		(start 119.641874 -55.000144)
		(end 119.641874 -55.999888)
		(stroke
			(width 0.2)
			(type default)
		)
		(layer "In3.Cu")
	)
	(gr_arc
		(start 119.641874 -52.999894)
		(mid 119.999887 -53.358288)
		(end 120.358154 -53.000148)
		(stroke
			(width 0.2)
			(type default)
		)
		(layer "In3.Cu")
	)
	(gr_line
		(start 119.641874 -52.00015)
		(end 119.641874 -52.999894)
		(stroke
			(width 0.2)
			(type default)
		)
		(layer "In3.Cu")
	)
	(gr_line
		(start 120.358154 -56.000142)
		(end 120.358154 -55.000144)
		(stroke
			(width 0.2)
			(type default)
		)
		(layer "In3.Cu")
	)
	(gr_arc
		(start 120.358154 -55.000144)
		(mid 120.000014 -54.642004)
		(end 119.641874 -55.000144)
		(stroke
			(width 0.2)
			(type default)
		)
		(layer "In3.Cu")
	)
	(gr_line
		(start 120.358154 -53.000148)
		(end 120.358154 -52.00015)
		(stroke
			(width 0.2)
			(type default)
		)
		(layer "In3.Cu")
	)
	(gr_arc
		(start 120.358154 -52.00015)
		(mid 120.000014 -51.64201)
		(end 119.641874 -52.00015)
		(stroke
			(width 0.2)
			(type default)
		)
		(layer "In3.Cu")
	)
	(gr_arc
		(start 120.641872 -55.999888)
		(mid 120.999885 -56.358282)
		(end 121.358152 -56.000142)
		(stroke
			(width 0.2)
			(type default)
		)
		(layer "In3.Cu")
	)
	(gr_line
		(start 120.641872 -55.000144)
		(end 120.641872 -55.999888)
		(stroke
			(width 0.2)
			(type default)
		)
		(layer "In3.Cu")
	)
	(gr_arc
		(start 120.641872 -51.999896)
		(mid 120.999885 -52.35829)
		(end 121.358152 -52.00015)
		(stroke
			(width 0.2)
			(type default)
		)
		(layer "In3.Cu")
	)
	(gr_line
		(start 120.641872 -51.000152)
		(end 120.641872 -51.999896)
		(stroke
			(width 0.2)
			(type default)
		)
		(layer "In3.Cu")
	)
	(gr_line
		(start 120.761506 -11.20013)
		(end 120.761506 -9.800082)
		(stroke
			(width 0.2)
			(type default)
		)
		(layer "In3.Cu")
	)
	(gr_arc
		(start 120.761506 -9.800082)
		(mid 120.200166 -9.238742)
		(end 119.638826 -9.800082)
		(stroke
			(width 0.2)
			(type default)
		)
		(layer "In3.Cu")
	)
	(gr_line
		(start 120.761506 -3.999992)
		(end 120.761506 -2.600198)
		(stroke
			(width 0.2)
			(type default)
		)
		(layer "In3.Cu")
	)
	(gr_arc
		(start 120.761506 -2.600198)
		(mid 120.200166 -2.038858)
		(end 119.638826 -2.600198)
		(stroke
			(width 0.2)
			(type default)
		)
		(layer "In3.Cu")
	)
	(gr_line
		(start 120.79224 -127.32639)
		(end 112.499902 -126.000002)
		(stroke
			(width 2.54)
			(type default)
		)
		(layer "In3.Cu")
	)
	(gr_line
		(start 121.10593 -62.486286)
		(end 121.510044 -62.8904)
		(stroke
			(width 0.381)
			(type default)
		)
		(layer "In3.Cu")
	)
	(gr_line
		(start 121.2088 -95.4278)
		(end 121.4882 -95.1484)
		(stroke
			(width 0.381)
			(type default)
		)
		(layer "In3.Cu")
	)
	(gr_line
		(start 121.358152 -56.000142)
		(end 121.358152 -55.000144)
		(stroke
			(width 0.2)
			(type default)
		)
		(layer "In3.Cu")
	)
	(gr_arc
		(start 121.358152 -55.000144)
		(mid 121.000012 -54.642004)
		(end 120.641872 -55.000144)
		(stroke
			(width 0.2)
			(type default)
		)
		(layer "In3.Cu")
	)
	(gr_line
		(start 121.358152 -52.00015)
		(end 121.358152 -51.000152)
		(stroke
			(width 0.2)
			(type default)
		)
		(layer "In3.Cu")
	)
	(gr_arc
		(start 121.358152 -51.000152)
		(mid 121.000012 -50.642012)
		(end 120.641872 -51.000152)
		(stroke
			(width 0.2)
			(type default)
		)
		(layer "In3.Cu")
	)
	(gr_arc
		(start 121.43867 -12.399772)
		(mid 121.999883 -12.961366)
		(end 122.56135 -12.400026)
		(stroke
			(width 0.2)
			(type default)
		)
		(layer "In3.Cu")
	)
	(gr_line
		(start 121.43867 -10.999978)
		(end 121.43867 -12.399772)
		(stroke
			(width 0.2)
			(type default)
		)
		(layer "In3.Cu")
	)
	(gr_arc
		(start 121.43867 -5.199888)
		(mid 121.999883 -5.761482)
		(end 122.56135 -5.200142)
		(stroke
			(width 0.2)
			(type default)
		)
		(layer "In3.Cu")
	)
	(gr_line
		(start 121.43867 -3.800094)
		(end 121.43867 -5.199888)
		(stroke
			(width 0.2)
			(type default)
		)
		(layer "In3.Cu")
	)
	(gr_line
		(start 121.50979 -71.441564)
		(end 121.510044 -71.44131)
		(stroke
			(width 0.381)
			(type default)
		)
		(layer "In3.Cu")
	)
	(gr_line
		(start 121.510044 -62.8904)
		(end 121.510044 -95.4532)
		(stroke
			(width 0.381)
			(type default)
		)
		(layer "In3.Cu")
	)
	(gr_line
		(start 121.5644 -77.5208)
		(end 140.790676 -77.5208)
		(stroke
			(width 0.381)
			(type default)
		)
		(layer "In3.Cu")
	)
	(gr_line
		(start 121.6152 -77.8256)
		(end 121.8946 -77.5462)
		(stroke
			(width 0.381)
			(type default)
		)
		(layer "In3.Cu")
	)
	(gr_line
		(start 121.6152 -77.2668)
		(end 121.8946 -77.5462)
		(stroke
			(width 0.381)
			(type default)
		)
		(layer "In3.Cu")
	)
	(gr_arc
		(start 121.64187 -55.999888)
		(mid 121.999883 -56.358282)
		(end 122.35815 -56.000142)
		(stroke
			(width 0.2)
			(type default)
		)
		(layer "In3.Cu")
	)
	(gr_line
		(start 121.64187 -55.000144)
		(end 121.64187 -55.999888)
		(stroke
			(width 0.2)
			(type default)
		)
		(layer "In3.Cu")
	)
	(gr_arc
		(start 121.64187 -52.999894)
		(mid 121.999883 -53.358288)
		(end 122.35815 -53.000148)
		(stroke
			(width 0.2)
			(type default)
		)
		(layer "In3.Cu")
	)
	(gr_line
		(start 121.64187 -52.00015)
		(end 121.64187 -52.999894)
		(stroke
			(width 0.2)
			(type default)
		)
		(layer "In3.Cu")
	)
	(gr_line
		(start 121.7676 -95.4278)
		(end 121.4882 -95.1484)
		(stroke
			(width 0.381)
			(type default)
		)
		(layer "In3.Cu")
	)
	(gr_line
		(start 122.35815 -56.000142)
		(end 122.35815 -55.000144)
		(stroke
			(width 0.2)
			(type default)
		)
		(layer "In3.Cu")
	)
	(gr_arc
		(start 122.35815 -55.000144)
		(mid 122.00001 -54.642004)
		(end 121.64187 -55.000144)
		(stroke
			(width 0.2)
			(type default)
		)
		(layer "In3.Cu")
	)
	(gr_line
		(start 122.35815 -53.000148)
		(end 122.35815 -52.00015)
		(stroke
			(width 0.2)
			(type default)
		)
		(layer "In3.Cu")
	)
	(gr_arc
		(start 122.35815 -52.00015)
		(mid 122.00001 -51.64201)
		(end 121.64187 -52.00015)
		(stroke
			(width 0.2)
			(type default)
		)
		(layer "In3.Cu")
	)
	(gr_line
		(start 122.56135 -12.400026)
		(end 122.56135 -10.999978)
		(stroke
			(width 0.2)
			(type default)
		)
		(layer "In3.Cu")
	)
	(gr_arc
		(start 122.56135 -10.999978)
		(mid 122.00001 -10.438638)
		(end 121.43867 -10.999978)
		(stroke
			(width 0.2)
			(type default)
		)
		(layer "In3.Cu")
	)
	(gr_line
		(start 122.56135 -5.200142)
		(end 122.56135 -3.800094)
		(stroke
			(width 0.2)
			(type default)
		)
		(layer "In3.Cu")
	)
	(gr_arc
		(start 122.56135 -3.800094)
		(mid 122.00001 -3.238754)
		(end 121.43867 -3.800094)
		(stroke
			(width 0.2)
			(type default)
		)
		(layer "In3.Cu")
	)
	(gr_arc
		(start 122.641868 -55.999888)
		(mid 122.999881 -56.358282)
		(end 123.358148 -56.000142)
		(stroke
			(width 0.2)
			(type default)
		)
		(layer "In3.Cu")
	)
	(gr_line
		(start 122.641868 -55.000144)
		(end 122.641868 -55.999888)
		(stroke
			(width 0.2)
			(type default)
		)
		(layer "In3.Cu")
	)
	(gr_arc
		(start 122.641868 -51.999896)
		(mid 122.999881 -52.35829)
		(end 123.358148 -52.00015)
		(stroke
			(width 0.2)
			(type default)
		)
		(layer "In3.Cu")
	)
	(gr_line
		(start 122.641868 -51.000152)
		(end 122.641868 -51.999896)
		(stroke
			(width 0.2)
			(type default)
		)
		(layer "In3.Cu")
	)
	(gr_arc
		(start 123.238768 -11.199876)
		(mid 123.799981 -11.76147)
		(end 124.361448 -11.20013)
		(stroke
			(width 0.2)
			(type default)
		)
		(layer "In3.Cu")
	)
	(gr_line
		(start 123.238768 -9.800082)
		(end 123.238768 -11.199876)
		(stroke
			(width 0.2)
			(type default)
		)
		(layer "In3.Cu")
	)
	(gr_arc
		(start 123.238768 -3.999738)
		(mid 123.799981 -4.561332)
		(end 124.361448 -3.999992)
		(stroke
			(width 0.2)
			(type default)
		)
		(layer "In3.Cu")
	)
	(gr_line
		(start 123.238768 -2.600198)
		(end 123.238768 -3.999738)
		(stroke
			(width 0.2)
			(type default)
		)
		(layer "In3.Cu")
	)
	(gr_line
		(start 123.358148 -56.000142)
		(end 123.358148 -55.000144)
		(stroke
			(width 0.2)
			(type default)
		)
		(layer "In3.Cu")
	)
	(gr_arc
		(start 123.358148 -55.000144)
		(mid 123.000008 -54.642004)
		(end 122.641868 -55.000144)
		(stroke
			(width 0.2)
			(type default)
		)
		(layer "In3.Cu")
	)
	(gr_line
		(start 123.358148 -52.00015)
		(end 123.358148 -51.000152)
		(stroke
			(width 0.2)
			(type default)
		)
		(layer "In3.Cu")
	)
	(gr_arc
		(start 123.358148 -51.000152)
		(mid 123.000008 -50.642012)
		(end 122.641868 -51.000152)
		(stroke
			(width 0.2)
			(type default)
		)
		(layer "In3.Cu")
	)
	(gr_arc
		(start 123.641866 -55.999888)
		(mid 123.999879 -56.358282)
		(end 124.358146 -56.000142)
		(stroke
			(width 0.2)
			(type default)
		)
		(layer "In3.Cu")
	)
	(gr_line
		(start 123.641866 -55.000144)
		(end 123.641866 -55.999888)
		(stroke
			(width 0.2)
			(type default)
		)
		(layer "In3.Cu")
	)
	(gr_arc
		(start 123.641866 -52.999894)
		(mid 123.999879 -53.358288)
		(end 124.358146 -53.000148)
		(stroke
			(width 0.2)
			(type default)
		)
		(layer "In3.Cu")
	)
	(gr_line
		(start 123.641866 -52.00015)
		(end 123.641866 -52.999894)
		(stroke
			(width 0.2)
			(type default)
		)
		(layer "In3.Cu")
	)
	(gr_arc
		(start 124.225558 -47.001684)
		(mid 124.682631 -47.459138)
		(end 125.139958 -47.001938)
		(stroke
			(width 0.2)
			(type default)
		)
		(layer "In3.Cu")
	)
	(gr_line
		(start 124.225558 -45.858938)
		(end 124.225558 -47.001684)
		(stroke
			(width 0.2)
			(type default)
		)
		(layer "In3.Cu")
	)
	(gr_line
		(start 124.358146 -56.000142)
		(end 124.358146 -55.000144)
		(stroke
			(width 0.2)
			(type default)
		)
		(layer "In3.Cu")
	)
	(gr_arc
		(start 124.358146 -55.000144)
		(mid 124.000006 -54.642004)
		(end 123.641866 -55.000144)
		(stroke
			(width 0.2)
			(type default)
		)
		(layer "In3.Cu")
	)
	(gr_line
		(start 124.358146 -53.000148)
		(end 124.358146 -52.00015)
		(stroke
			(width 0.2)
			(type default)
		)
		(layer "In3.Cu")
	)
	(gr_arc
		(start 124.358146 -52.00015)
		(mid 124.000006 -51.64201)
		(end 123.641866 -52.00015)
		(stroke
			(width 0.2)
			(type default)
		)
		(layer "In3.Cu")
	)
	(gr_line
		(start 124.361448 -11.20013)
		(end 124.361448 -9.800082)
		(stroke
			(width 0.2)
			(type default)
		)
		(layer "In3.Cu")
	)
	(gr_arc
		(start 124.361448 -9.800082)
		(mid 123.800108 -9.238742)
		(end 123.238768 -9.800082)
		(stroke
			(width 0.2)
			(type default)
		)
		(layer "In3.Cu")
	)
	(gr_line
		(start 124.361448 -3.999992)
		(end 124.361448 -2.600198)
		(stroke
			(width 0.2)
			(type default)
		)
		(layer "In3.Cu")
	)
	(gr_arc
		(start 124.361448 -2.600198)
		(mid 123.800108 -2.038858)
		(end 123.238768 -2.600198)
		(stroke
			(width 0.2)
			(type default)
		)
		(layer "In3.Cu")
	)
	(gr_line
		(start 125.002544 -142.999968)
		(end 125.002544 -132.263642)
		(stroke
			(width 2.54)
			(type default)
		)
		(layer "In3.Cu")
	)
	(gr_arc
		(start 125.002544 -142.999968)
		(mid 125.58832 -144.414185)
		(end 127.00254 -144.999964)
		(stroke
			(width 2.54)
			(type default)
		)
		(layer "In3.Cu")
	)
	(gr_arc
		(start 125.002544 -132.263642)
		(mid 123.807045 -129.019301)
		(end 120.79224 -127.32639)
		(stroke
			(width 2.54)
			(type default)
		)
		(layer "In3.Cu")
	)
	(gr_arc
		(start 125.038866 -12.399772)
		(mid 125.600079 -12.961366)
		(end 126.161546 -12.400026)
		(stroke
			(width 0.2)
			(type default)
		)
		(layer "In3.Cu")
	)
	(gr_line
		(start 125.038866 -10.999978)
		(end 125.038866 -12.399772)
		(stroke
			(width 0.2)
			(type default)
		)
		(layer "In3.Cu")
	)
	(gr_arc
		(start 125.038866 -5.199888)
		(mid 125.600079 -5.761482)
		(end 126.161546 -5.200142)
		(stroke
			(width 0.2)
			(type default)
		)
		(layer "In3.Cu")
	)
	(gr_line
		(start 125.038866 -3.800094)
		(end 125.038866 -5.199888)
		(stroke
			(width 0.2)
			(type default)
		)
		(layer "In3.Cu")
	)
	(gr_line
		(start 125.139958 -47.001938)
		(end 125.139958 -45.858938)
		(stroke
			(width 0.2)
			(type default)
		)
		(layer "In3.Cu")
	)
	(gr_arc
		(start 125.139958 -45.858938)
		(mid 124.682758 -45.401738)
		(end 124.225558 -45.858938)
		(stroke
			(width 0.2)
			(type default)
		)
		(layer "In3.Cu")
	)
	(gr_line
		(start 126.000002 -77.35824)
		(end 127 -77.35824)
		(stroke
			(width 0.2)
			(type default)
		)
		(layer "In3.Cu")
	)
	(gr_line
		(start 126.000002 -76.358242)
		(end 127 -76.358242)
		(stroke
			(width 0.2)
			(type default)
		)
		(layer "In3.Cu")
	)
	(gr_line
		(start 126.000002 -75.358244)
		(end 127 -75.358244)
		(stroke
			(width 0.2)
			(type default)
		)
		(layer "In3.Cu")
	)
	(gr_line
		(start 126.000002 -74.358246)
		(end 127 -74.358246)
		(stroke
			(width 0.2)
			(type default)
		)
		(layer "In3.Cu")
	)
	(gr_line
		(start 126.000002 -73.358248)
		(end 127 -73.358248)
		(stroke
			(width 0.2)
			(type default)
		)
		(layer "In3.Cu")
	)
	(gr_line
		(start 126.000002 -72.35825)
		(end 127 -72.35825)
		(stroke
			(width 0.2)
			(type default)
		)
		(layer "In3.Cu")
	)
	(gr_line
		(start 126.000002 -71.358252)
		(end 127 -71.358252)
		(stroke
			(width 0.2)
			(type default)
		)
		(layer "In3.Cu")
	)
	(gr_line
		(start 126.000002 -70.358254)
		(end 127 -70.358254)
		(stroke
			(width 0.2)
			(type default)
		)
		(layer "In3.Cu")
	)
	(gr_line
		(start 126.000002 -69.358256)
		(end 127 -69.358256)
		(stroke
			(width 0.2)
			(type default)
		)
		(layer "In3.Cu")
	)
	(gr_line
		(start 126.000002 -68.358258)
		(end 127 -68.358258)
		(stroke
			(width 0.2)
			(type default)
		)
		(layer "In3.Cu")
	)
	(gr_line
		(start 126.000002 -66.358262)
		(end 127 -66.358262)
		(stroke
			(width 0.2)
			(type default)
		)
		(layer "In3.Cu")
	)
	(gr_line
		(start 126.000002 -65.358264)
		(end 127 -65.358264)
		(stroke
			(width 0.2)
			(type default)
		)
		(layer "In3.Cu")
	)
	(gr_line
		(start 126.000002 -64.358266)
		(end 127 -64.358266)
		(stroke
			(width 0.2)
			(type default)
		)
		(layer "In3.Cu")
	)
	(gr_line
		(start 126.000002 -63.358268)
		(end 127 -63.358268)
		(stroke
			(width 0.2)
			(type default)
		)
		(layer "In3.Cu")
	)
	(gr_line
		(start 126.000002 -62.35827)
		(end 127 -62.35827)
		(stroke
			(width 0.2)
			(type default)
		)
		(layer "In3.Cu")
	)
	(gr_line
		(start 126.000002 -61.358272)
		(end 127 -61.358272)
		(stroke
			(width 0.2)
			(type default)
		)
		(layer "In3.Cu")
	)
	(gr_line
		(start 126.000002 -60.358274)
		(end 127 -60.358274)
		(stroke
			(width 0.2)
			(type default)
		)
		(layer "In3.Cu")
	)
	(gr_line
		(start 126.000002 -59.358276)
		(end 127 -59.358276)
		(stroke
			(width 0.2)
			(type default)
		)
		(layer "In3.Cu")
	)
	(gr_line
		(start 126.000002 -58.358278)
		(end 127 -58.358278)
		(stroke
			(width 0.2)
			(type default)
		)
		(layer "In3.Cu")
	)
	(gr_line
		(start 126.000002 -57.35828)
		(end 127 -57.35828)
		(stroke
			(width 0.2)
			(type default)
		)
		(layer "In3.Cu")
	)
	(gr_line
		(start 126.000002 -56.358282)
		(end 127 -56.358282)
		(stroke
			(width 0.2)
			(type default)
		)
		(layer "In3.Cu")
	)
	(gr_line
		(start 126.000002 -55.358284)
		(end 127 -55.358284)
		(stroke
			(width 0.2)
			(type default)
		)
		(layer "In3.Cu")
	)
	(gr_line
		(start 126.000002 -54.358286)
		(end 127 -54.358286)
		(stroke
			(width 0.2)
			(type default)
		)
		(layer "In3.Cu")
	)
	(gr_arc
		(start 126.000256 -76.64196)
		(mid 125.641862 -76.999973)
		(end 126.000002 -77.35824)
		(stroke
			(width 0.2)
			(type default)
		)
		(layer "In3.Cu")
	)
	(gr_arc
		(start 126.000256 -75.641962)
		(mid 125.641862 -75.999975)
		(end 126.000002 -76.358242)
		(stroke
			(width 0.2)
			(type default)
		)
		(layer "In3.Cu")
	)
	(gr_arc
		(start 126.000256 -74.641964)
		(mid 125.641862 -74.999977)
		(end 126.000002 -75.358244)
		(stroke
			(width 0.2)
			(type default)
		)
		(layer "In3.Cu")
	)
	(gr_arc
		(start 126.000256 -73.641966)
		(mid 125.641862 -73.999979)
		(end 126.000002 -74.358246)
		(stroke
			(width 0.2)
			(type default)
		)
		(layer "In3.Cu")
	)
	(gr_arc
		(start 126.000256 -72.641968)
		(mid 125.641862 -72.999981)
		(end 126.000002 -73.358248)
		(stroke
			(width 0.2)
			(type default)
		)
		(layer "In3.Cu")
	)
	(gr_arc
		(start 126.000256 -71.64197)
		(mid 125.641862 -71.999983)
		(end 126.000002 -72.35825)
		(stroke
			(width 0.2)
			(type default)
		)
		(layer "In3.Cu")
	)
	(gr_arc
		(start 126.000256 -70.641972)
		(mid 125.641862 -70.999985)
		(end 126.000002 -71.358252)
		(stroke
			(width 0.2)
			(type default)
		)
		(layer "In3.Cu")
	)
	(gr_arc
		(start 126.000256 -69.641974)
		(mid 125.641862 -69.999987)
		(end 126.000002 -70.358254)
		(stroke
			(width 0.2)
			(type default)
		)
		(layer "In3.Cu")
	)
	(gr_arc
		(start 126.000256 -68.641976)
		(mid 125.641862 -68.999989)
		(end 126.000002 -69.358256)
		(stroke
			(width 0.2)
			(type default)
		)
		(layer "In3.Cu")
	)
	(gr_arc
		(start 126.000256 -67.641978)
		(mid 125.641862 -67.999991)
		(end 126.000002 -68.358258)
		(stroke
			(width 0.2)
			(type default)
		)
		(layer "In3.Cu")
	)
	(gr_arc
		(start 126.000256 -65.641982)
		(mid 125.641862 -65.999995)
		(end 126.000002 -66.358262)
		(stroke
			(width 0.2)
			(type default)
		)
		(layer "In3.Cu")
	)
	(gr_arc
		(start 126.000256 -64.641984)
		(mid 125.641862 -64.999997)
		(end 126.000002 -65.358264)
		(stroke
			(width 0.2)
			(type default)
		)
		(layer "In3.Cu")
	)
	(gr_arc
		(start 126.000256 -63.641986)
		(mid 125.641862 -63.999999)
		(end 126.000002 -64.358266)
		(stroke
			(width 0.2)
			(type default)
		)
		(layer "In3.Cu")
	)
	(gr_arc
		(start 126.000256 -62.641988)
		(mid 125.641862 -63.000001)
		(end 126.000002 -63.358268)
		(stroke
			(width 0.2)
			(type default)
		)
		(layer "In3.Cu")
	)
	(gr_arc
		(start 126.000256 -61.64199)
		(mid 125.641862 -62.000003)
		(end 126.000002 -62.35827)
		(stroke
			(width 0.2)
			(type default)
		)
		(layer "In3.Cu")
	)
	(gr_arc
		(start 126.000256 -60.641992)
		(mid 125.641862 -61.000005)
		(end 126.000002 -61.358272)
		(stroke
			(width 0.2)
			(type default)
		)
		(layer "In3.Cu")
	)
	(gr_arc
		(start 126.000256 -59.641994)
		(mid 125.641862 -60.000007)
		(end 126.000002 -60.358274)
		(stroke
			(width 0.2)
			(type default)
		)
		(layer "In3.Cu")
	)
	(gr_arc
		(start 126.000256 -58.641996)
		(mid 125.641862 -59.000009)
		(end 126.000002 -59.358276)
		(stroke
			(width 0.2)
			(type default)
		)
		(layer "In3.Cu")
	)
	(gr_arc
		(start 126.000256 -57.641998)
		(mid 125.641862 -58.000011)
		(end 126.000002 -58.358278)
		(stroke
			(width 0.2)
			(type default)
		)
		(layer "In3.Cu")
	)
	(gr_arc
		(start 126.000256 -56.642)
		(mid 125.641862 -57.000013)
		(end 126.000002 -57.35828)
		(stroke
			(width 0.2)
			(type default)
		)
		(layer "In3.Cu")
	)
	(gr_arc
		(start 126.000256 -55.642002)
		(mid 125.641862 -56.000015)
		(end 126.000002 -56.358282)
		(stroke
			(width 0.2)
			(type default)
		)
		(layer "In3.Cu")
	)
	(gr_arc
		(start 126.000256 -54.642004)
		(mid 125.641862 -55.000017)
		(end 126.000002 -55.358284)
		(stroke
			(width 0.2)
			(type default)
		)
		(layer "In3.Cu")
	)
	(gr_arc
		(start 126.000256 -53.642006)
		(mid 125.641862 -54.000019)
		(end 126.000002 -54.358286)
		(stroke
			(width 0.2)
			(type default)
		)
		(layer "In3.Cu")
	)
	(gr_line
		(start 126.161546 -12.400026)
		(end 126.161546 -10.999978)
		(stroke
			(width 0.2)
			(type default)
		)
		(layer "In3.Cu")
	)
	(gr_arc
		(start 126.161546 -10.999978)
		(mid 125.600206 -10.438638)
		(end 125.038866 -10.999978)
		(stroke
			(width 0.2)
			(type default)
		)
		(layer "In3.Cu")
	)
	(gr_line
		(start 126.161546 -5.200142)
		(end 126.161546 -3.800094)
		(stroke
			(width 0.2)
			(type default)
		)
		(layer "In3.Cu")
	)
	(gr_arc
		(start 126.161546 -3.800094)
		(mid 125.600206 -3.238754)
		(end 125.038866 -3.800094)
		(stroke
			(width 0.2)
			(type default)
		)
		(layer "In3.Cu")
	)
	(gr_arc
		(start 126.619508 -46.986952)
		(mid 127.076581 -47.444406)
		(end 127.533908 -46.987206)
		(stroke
			(width 0.2)
			(type default)
		)
		(layer "In3.Cu")
	)
	(gr_line
		(start 126.619508 -45.844206)
		(end 126.619508 -46.986952)
		(stroke
			(width 0.2)
			(type default)
		)
		(layer "In3.Cu")
	)
	(gr_arc
		(start 126.83871 -11.199876)
		(mid 127.399923 -11.76147)
		(end 127.96139 -11.20013)
		(stroke
			(width 0.2)
			(type default)
		)
		(layer "In3.Cu")
	)
	(gr_line
		(start 126.83871 -9.800082)
		(end 126.83871 -11.199876)
		(stroke
			(width 0.2)
			(type default)
		)
		(layer "In3.Cu")
	)
	(gr_arc
		(start 126.83871 -3.999738)
		(mid 127.399923 -4.561332)
		(end 127.96139 -3.999992)
		(stroke
			(width 0.2)
			(type default)
		)
		(layer "In3.Cu")
	)
	(gr_line
		(start 126.83871 -2.600198)
		(end 126.83871 -3.999738)
		(stroke
			(width 0.2)
			(type default)
		)
		(layer "In3.Cu")
	)
	(gr_arc
		(start 127 -77.35824)
		(mid 127.35814 -77.0001)
		(end 127 -76.64196)
		(stroke
			(width 0.2)
			(type default)
		)
		(layer "In3.Cu")
	)
	(gr_line
		(start 127 -76.64196)
		(end 126.000256 -76.64196)
		(stroke
			(width 0.2)
			(type default)
		)
		(layer "In3.Cu")
	)
	(gr_arc
		(start 127 -76.358242)
		(mid 127.35814 -76.000102)
		(end 127 -75.641962)
		(stroke
			(width 0.2)
			(type default)
		)
		(layer "In3.Cu")
	)
	(gr_line
		(start 127 -75.641962)
		(end 126.000256 -75.641962)
		(stroke
			(width 0.2)
			(type default)
		)
		(layer "In3.Cu")
	)
	(gr_arc
		(start 127 -75.358244)
		(mid 127.35814 -75.000104)
		(end 127 -74.641964)
		(stroke
			(width 0.2)
			(type default)
		)
		(layer "In3.Cu")
	)
	(gr_line
		(start 127 -74.641964)
		(end 126.000256 -74.641964)
		(stroke
			(width 0.2)
			(type default)
		)
		(layer "In3.Cu")
	)
	(gr_arc
		(start 127 -74.358246)
		(mid 127.35814 -74.000106)
		(end 127 -73.641966)
		(stroke
			(width 0.2)
			(type default)
		)
		(layer "In3.Cu")
	)
	(gr_line
		(start 127 -73.641966)
		(end 126.000256 -73.641966)
		(stroke
			(width 0.2)
			(type default)
		)
		(layer "In3.Cu")
	)
	(gr_arc
		(start 127 -73.358248)
		(mid 127.35814 -73.000108)
		(end 127 -72.641968)
		(stroke
			(width 0.2)
			(type default)
		)
		(layer "In3.Cu")
	)
	(gr_line
		(start 127 -72.641968)
		(end 126.000256 -72.641968)
		(stroke
			(width 0.2)
			(type default)
		)
		(layer "In3.Cu")
	)
	(gr_arc
		(start 127 -72.35825)
		(mid 127.35814 -72.00011)
		(end 127 -71.64197)
		(stroke
			(width 0.2)
			(type default)
		)
		(layer "In3.Cu")
	)
	(gr_line
		(start 127 -71.64197)
		(end 126.000256 -71.64197)
		(stroke
			(width 0.2)
			(type default)
		)
		(layer "In3.Cu")
	)
	(gr_arc
		(start 127 -71.358252)
		(mid 127.35814 -71.000112)
		(end 127 -70.641972)
		(stroke
			(width 0.2)
			(type default)
		)
		(layer "In3.Cu")
	)
	(gr_line
		(start 127 -70.641972)
		(end 126.000256 -70.641972)
		(stroke
			(width 0.2)
			(type default)
		)
		(layer "In3.Cu")
	)
	(gr_arc
		(start 127 -70.358254)
		(mid 127.35814 -70.000114)
		(end 127 -69.641974)
		(stroke
			(width 0.2)
			(type default)
		)
		(layer "In3.Cu")
	)
	(gr_line
		(start 127 -69.641974)
		(end 126.000256 -69.641974)
		(stroke
			(width 0.2)
			(type default)
		)
		(layer "In3.Cu")
	)
	(gr_arc
		(start 127 -69.358256)
		(mid 127.35814 -69.000116)
		(end 127 -68.641976)
		(stroke
			(width 0.2)
			(type default)
		)
		(layer "In3.Cu")
	)
	(gr_line
		(start 127 -68.641976)
		(end 126.000256 -68.641976)
		(stroke
			(width 0.2)
			(type default)
		)
		(layer "In3.Cu")
	)
	(gr_arc
		(start 127 -68.358258)
		(mid 127.35814 -68.000118)
		(end 127 -67.641978)
		(stroke
			(width 0.2)
			(type default)
		)
		(layer "In3.Cu")
	)
	(gr_line
		(start 127 -67.641978)
		(end 126.000256 -67.641978)
		(stroke
			(width 0.2)
			(type default)
		)
		(layer "In3.Cu")
	)
	(gr_arc
		(start 127 -66.358262)
		(mid 127.35814 -66.000122)
		(end 127 -65.641982)
		(stroke
			(width 0.2)
			(type default)
		)
		(layer "In3.Cu")
	)
	(gr_line
		(start 127 -65.641982)
		(end 126.000256 -65.641982)
		(stroke
			(width 0.2)
			(type default)
		)
		(layer "In3.Cu")
	)
	(gr_arc
		(start 127 -65.358264)
		(mid 127.35814 -65.000124)
		(end 127 -64.641984)
		(stroke
			(width 0.2)
			(type default)
		)
		(layer "In3.Cu")
	)
	(gr_line
		(start 127 -64.641984)
		(end 126.000256 -64.641984)
		(stroke
			(width 0.2)
			(type default)
		)
		(layer "In3.Cu")
	)
	(gr_arc
		(start 127 -64.358266)
		(mid 127.35814 -64.000126)
		(end 127 -63.641986)
		(stroke
			(width 0.2)
			(type default)
		)
		(layer "In3.Cu")
	)
	(gr_line
		(start 127 -63.641986)
		(end 126.000256 -63.641986)
		(stroke
			(width 0.2)
			(type default)
		)
		(layer "In3.Cu")
	)
	(gr_arc
		(start 127 -63.358268)
		(mid 127.35814 -63.000128)
		(end 127 -62.641988)
		(stroke
			(width 0.2)
			(type default)
		)
		(layer "In3.Cu")
	)
	(gr_line
		(start 127 -62.641988)
		(end 126.000256 -62.641988)
		(stroke
			(width 0.2)
			(type default)
		)
		(layer "In3.Cu")
	)
	(gr_arc
		(start 127 -62.35827)
		(mid 127.35814 -62.00013)
		(end 127 -61.64199)
		(stroke
			(width 0.2)
			(type default)
		)
		(layer "In3.Cu")
	)
	(gr_line
		(start 127 -61.64199)
		(end 126.000256 -61.64199)
		(stroke
			(width 0.2)
			(type default)
		)
		(layer "In3.Cu")
	)
	(gr_arc
		(start 127 -61.358272)
		(mid 127.35814 -61.000132)
		(end 127 -60.641992)
		(stroke
			(width 0.2)
			(type default)
		)
		(layer "In3.Cu")
	)
	(gr_line
		(start 127 -60.641992)
		(end 126.000256 -60.641992)
		(stroke
			(width 0.2)
			(type default)
		)
		(layer "In3.Cu")
	)
	(gr_arc
		(start 127 -60.358274)
		(mid 127.35814 -60.000134)
		(end 127 -59.641994)
		(stroke
			(width 0.2)
			(type default)
		)
		(layer "In3.Cu")
	)
	(gr_line
		(start 127 -59.641994)
		(end 126.000256 -59.641994)
		(stroke
			(width 0.2)
			(type default)
		)
		(layer "In3.Cu")
	)
	(gr_arc
		(start 127 -59.358276)
		(mid 127.35814 -59.000136)
		(end 127 -58.641996)
		(stroke
			(width 0.2)
			(type default)
		)
		(layer "In3.Cu")
	)
	(gr_line
		(start 127 -58.641996)
		(end 126.000256 -58.641996)
		(stroke
			(width 0.2)
			(type default)
		)
		(layer "In3.Cu")
	)
	(gr_arc
		(start 127 -58.358278)
		(mid 127.35814 -58.000138)
		(end 127 -57.641998)
		(stroke
			(width 0.2)
			(type default)
		)
		(layer "In3.Cu")
	)
	(gr_line
		(start 127 -57.641998)
		(end 126.000256 -57.641998)
		(stroke
			(width 0.2)
			(type default)
		)
		(layer "In3.Cu")
	)
	(gr_arc
		(start 127 -57.35828)
		(mid 127.35814 -57.00014)
		(end 127 -56.642)
		(stroke
			(width 0.2)
			(type default)
		)
		(layer "In3.Cu")
	)
	(gr_line
		(start 127 -56.642)
		(end 126.000256 -56.642)
		(stroke
			(width 0.2)
			(type default)
		)
		(layer "In3.Cu")
	)
	(gr_arc
		(start 127 -56.358282)
		(mid 127.35814 -56.000142)
		(end 127 -55.642002)
		(stroke
			(width 0.2)
			(type default)
		)
		(layer "In3.Cu")
	)
	(gr_line
		(start 127 -55.642002)
		(end 126.000256 -55.642002)
		(stroke
			(width 0.2)
			(type default)
		)
		(layer "In3.Cu")
	)
	(gr_arc
		(start 127 -55.358284)
		(mid 127.35814 -55.000144)
		(end 127 -54.642004)
		(stroke
			(width 0.2)
			(type default)
		)
		(layer "In3.Cu")
	)
	(gr_line
		(start 127 -54.642004)
		(end 126.000256 -54.642004)
		(stroke
			(width 0.2)
			(type default)
		)
		(layer "In3.Cu")
	)
	(gr_arc
		(start 127 -54.358286)
		(mid 127.35814 -54.000146)
		(end 127 -53.642006)
		(stroke
			(width 0.2)
			(type default)
		)
		(layer "In3.Cu")
	)
	(gr_line
		(start 127 -53.642006)
		(end 126.000256 -53.642006)
		(stroke
			(width 0.2)
			(type default)
		)
		(layer "In3.Cu")
	)
	(gr_line
		(start 127 -53.358288)
		(end 127.999998 -53.358288)
		(stroke
			(width 0.2)
			(type default)
		)
		(layer "In3.Cu")
	)
	(gr_arc
		(start 127.000254 -52.642008)
		(mid 126.64186 -53.000021)
		(end 127 -53.358288)
		(stroke
			(width 0.2)
			(type default)
		)
		(layer "In3.Cu")
	)
	(gr_line
		(start 127.533908 -46.987206)
		(end 127.533908 -45.844206)
		(stroke
			(width 0.2)
			(type default)
		)
		(layer "In3.Cu")
	)
	(gr_arc
		(start 127.533908 -45.844206)
		(mid 127.076708 -45.387006)
		(end 126.619508 -45.844206)
		(stroke
			(width 0.2)
			(type default)
		)
		(layer "In3.Cu")
	)
	(gr_line
		(start 127.96139 -11.20013)
		(end 127.96139 -9.800082)
		(stroke
			(width 0.2)
			(type default)
		)
		(layer "In3.Cu")
	)
	(gr_arc
		(start 127.96139 -9.800082)
		(mid 127.40005 -9.238742)
		(end 126.83871 -9.800082)
		(stroke
			(width 0.2)
			(type default)
		)
		(layer "In3.Cu")
	)
	(gr_line
		(start 127.96139 -3.999992)
		(end 127.96139 -2.600198)
		(stroke
			(width 0.2)
			(type default)
		)
		(layer "In3.Cu")
	)
	(gr_arc
		(start 127.96139 -2.600198)
		(mid 127.40005 -2.038858)
		(end 126.83871 -2.600198)
		(stroke
			(width 0.2)
			(type default)
		)
		(layer "In3.Cu")
	)
	(gr_arc
		(start 127.999998 -53.358288)
		(mid 128.358138 -53.000148)
		(end 127.999998 -52.642008)
		(stroke
			(width 0.2)
			(type default)
		)
		(layer "In3.Cu")
	)
	(gr_line
		(start 127.999998 -52.642008)
		(end 127.000254 -52.642008)
		(stroke
			(width 0.2)
			(type default)
		)
		(layer "In3.Cu")
	)
	(gr_arc
		(start 128.638808 -12.399772)
		(mid 129.200021 -12.961366)
		(end 129.761488 -12.400026)
		(stroke
			(width 0.2)
			(type default)
		)
		(layer "In3.Cu")
	)
	(gr_line
		(start 128.638808 -10.999978)
		(end 128.638808 -12.399772)
		(stroke
			(width 0.2)
			(type default)
		)
		(layer "In3.Cu")
	)
	(gr_arc
		(start 128.638808 -5.199888)
		(mid 129.200021 -5.761482)
		(end 129.761488 -5.200142)
		(stroke
			(width 0.2)
			(type default)
		)
		(layer "In3.Cu")
	)
	(gr_line
		(start 128.638808 -3.800094)
		(end 128.638808 -5.199888)
		(stroke
			(width 0.2)
			(type default)
		)
		(layer "In3.Cu")
	)
	(gr_line
		(start 128.999996 -72.35825)
		(end 129.999994 -72.35825)
		(stroke
			(width 0.2)
			(type default)
		)
		(layer "In3.Cu")
	)
	(gr_line
		(start 128.999996 -70.358254)
		(end 129.999994 -70.358254)
		(stroke
			(width 0.2)
			(type default)
		)
		(layer "In3.Cu")
	)
	(gr_line
		(start 128.999996 -68.358258)
		(end 129.999994 -68.358258)
		(stroke
			(width 0.2)
			(type default)
		)
		(layer "In3.Cu")
	)
	(gr_line
		(start 128.999996 -65.358264)
		(end 129.999994 -65.358264)
		(stroke
			(width 0.2)
			(type default)
		)
		(layer "In3.Cu")
	)
	(gr_line
		(start 128.999996 -63.358268)
		(end 129.999994 -63.358268)
		(stroke
			(width 0.2)
			(type default)
		)
		(layer "In3.Cu")
	)
	(gr_line
		(start 128.999996 -61.358272)
		(end 129.999994 -61.358272)
		(stroke
			(width 0.2)
			(type default)
		)
		(layer "In3.Cu")
	)
	(gr_arc
		(start 129.00025 -71.64197)
		(mid 128.641856 -71.999983)
		(end 128.999996 -72.35825)
		(stroke
			(width 0.2)
			(type default)
		)
		(layer "In3.Cu")
	)
	(gr_arc
		(start 129.00025 -69.641974)
		(mid 128.641856 -69.999987)
		(end 128.999996 -70.358254)
		(stroke
			(width 0.2)
			(type default)
		)
		(layer "In3.Cu")
	)
	(gr_arc
		(start 129.00025 -67.641978)
		(mid 128.641856 -67.999991)
		(end 128.999996 -68.358258)
		(stroke
			(width 0.2)
			(type default)
		)
		(layer "In3.Cu")
	)
	(gr_arc
		(start 129.00025 -64.641984)
		(mid 128.641856 -64.999997)
		(end 128.999996 -65.358264)
		(stroke
			(width 0.2)
			(type default)
		)
		(layer "In3.Cu")
	)
	(gr_arc
		(start 129.00025 -62.641988)
		(mid 128.641856 -63.000001)
		(end 128.999996 -63.358268)
		(stroke
			(width 0.2)
			(type default)
		)
		(layer "In3.Cu")
	)
	(gr_arc
		(start 129.00025 -60.641992)
		(mid 128.641856 -61.000005)
		(end 128.999996 -61.358272)
		(stroke
			(width 0.2)
			(type default)
		)
		(layer "In3.Cu")
	)
	(gr_arc
		(start 129.191258 -46.97222)
		(mid 129.648331 -47.429674)
		(end 130.105658 -46.972474)
		(stroke
			(width 0.2)
			(type default)
		)
		(layer "In3.Cu")
	)
	(gr_line
		(start 129.191258 -45.829474)
		(end 129.191258 -46.97222)
		(stroke
			(width 0.2)
			(type default)
		)
		(layer "In3.Cu")
	)
	(gr_line
		(start 129.761488 -12.400026)
		(end 129.761488 -10.999978)
		(stroke
			(width 0.2)
			(type default)
		)
		(layer "In3.Cu")
	)
	(gr_arc
		(start 129.761488 -10.999978)
		(mid 129.200148 -10.438638)
		(end 128.638808 -10.999978)
		(stroke
			(width 0.2)
			(type default)
		)
		(layer "In3.Cu")
	)
	(gr_line
		(start 129.761488 -5.200142)
		(end 129.761488 -3.800094)
		(stroke
			(width 0.2)
			(type default)
		)
		(layer "In3.Cu")
	)
	(gr_arc
		(start 129.761488 -3.800094)
		(mid 129.200148 -3.238754)
		(end 128.638808 -3.800094)
		(stroke
			(width 0.2)
			(type default)
		)
		(layer "In3.Cu")
	)
	(gr_line
		(start 129.999994 -73.358248)
		(end 130.999992 -73.358248)
		(stroke
			(width 0.2)
			(type default)
		)
		(layer "In3.Cu")
	)
	(gr_arc
		(start 129.999994 -72.35825)
		(mid 130.358134 -72.00011)
		(end 129.999994 -71.64197)
		(stroke
			(width 0.2)
			(type default)
		)
		(layer "In3.Cu")
	)
	(gr_line
		(start 129.999994 -71.64197)
		(end 129.00025 -71.64197)
		(stroke
			(width 0.2)
			(type default)
		)
		(layer "In3.Cu")
	)
	(gr_line
		(start 129.999994 -71.358252)
		(end 130.999992 -71.358252)
		(stroke
			(width 0.2)
			(type default)
		)
		(layer "In3.Cu")
	)
	(gr_arc
		(start 129.999994 -70.358254)
		(mid 130.358134 -70.000114)
		(end 129.999994 -69.641974)
		(stroke
			(width 0.2)
			(type default)
		)
		(layer "In3.Cu")
	)
	(gr_line
		(start 129.999994 -69.641974)
		(end 129.00025 -69.641974)
		(stroke
			(width 0.2)
			(type default)
		)
		(layer "In3.Cu")
	)
	(gr_line
		(start 129.999994 -69.358256)
		(end 130.999992 -69.358256)
		(stroke
			(width 0.2)
			(type default)
		)
		(layer "In3.Cu")
	)
	(gr_arc
		(start 129.999994 -68.358258)
		(mid 130.358134 -68.000118)
		(end 129.999994 -67.641978)
		(stroke
			(width 0.2)
			(type default)
		)
		(layer "In3.Cu")
	)
	(gr_line
		(start 129.999994 -67.641978)
		(end 129.00025 -67.641978)
		(stroke
			(width 0.2)
			(type default)
		)
		(layer "In3.Cu")
	)
	(gr_line
		(start 129.999994 -66.358262)
		(end 130.999992 -66.358262)
		(stroke
			(width 0.2)
			(type default)
		)
		(layer "In3.Cu")
	)
	(gr_arc
		(start 129.999994 -65.358264)
		(mid 130.358134 -65.000124)
		(end 129.999994 -64.641984)
		(stroke
			(width 0.2)
			(type default)
		)
		(layer "In3.Cu")
	)
	(gr_line
		(start 129.999994 -64.641984)
		(end 129.00025 -64.641984)
		(stroke
			(width 0.2)
			(type default)
		)
		(layer "In3.Cu")
	)
	(gr_line
		(start 129.999994 -64.358266)
		(end 130.999992 -64.358266)
		(stroke
			(width 0.2)
			(type default)
		)
		(layer "In3.Cu")
	)
	(gr_arc
		(start 129.999994 -63.358268)
		(mid 130.358134 -63.000128)
		(end 129.999994 -62.641988)
		(stroke
			(width 0.2)
			(type default)
		)
		(layer "In3.Cu")
	)
	(gr_line
		(start 129.999994 -62.641988)
		(end 129.00025 -62.641988)
		(stroke
			(width 0.2)
			(type default)
		)
		(layer "In3.Cu")
	)
	(gr_line
		(start 129.999994 -62.35827)
		(end 130.999992 -62.35827)
		(stroke
			(width 0.2)
			(type default)
		)
		(layer "In3.Cu")
	)
	(gr_arc
		(start 129.999994 -61.358272)
		(mid 130.358134 -61.000132)
		(end 129.999994 -60.641992)
		(stroke
			(width 0.2)
			(type default)
		)
		(layer "In3.Cu")
	)
	(gr_line
		(start 129.999994 -60.641992)
		(end 129.00025 -60.641992)
		(stroke
			(width 0.2)
			(type default)
		)
		(layer "In3.Cu")
	)
	(gr_arc
		(start 130.000248 -72.641968)
		(mid 129.641854 -72.999981)
		(end 129.999994 -73.358248)
		(stroke
			(width 0.2)
			(type default)
		)
		(layer "In3.Cu")
	)
	(gr_arc
		(start 130.000248 -70.641972)
		(mid 129.641854 -70.999985)
		(end 129.999994 -71.358252)
		(stroke
			(width 0.2)
			(type default)
		)
		(layer "In3.Cu")
	)
	(gr_arc
		(start 130.000248 -68.641976)
		(mid 129.641854 -68.999989)
		(end 129.999994 -69.358256)
		(stroke
			(width 0.2)
			(type default)
		)
		(layer "In3.Cu")
	)
	(gr_arc
		(start 130.000248 -65.641982)
		(mid 129.641854 -65.999995)
		(end 129.999994 -66.358262)
		(stroke
			(width 0.2)
			(type default)
		)
		(layer "In3.Cu")
	)
	(gr_arc
		(start 130.000248 -63.641986)
		(mid 129.641854 -63.999999)
		(end 129.999994 -64.358266)
		(stroke
			(width 0.2)
			(type default)
		)
		(layer "In3.Cu")
	)
	(gr_arc
		(start 130.000248 -61.64199)
		(mid 129.641854 -62.000003)
		(end 129.999994 -62.35827)
		(stroke
			(width 0.2)
			(type default)
		)
		(layer "In3.Cu")
	)
	(gr_line
		(start 130.105658 -46.972474)
		(end 130.105658 -45.829474)
		(stroke
			(width 0.2)
			(type default)
		)
		(layer "In3.Cu")
	)
	(gr_arc
		(start 130.105658 -45.829474)
		(mid 129.648458 -45.372274)
		(end 129.191258 -45.829474)
		(stroke
			(width 0.2)
			(type default)
		)
		(layer "In3.Cu")
	)
	(gr_arc
		(start 130.438652 -11.199876)
		(mid 130.999865 -11.76147)
		(end 131.561332 -11.20013)
		(stroke
			(width 0.2)
			(type default)
		)
		(layer "In3.Cu")
	)
	(gr_line
		(start 130.438652 -9.800082)
		(end 130.438652 -11.199876)
		(stroke
			(width 0.2)
			(type default)
		)
		(layer "In3.Cu")
	)
	(gr_arc
		(start 130.438652 -3.999738)
		(mid 130.999865 -4.561332)
		(end 131.561332 -3.999992)
		(stroke
			(width 0.2)
			(type default)
		)
		(layer "In3.Cu")
	)
	(gr_line
		(start 130.438652 -2.600198)
		(end 130.438652 -3.999738)
		(stroke
			(width 0.2)
			(type default)
		)
		(layer "In3.Cu")
	)
	(gr_arc
		(start 130.999992 -73.358248)
		(mid 131.358132 -73.000108)
		(end 130.999992 -72.641968)
		(stroke
			(width 0.2)
			(type default)
		)
		(layer "In3.Cu")
	)
	(gr_line
		(start 130.999992 -72.641968)
		(end 130.000248 -72.641968)
		(stroke
			(width 0.2)
			(type default)
		)
		(layer "In3.Cu")
	)
	(gr_arc
		(start 130.999992 -71.358252)
		(mid 131.358132 -71.000112)
		(end 130.999992 -70.641972)
		(stroke
			(width 0.2)
			(type default)
		)
		(layer "In3.Cu")
	)
	(gr_line
		(start 130.999992 -70.641972)
		(end 130.000248 -70.641972)
		(stroke
			(width 0.2)
			(type default)
		)
		(layer "In3.Cu")
	)
	(gr_arc
		(start 130.999992 -69.358256)
		(mid 131.358132 -69.000116)
		(end 130.999992 -68.641976)
		(stroke
			(width 0.2)
			(type default)
		)
		(layer "In3.Cu")
	)
	(gr_line
		(start 130.999992 -68.641976)
		(end 130.000248 -68.641976)
		(stroke
			(width 0.2)
			(type default)
		)
		(layer "In3.Cu")
	)
	(gr_arc
		(start 130.999992 -66.358262)
		(mid 131.358132 -66.000122)
		(end 130.999992 -65.641982)
		(stroke
			(width 0.2)
			(type default)
		)
		(layer "In3.Cu")
	)
	(gr_line
		(start 130.999992 -65.641982)
		(end 130.000248 -65.641982)
		(stroke
			(width 0.2)
			(type default)
		)
		(layer "In3.Cu")
	)
	(gr_arc
		(start 130.999992 -64.358266)
		(mid 131.358132 -64.000126)
		(end 130.999992 -63.641986)
		(stroke
			(width 0.2)
			(type default)
		)
		(layer "In3.Cu")
	)
	(gr_line
		(start 130.999992 -63.641986)
		(end 130.000248 -63.641986)
		(stroke
			(width 0.2)
			(type default)
		)
		(layer "In3.Cu")
	)
	(gr_arc
		(start 130.999992 -62.35827)
		(mid 131.358132 -62.00013)
		(end 130.999992 -61.64199)
		(stroke
			(width 0.2)
			(type default)
		)
		(layer "In3.Cu")
	)
	(gr_line
		(start 130.999992 -61.64199)
		(end 130.000248 -61.64199)
		(stroke
			(width 0.2)
			(type default)
		)
		(layer "In3.Cu")
	)
	(gr_line
		(start 131.561332 -11.20013)
		(end 131.561332 -9.800082)
		(stroke
			(width 0.2)
			(type default)
		)
		(layer "In3.Cu")
	)
	(gr_arc
		(start 131.561332 -9.800082)
		(mid 130.999992 -9.238742)
		(end 130.438652 -9.800082)
		(stroke
			(width 0.2)
			(type default)
		)
		(layer "In3.Cu")
	)
	(gr_line
		(start 131.561332 -3.999992)
		(end 131.561332 -2.600198)
		(stroke
			(width 0.2)
			(type default)
		)
		(layer "In3.Cu")
	)
	(gr_arc
		(start 131.561332 -2.600198)
		(mid 130.999992 -2.038858)
		(end 130.438652 -2.600198)
		(stroke
			(width 0.2)
			(type default)
		)
		(layer "In3.Cu")
	)
	(gr_arc
		(start 131.763008 -46.957488)
		(mid 132.220081 -47.414942)
		(end 132.677408 -46.957742)
		(stroke
			(width 0.2)
			(type default)
		)
		(layer "In3.Cu")
	)
	(gr_line
		(start 131.763008 -45.814742)
		(end 131.763008 -46.957488)
		(stroke
			(width 0.2)
			(type default)
		)
		(layer "In3.Cu")
	)
	(gr_circle
		(center 132.03936 -95.463614)
		(end 132.039614 -95.463614)
		(stroke
			(width 0.381)
			(type default)
		)
		(fill no)
		(layer "In3.Cu")
	)
	(gr_line
		(start 132.03936 -95.46336)
		(end 70.19036 -95.46336)
		(stroke
			(width 0.381)
			(type default)
		)
		(layer "In3.Cu")
	)
	(gr_arc
		(start 132.23875 -12.399772)
		(mid 132.799963 -12.961366)
		(end 133.36143 -12.400026)
		(stroke
			(width 0.2)
			(type default)
		)
		(layer "In3.Cu")
	)
	(gr_line
		(start 132.23875 -10.999978)
		(end 132.23875 -12.399772)
		(stroke
			(width 0.2)
			(type default)
		)
		(layer "In3.Cu")
	)
	(gr_arc
		(start 132.23875 -5.199888)
		(mid 132.799963 -5.761482)
		(end 133.36143 -5.200142)
		(stroke
			(width 0.2)
			(type default)
		)
		(layer "In3.Cu")
	)
	(gr_line
		(start 132.23875 -3.800094)
		(end 132.23875 -5.199888)
		(stroke
			(width 0.2)
			(type default)
		)
		(layer "In3.Cu")
	)
	(gr_line
		(start 132.677408 -46.957742)
		(end 132.677408 -45.814742)
		(stroke
			(width 0.2)
			(type default)
		)
		(layer "In3.Cu")
	)
	(gr_arc
		(start 132.677408 -45.814742)
		(mid 132.220208 -45.357542)
		(end 131.763008 -45.814742)
		(stroke
			(width 0.2)
			(type default)
		)
		(layer "In3.Cu")
	)
	(gr_line
		(start 133.36143 -12.400026)
		(end 133.36143 -10.999978)
		(stroke
			(width 0.2)
			(type default)
		)
		(layer "In3.Cu")
	)
	(gr_arc
		(start 133.36143 -10.999978)
		(mid 132.80009 -10.438638)
		(end 132.23875 -10.999978)
		(stroke
			(width 0.2)
			(type default)
		)
		(layer "In3.Cu")
	)
	(gr_line
		(start 133.36143 -5.200142)
		(end 133.36143 -3.800094)
		(stroke
			(width 0.2)
			(type default)
		)
		(layer "In3.Cu")
	)
	(gr_arc
		(start 133.36143 -3.800094)
		(mid 132.80009 -3.238754)
		(end 132.23875 -3.800094)
		(stroke
			(width 0.2)
			(type default)
		)
		(layer "In3.Cu")
	)
	(gr_line
		(start 133.84784 -97.27184)
		(end 132.03936 -95.46336)
		(stroke
			(width 0.381)
			(type default)
		)
		(layer "In3.Cu")
	)
	(gr_circle
		(center 133.84784 -97.271586)
		(end 133.848094 -97.271586)
		(stroke
			(width 0.381)
			(type default)
		)
		(fill no)
		(layer "In3.Cu")
	)
	(gr_arc
		(start 134.038848 -11.199876)
		(mid 134.600061 -11.76147)
		(end 135.161528 -11.20013)
		(stroke
			(width 0.2)
			(type default)
		)
		(layer "In3.Cu")
	)
	(gr_line
		(start 134.038848 -9.800082)
		(end 134.038848 -11.199876)
		(stroke
			(width 0.2)
			(type default)
		)
		(layer "In3.Cu")
	)
	(gr_arc
		(start 134.038848 -3.999738)
		(mid 134.600061 -4.561332)
		(end 135.161528 -3.999992)
		(stroke
			(width 0.2)
			(type default)
		)
		(layer "In3.Cu")
	)
	(gr_line
		(start 134.038848 -2.600198)
		(end 134.038848 -3.999738)
		(stroke
			(width 0.2)
			(type default)
		)
		(layer "In3.Cu")
	)
	(gr_line
		(start 135.161528 -11.20013)
		(end 135.161528 -9.800082)
		(stroke
			(width 0.2)
			(type default)
		)
		(layer "In3.Cu")
	)
	(gr_arc
		(start 135.161528 -9.800082)
		(mid 134.600188 -9.238742)
		(end 134.038848 -9.800082)
		(stroke
			(width 0.2)
			(type default)
		)
		(layer "In3.Cu")
	)
	(gr_line
		(start 135.161528 -3.999992)
		(end 135.161528 -2.600198)
		(stroke
			(width 0.2)
			(type default)
		)
		(layer "In3.Cu")
	)
	(gr_arc
		(start 135.161528 -2.600198)
		(mid 134.600188 -2.038858)
		(end 134.038848 -2.600198)
		(stroke
			(width 0.2)
			(type default)
		)
		(layer "In3.Cu")
	)
	(gr_arc
		(start 135.838692 -12.399772)
		(mid 136.399905 -12.961366)
		(end 136.961372 -12.400026)
		(stroke
			(width 0.2)
			(type default)
		)
		(layer "In3.Cu")
	)
	(gr_line
		(start 135.838692 -10.999978)
		(end 135.838692 -12.399772)
		(stroke
			(width 0.2)
			(type default)
		)
		(layer "In3.Cu")
	)
	(gr_arc
		(start 135.838692 -5.199888)
		(mid 136.399905 -5.761482)
		(end 136.961372 -5.200142)
		(stroke
			(width 0.2)
			(type default)
		)
		(layer "In3.Cu")
	)
	(gr_line
		(start 135.838692 -3.800094)
		(end 135.838692 -5.199888)
		(stroke
			(width 0.2)
			(type default)
		)
		(layer "In3.Cu")
	)
	(gr_line
		(start 136.19988 -97.27184)
		(end 133.84784 -97.27184)
		(stroke
			(width 0.381)
			(type default)
		)
		(layer "In3.Cu")
	)
	(gr_circle
		(center 136.19988 -97.271586)
		(end 136.200134 -97.271586)
		(stroke
			(width 0.381)
			(type default)
		)
		(fill no)
		(layer "In3.Cu")
	)
	(gr_line
		(start 136.961372 -12.400026)
		(end 136.961372 -10.999978)
		(stroke
			(width 0.2)
			(type default)
		)
		(layer "In3.Cu")
	)
	(gr_arc
		(start 136.961372 -10.999978)
		(mid 136.400032 -10.438638)
		(end 135.838692 -10.999978)
		(stroke
			(width 0.2)
			(type default)
		)
		(layer "In3.Cu")
	)
	(gr_line
		(start 136.961372 -5.200142)
		(end 136.961372 -3.800094)
		(stroke
			(width 0.2)
			(type default)
		)
		(layer "In3.Cu")
	)
	(gr_arc
		(start 136.961372 -3.800094)
		(mid 136.400032 -3.238754)
		(end 135.838692 -3.800094)
		(stroke
			(width 0.2)
			(type default)
		)
		(layer "In3.Cu")
	)
	(gr_arc
		(start 137.63879 -11.199876)
		(mid 138.200003 -11.76147)
		(end 138.76147 -11.20013)
		(stroke
			(width 0.2)
			(type default)
		)
		(layer "In3.Cu")
	)
	(gr_line
		(start 137.63879 -9.800082)
		(end 137.63879 -11.199876)
		(stroke
			(width 0.2)
			(type default)
		)
		(layer "In3.Cu")
	)
	(gr_arc
		(start 137.63879 -3.999738)
		(mid 138.200003 -4.561332)
		(end 138.76147 -3.999992)
		(stroke
			(width 0.2)
			(type default)
		)
		(layer "In3.Cu")
	)
	(gr_line
		(start 137.63879 -2.600198)
		(end 137.63879 -3.999738)
		(stroke
			(width 0.2)
			(type default)
		)
		(layer "In3.Cu")
	)
	(gr_circle
		(center 138.38174 -95.090234)
		(end 138.381994 -95.090234)
		(stroke
			(width 0.381)
			(type default)
		)
		(fill no)
		(layer "In3.Cu")
	)
	(gr_line
		(start 138.38174 -95.08998)
		(end 136.19988 -97.27184)
		(stroke
			(width 0.381)
			(type default)
		)
		(layer "In3.Cu")
	)
	(gr_line
		(start 138.479022 -76.90866)
		(end 139.622022 -76.90866)
		(stroke
			(width 0.2)
			(type default)
		)
		(layer "In3.Cu")
	)
	(gr_line
		(start 138.479022 -76.907898)
		(end 138.479022 -76.90866)
		(stroke
			(width 0.2)
			(type default)
		)
		(layer "In3.Cu")
	)
	(gr_arc
		(start 138.479022 -76.142342)
		(mid 138.096244 -76.52512)
		(end 138.479022 -76.907898)
		(stroke
			(width 0.2)
			(type default)
		)
		(layer "In3.Cu")
	)
	(gr_line
		(start 138.479022 -76.141834)
		(end 138.479022 -76.142342)
		(stroke
			(width 0.2)
			(type default)
		)
		(layer "In3.Cu")
	)
	(gr_line
		(start 138.479276 -76.14158)
		(end 138.479022 -76.141834)
		(stroke
			(width 0.2)
			(type default)
		)
		(layer "In3.Cu")
	)
	(gr_line
		(start 138.486134 -78.811374)
		(end 139.62888 -78.811374)
		(stroke
			(width 0.2)
			(type default)
		)
		(layer "In3.Cu")
	)
	(gr_line
		(start 138.486134 -78.810612)
		(end 138.486134 -78.811374)
		(stroke
			(width 0.2)
			(type default)
		)
		(layer "In3.Cu")
	)
	(gr_arc
		(start 138.486134 -78.045056)
		(mid 138.103356 -78.427834)
		(end 138.486134 -78.810612)
		(stroke
			(width 0.2)
			(type default)
		)
		(layer "In3.Cu")
	)
	(gr_line
		(start 138.486134 -78.044294)
		(end 138.486134 -78.045056)
		(stroke
			(width 0.2)
			(type default)
		)
		(layer "In3.Cu")
	)
	(gr_line
		(start 138.500612 -80.580992)
		(end 139.643612 -80.580992)
		(stroke
			(width 0.2)
			(type default)
		)
		(layer "In3.Cu")
	)
	(gr_line
		(start 138.500612 -80.58023)
		(end 138.500612 -80.580992)
		(stroke
			(width 0.2)
			(type default)
		)
		(layer "In3.Cu")
	)
	(gr_arc
		(start 138.500612 -79.814674)
		(mid 138.117834 -80.197452)
		(end 138.500612 -80.58023)
		(stroke
			(width 0.2)
			(type default)
		)
		(layer "In3.Cu")
	)
	(gr_line
		(start 138.500612 -79.814166)
		(end 138.500612 -79.814674)
		(stroke
			(width 0.2)
			(type default)
		)
		(layer "In3.Cu")
	)
	(gr_line
		(start 138.500866 -79.813912)
		(end 138.500612 -79.814166)
		(stroke
			(width 0.2)
			(type default)
		)
		(layer "In3.Cu")
	)
	(gr_circle
		(center 138.59002 -95.090234)
		(end 138.590274 -95.090234)
		(stroke
			(width 0.381)
			(type default)
		)
		(fill no)
		(layer "In3.Cu")
	)
	(gr_line
		(start 138.739118 -65.426844)
		(end 139.881864 -65.426844)
		(stroke
			(width 0.2)
			(type default)
		)
		(layer "In3.Cu")
	)
	(gr_arc
		(start 138.739118 -64.517524)
		(mid 138.284458 -64.972184)
		(end 138.739118 -65.426844)
		(stroke
			(width 0.2)
			(type default)
		)
		(layer "In3.Cu")
	)
	(gr_line
		(start 138.76147 -11.20013)
		(end 138.76147 -9.800082)
		(stroke
			(width 0.2)
			(type default)
		)
		(layer "In3.Cu")
	)
	(gr_arc
		(start 138.76147 -9.800082)
		(mid 138.20013 -9.238742)
		(end 137.63879 -9.800082)
		(stroke
			(width 0.2)
			(type default)
		)
		(layer "In3.Cu")
	)
	(gr_line
		(start 138.76147 -3.999992)
		(end 138.76147 -2.600198)
		(stroke
			(width 0.2)
			(type default)
		)
		(layer "In3.Cu")
	)
	(gr_arc
		(start 138.76147 -2.600198)
		(mid 138.20013 -2.038858)
		(end 137.63879 -2.600198)
		(stroke
			(width 0.2)
			(type default)
		)
		(layer "In3.Cu")
	)
	(gr_line
		(start 138.80465 -63.499746)
		(end 139.947396 -63.499746)
		(stroke
			(width 0.2)
			(type default)
		)
		(layer "In3.Cu")
	)
	(gr_arc
		(start 138.80465 -62.590426)
		(mid 138.34999 -63.045086)
		(end 138.80465 -63.499746)
		(stroke
			(width 0.2)
			(type default)
		)
		(layer "In3.Cu")
	)
	(gr_line
		(start 138.843258 -82.691986)
		(end 139.986258 -82.691986)
		(stroke
			(width 0.2)
			(type default)
		)
		(layer "In3.Cu")
	)
	(gr_line
		(start 138.843258 -82.691224)
		(end 138.843258 -82.691986)
		(stroke
			(width 0.2)
			(type default)
		)
		(layer "In3.Cu")
	)
	(gr_arc
		(start 138.843258 -81.925668)
		(mid 138.46048 -82.308446)
		(end 138.843258 -82.691224)
		(stroke
			(width 0.2)
			(type default)
		)
		(layer "In3.Cu")
	)
	(gr_line
		(start 138.843258 -81.92516)
		(end 138.843258 -81.925668)
		(stroke
			(width 0.2)
			(type default)
		)
		(layer "In3.Cu")
	)
	(gr_line
		(start 138.843512 -81.924906)
		(end 138.843258 -81.92516)
		(stroke
			(width 0.2)
			(type default)
		)
		(layer "In3.Cu")
	)
	(gr_line
		(start 139.03071 -61.576712)
		(end 140.173456 -61.576712)
		(stroke
			(width 0.2)
			(type default)
		)
		(layer "In3.Cu")
	)
	(gr_arc
		(start 139.03071 -60.667392)
		(mid 138.57605 -61.122052)
		(end 139.03071 -61.576712)
		(stroke
			(width 0.2)
			(type default)
		)
		(layer "In3.Cu")
	)
	(gr_arc
		(start 139.438634 -12.399772)
		(mid 139.999847 -12.961366)
		(end 140.561314 -12.400026)
		(stroke
			(width 0.2)
			(type default)
		)
		(layer "In3.Cu")
	)
	(gr_line
		(start 139.438634 -10.999978)
		(end 139.438634 -12.399772)
		(stroke
			(width 0.2)
			(type default)
		)
		(layer "In3.Cu")
	)
	(gr_arc
		(start 139.438634 -5.199888)
		(mid 139.999847 -5.761482)
		(end 140.561314 -5.200142)
		(stroke
			(width 0.2)
			(type default)
		)
		(layer "In3.Cu")
	)
	(gr_line
		(start 139.438634 -3.800094)
		(end 139.438634 -5.199888)
		(stroke
			(width 0.2)
			(type default)
		)
		(layer "In3.Cu")
	)
	(gr_line
		(start 139.446 -59.35726)
		(end 140.588746 -59.35726)
		(stroke
			(width 0.2)
			(type default)
		)
		(layer "In3.Cu")
	)
	(gr_arc
		(start 139.446 -58.44794)
		(mid 138.99134 -58.9026)
		(end 139.446 -59.35726)
		(stroke
			(width 0.2)
			(type default)
		)
		(layer "In3.Cu")
	)
	(gr_line
		(start 139.622022 -76.90866)
		(end 139.622022 -76.907898)
		(stroke
			(width 0.2)
			(type default)
		)
		(layer "In3.Cu")
	)
	(gr_arc
		(start 139.622022 -76.907898)
		(mid 140.0048 -76.52512)
		(end 139.622022 -76.142342)
		(stroke
			(width 0.2)
			(type default)
		)
		(layer "In3.Cu")
	)
	(gr_line
		(start 139.622022 -76.142342)
		(end 139.622022 -76.14158)
		(stroke
			(width 0.2)
			(type default)
		)
		(layer "In3.Cu")
	)
	(gr_line
		(start 139.622022 -76.14158)
		(end 138.479276 -76.14158)
		(stroke
			(width 0.2)
			(type default)
		)
		(layer "In3.Cu")
	)
	(gr_line
		(start 139.62888 -78.811374)
		(end 139.629134 -78.81112)
		(stroke
			(width 0.2)
			(type default)
		)
		(layer "In3.Cu")
	)
	(gr_line
		(start 139.629134 -78.81112)
		(end 139.629134 -78.810612)
		(stroke
			(width 0.2)
			(type default)
		)
		(layer "In3.Cu")
	)
	(gr_arc
		(start 139.629134 -78.810612)
		(mid 140.011912 -78.427834)
		(end 139.629134 -78.045056)
		(stroke
			(width 0.2)
			(type default)
		)
		(layer "In3.Cu")
	)
	(gr_line
		(start 139.629134 -78.045056)
		(end 139.629134 -78.044294)
		(stroke
			(width 0.2)
			(type default)
		)
		(layer "In3.Cu")
	)
	(gr_line
		(start 139.629134 -78.044294)
		(end 138.486134 -78.044294)
		(stroke
			(width 0.2)
			(type default)
		)
		(layer "In3.Cu")
	)
	(gr_line
		(start 139.643612 -80.580992)
		(end 139.643612 -80.58023)
		(stroke
			(width 0.2)
			(type default)
		)
		(layer "In3.Cu")
	)
	(gr_arc
		(start 139.643612 -80.58023)
		(mid 140.02639 -80.197452)
		(end 139.643612 -79.814674)
		(stroke
			(width 0.2)
			(type default)
		)
		(layer "In3.Cu")
	)
	(gr_line
		(start 139.643612 -79.814674)
		(end 139.643612 -79.813912)
		(stroke
			(width 0.2)
			(type default)
		)
		(layer "In3.Cu")
	)
	(gr_line
		(start 139.643612 -79.813912)
		(end 138.500866 -79.813912)
		(stroke
			(width 0.2)
			(type default)
		)
		(layer "In3.Cu")
	)
	(gr_arc
		(start 139.881864 -65.426844)
		(mid 140.336778 -64.972311)
		(end 139.882118 -64.517524)
		(stroke
			(width 0.2)
			(type default)
		)
		(layer "In3.Cu")
	)
	(gr_line
		(start 139.882118 -64.517524)
		(end 138.739118 -64.517524)
		(stroke
			(width 0.2)
			(type default)
		)
		(layer "In3.Cu")
	)
	(gr_arc
		(start 139.947396 -63.499746)
		(mid 140.40231 -63.045213)
		(end 139.94765 -62.590426)
		(stroke
			(width 0.2)
			(type default)
		)
		(layer "In3.Cu")
	)
	(gr_line
		(start 139.94765 -62.590426)
		(end 138.80465 -62.590426)
		(stroke
			(width 0.2)
			(type default)
		)
		(layer "In3.Cu")
	)
	(gr_line
		(start 139.986258 -82.691986)
		(end 139.986258 -82.691224)
		(stroke
			(width 0.2)
			(type default)
		)
		(layer "In3.Cu")
	)
	(gr_arc
		(start 139.986258 -82.691224)
		(mid 140.369036 -82.308446)
		(end 139.986258 -81.925668)
		(stroke
			(width 0.2)
			(type default)
		)
		(layer "In3.Cu")
	)
	(gr_line
		(start 139.986258 -81.925668)
		(end 139.986258 -81.924906)
		(stroke
			(width 0.2)
			(type default)
		)
		(layer "In3.Cu")
	)
	(gr_line
		(start 139.986258 -81.924906)
		(end 138.843512 -81.924906)
		(stroke
			(width 0.2)
			(type default)
		)
		(layer "In3.Cu")
	)
	(gr_arc
		(start 140.173456 -61.576712)
		(mid 140.62837 -61.122179)
		(end 140.17371 -60.667392)
		(stroke
			(width 0.2)
			(type default)
		)
		(layer "In3.Cu")
	)
	(gr_line
		(start 140.17371 -60.667392)
		(end 139.03071 -60.667392)
		(stroke
			(width 0.2)
			(type default)
		)
		(layer "In3.Cu")
	)
	(gr_line
		(start 140.561314 -12.400026)
		(end 140.561314 -10.999978)
		(stroke
			(width 0.2)
			(type default)
		)
		(layer "In3.Cu")
	)
	(gr_arc
		(start 140.561314 -10.999978)
		(mid 139.999974 -10.438638)
		(end 139.438634 -10.999978)
		(stroke
			(width 0.2)
			(type default)
		)
		(layer "In3.Cu")
	)
	(gr_line
		(start 140.561314 -5.200142)
		(end 140.561314 -3.800094)
		(stroke
			(width 0.2)
			(type default)
		)
		(layer "In3.Cu")
	)
	(gr_arc
		(start 140.561314 -3.800094)
		(mid 139.999974 -3.238754)
		(end 139.438634 -3.800094)
		(stroke
			(width 0.2)
			(type default)
		)
		(layer "In3.Cu")
	)
	(gr_arc
		(start 140.588746 -59.35726)
		(mid 141.04366 -58.902727)
		(end 140.589 -58.44794)
		(stroke
			(width 0.2)
			(type default)
		)
		(layer "In3.Cu")
	)
	(gr_line
		(start 140.589 -58.44794)
		(end 139.446 -58.44794)
		(stroke
			(width 0.2)
			(type default)
		)
		(layer "In3.Cu")
	)
	(gr_line
		(start 140.790676 -77.5208)
		(end 142.092172 -76.219304)
		(stroke
			(width 0.381)
			(type default)
		)
		(layer "In3.Cu")
	)
	(gr_arc
		(start 141.238732 -11.199876)
		(mid 141.799945 -11.76147)
		(end 142.361412 -11.20013)
		(stroke
			(width 0.2)
			(type default)
		)
		(layer "In3.Cu")
	)
	(gr_line
		(start 141.238732 -9.800082)
		(end 141.238732 -11.199876)
		(stroke
			(width 0.2)
			(type default)
		)
		(layer "In3.Cu")
	)
	(gr_arc
		(start 141.238732 -3.999738)
		(mid 141.799945 -4.561332)
		(end 142.361412 -3.999992)
		(stroke
			(width 0.2)
			(type default)
		)
		(layer "In3.Cu")
	)
	(gr_line
		(start 141.238732 -2.600198)
		(end 141.238732 -3.999738)
		(stroke
			(width 0.2)
			(type default)
		)
		(layer "In3.Cu")
	)
	(gr_line
		(start 142.092172 -76.219304)
		(end 142.092172 -47.351188)
		(stroke
			(width 0.381)
			(type default)
		)
		(layer "In3.Cu")
	)
	(gr_line
		(start 142.092172 -47.351188)
		(end 143.070834 -46.372526)
		(stroke
			(width 0.381)
			(type default)
		)
		(layer "In3.Cu")
	)
	(gr_line
		(start 142.361412 -11.20013)
		(end 142.361412 -9.800082)
		(stroke
			(width 0.2)
			(type default)
		)
		(layer "In3.Cu")
	)
	(gr_arc
		(start 142.361412 -9.800082)
		(mid 141.800072 -9.238742)
		(end 141.238732 -9.800082)
		(stroke
			(width 0.2)
			(type default)
		)
		(layer "In3.Cu")
	)
	(gr_line
		(start 142.361412 -3.999992)
		(end 142.361412 -2.600198)
		(stroke
			(width 0.2)
			(type default)
		)
		(layer "In3.Cu")
	)
	(gr_arc
		(start 142.361412 -2.600198)
		(mid 141.800072 -2.038858)
		(end 141.238732 -2.600198)
		(stroke
			(width 0.2)
			(type default)
		)
		(layer "In3.Cu")
	)
	(gr_line
		(start 142.539974 -30.226)
		(end 88.5952 -30.226)
		(stroke
			(width 0.381)
			(type default)
		)
		(layer "In3.Cu")
	)
	(gr_arc
		(start 143.03883 -12.399772)
		(mid 143.600043 -12.961366)
		(end 144.16151 -12.400026)
		(stroke
			(width 0.2)
			(type default)
		)
		(layer "In3.Cu")
	)
	(gr_line
		(start 143.03883 -10.999978)
		(end 143.03883 -12.399772)
		(stroke
			(width 0.2)
			(type default)
		)
		(layer "In3.Cu")
	)
	(gr_arc
		(start 143.03883 -5.199888)
		(mid 143.600043 -5.761482)
		(end 144.16151 -5.200142)
		(stroke
			(width 0.2)
			(type default)
		)
		(layer "In3.Cu")
	)
	(gr_line
		(start 143.03883 -3.800094)
		(end 143.03883 -5.199888)
		(stroke
			(width 0.2)
			(type default)
		)
		(layer "In3.Cu")
	)
	(gr_line
		(start 143.070834 -46.372526)
		(end 143.070834 -30.75686)
		(stroke
			(width 0.381)
			(type default)
		)
		(layer "In3.Cu")
	)
	(gr_line
		(start 143.070834 -30.75686)
		(end 142.539974 -30.226)
		(stroke
			(width 0.381)
			(type default)
		)
		(layer "In3.Cu")
	)
	(gr_line
		(start 144.16151 -12.400026)
		(end 144.16151 -10.999978)
		(stroke
			(width 0.2)
			(type default)
		)
		(layer "In3.Cu")
	)
	(gr_arc
		(start 144.16151 -10.999978)
		(mid 143.60017 -10.438638)
		(end 143.03883 -10.999978)
		(stroke
			(width 0.2)
			(type default)
		)
		(layer "In3.Cu")
	)
	(gr_line
		(start 144.16151 -5.200142)
		(end 144.16151 -3.800094)
		(stroke
			(width 0.2)
			(type default)
		)
		(layer "In3.Cu")
	)
	(gr_arc
		(start 144.16151 -3.800094)
		(mid 143.60017 -3.238754)
		(end 143.03883 -3.800094)
		(stroke
			(width 0.2)
			(type default)
		)
		(layer "In3.Cu")
	)
	(gr_arc
		(start 144.838674 -11.199876)
		(mid 145.399887 -11.76147)
		(end 145.961354 -11.20013)
		(stroke
			(width 0.2)
			(type default)
		)
		(layer "In3.Cu")
	)
	(gr_line
		(start 144.838674 -9.800082)
		(end 144.838674 -11.199876)
		(stroke
			(width 0.2)
			(type default)
		)
		(layer "In3.Cu")
	)
	(gr_arc
		(start 144.838674 -3.999738)
		(mid 145.399887 -4.561332)
		(end 145.961354 -3.999992)
		(stroke
			(width 0.2)
			(type default)
		)
		(layer "In3.Cu")
	)
	(gr_line
		(start 144.838674 -2.600198)
		(end 144.838674 -3.999738)
		(stroke
			(width 0.2)
			(type default)
		)
		(layer "In3.Cu")
	)
	(gr_arc
		(start 145.839434 -33.377886)
		(mid 146.191732 -33.920176)
		(end 146.734022 -33.567878)
		(stroke
			(width 0.2)
			(type default)
		)
		(layer "In3.Cu")
	)
	(gr_line
		(start 145.961354 -11.20013)
		(end 145.961354 -9.800082)
		(stroke
			(width 0.2)
			(type default)
		)
		(layer "In3.Cu")
	)
	(gr_arc
		(start 145.961354 -9.800082)
		(mid 145.400014 -9.238742)
		(end 144.838674 -9.800082)
		(stroke
			(width 0.2)
			(type default)
		)
		(layer "In3.Cu")
	)
	(gr_line
		(start 145.961354 -3.999992)
		(end 145.961354 -2.600198)
		(stroke
			(width 0.2)
			(type default)
		)
		(layer "In3.Cu")
	)
	(gr_arc
		(start 145.961354 -2.600198)
		(mid 145.400014 -2.038858)
		(end 144.838674 -2.600198)
		(stroke
			(width 0.2)
			(type default)
		)
		(layer "In3.Cu")
	)
	(gr_line
		(start 146.077178 -32.259778)
		(end 145.839434 -33.377886)
		(stroke
			(width 0.2)
			(type default)
		)
		(layer "In3.Cu")
	)
	(gr_arc
		(start 146.638772 -12.399772)
		(mid 147.199985 -12.961366)
		(end 147.761452 -12.400026)
		(stroke
			(width 0.2)
			(type default)
		)
		(layer "In3.Cu")
	)
	(gr_line
		(start 146.638772 -10.999978)
		(end 146.638772 -12.399772)
		(stroke
			(width 0.2)
			(type default)
		)
		(layer "In3.Cu")
	)
	(gr_arc
		(start 146.638772 -5.199888)
		(mid 147.199985 -5.761482)
		(end 147.761452 -5.200142)
		(stroke
			(width 0.2)
			(type default)
		)
		(layer "In3.Cu")
	)
	(gr_line
		(start 146.638772 -3.800094)
		(end 146.638772 -5.199888)
		(stroke
			(width 0.2)
			(type default)
		)
		(layer "In3.Cu")
	)
	(gr_line
		(start 146.734022 -33.567878)
		(end 146.969226 -32.460184)
		(stroke
			(width 0.2)
			(type default)
		)
		(layer "In3.Cu")
	)
	(gr_arc
		(start 146.859752 -47.469298)
		(mid 147.21205 -48.011588)
		(end 147.75434 -47.65929)
		(stroke
			(width 0.2)
			(type default)
		)
		(layer "In3.Cu")
	)
	(gr_arc
		(start 146.969226 -32.460184)
		(mid 146.624662 -31.908815)
		(end 146.077178 -32.259778)
		(stroke
			(width 0.2)
			(type default)
		)
		(layer "In3.Cu")
	)
	(gr_line
		(start 147.097496 -46.35119)
		(end 146.859752 -47.469298)
		(stroke
			(width 0.2)
			(type default)
		)
		(layer "In3.Cu")
	)
	(gr_line
		(start 147.75434 -47.65929)
		(end 147.989544 -46.551596)
		(stroke
			(width 0.2)
			(type default)
		)
		(layer "In3.Cu")
	)
	(gr_line
		(start 147.761452 -12.400026)
		(end 147.761452 -10.999978)
		(stroke
			(width 0.2)
			(type default)
		)
		(layer "In3.Cu")
	)
	(gr_arc
		(start 147.761452 -10.999978)
		(mid 147.200112 -10.438638)
		(end 146.638772 -10.999978)
		(stroke
			(width 0.2)
			(type default)
		)
		(layer "In3.Cu")
	)
	(gr_line
		(start 147.761452 -5.200142)
		(end 147.761452 -3.800094)
		(stroke
			(width 0.2)
			(type default)
		)
		(layer "In3.Cu")
	)
	(gr_arc
		(start 147.761452 -3.800094)
		(mid 147.200112 -3.238754)
		(end 146.638772 -3.800094)
		(stroke
			(width 0.2)
			(type default)
		)
		(layer "In3.Cu")
	)
	(gr_arc
		(start 147.907502 -51.437794)
		(mid 148.2598 -51.980084)
		(end 148.80209 -51.627786)
		(stroke
			(width 0.2)
			(type default)
		)
		(layer "In3.Cu")
	)
	(gr_arc
		(start 147.989544 -46.551596)
		(mid 147.64498 -46.000227)
		(end 147.097496 -46.35119)
		(stroke
			(width 0.2)
			(type default)
		)
		(layer "In3.Cu")
	)
	(gr_line
		(start 148.145246 -50.319686)
		(end 147.907502 -51.437794)
		(stroke
			(width 0.2)
			(type default)
		)
		(layer "In3.Cu")
	)
	(gr_arc
		(start 148.179536 -41.25849)
		(mid 148.531834 -41.80078)
		(end 149.074124 -41.448482)
		(stroke
			(width 0.2)
			(type default)
		)
		(layer "In3.Cu")
	)
	(gr_line
		(start 148.41728 -40.140382)
		(end 148.179536 -41.25849)
		(stroke
			(width 0.2)
			(type default)
		)
		(layer "In3.Cu")
	)
	(gr_arc
		(start 148.438616 -11.199876)
		(mid 148.999829 -11.76147)
		(end 149.561296 -11.20013)
		(stroke
			(width 0.2)
			(type default)
		)
		(layer "In3.Cu")
	)
	(gr_line
		(start 148.438616 -9.800082)
		(end 148.438616 -11.199876)
		(stroke
			(width 0.2)
			(type default)
		)
		(layer "In3.Cu")
	)
	(gr_arc
		(start 148.438616 -3.999738)
		(mid 148.999829 -4.561332)
		(end 149.561296 -3.999992)
		(stroke
			(width 0.2)
			(type default)
		)
		(layer "In3.Cu")
	)
	(gr_line
		(start 148.438616 -2.600198)
		(end 148.438616 -3.999738)
		(stroke
			(width 0.2)
			(type default)
		)
		(layer "In3.Cu")
	)
	(gr_arc
		(start 148.684742 -36.130992)
		(mid 149.03704 -36.673282)
		(end 149.57933 -36.320984)
		(stroke
			(width 0.2)
			(type default)
		)
		(layer "In3.Cu")
	)
	(gr_line
		(start 148.80209 -51.627786)
		(end 149.037294 -50.520092)
		(stroke
			(width 0.2)
			(type default)
		)
		(layer "In3.Cu")
	)
	(gr_line
		(start 148.922486 -35.012884)
		(end 148.684742 -36.130992)
		(stroke
			(width 0.2)
			(type default)
		)
		(layer "In3.Cu")
	)
	(gr_arc
		(start 148.957792 -55.395876)
		(mid 149.302356 -55.947245)
		(end 149.84984 -55.596282)
		(stroke
			(width 0.2)
			(type default)
		)
		(layer "In3.Cu")
	)
	(gr_arc
		(start 149.037294 -50.520092)
		(mid 148.69273 -49.968723)
		(end 148.145246 -50.319686)
		(stroke
			(width 0.2)
			(type default)
		)
		(layer "In3.Cu")
	)
	(gr_line
		(start 149.074124 -41.448482)
		(end 149.309328 -40.340788)
		(stroke
			(width 0.2)
			(type default)
		)
		(layer "In3.Cu")
	)
	(gr_arc
		(start 149.100286 -45.226986)
		(mid 149.452584 -45.769276)
		(end 149.994874 -45.416978)
		(stroke
			(width 0.2)
			(type default)
		)
		(layer "In3.Cu")
	)
	(gr_line
		(start 149.192996 -54.288182)
		(end 148.957792 -55.395876)
		(stroke
			(width 0.2)
			(type default)
		)
		(layer "In3.Cu")
	)
	(gr_arc
		(start 149.309328 -40.340788)
		(mid 148.964764 -39.789419)
		(end 148.41728 -40.140382)
		(stroke
			(width 0.2)
			(type default)
		)
		(layer "In3.Cu")
	)
	(gr_line
		(start 149.33803 -44.108878)
		(end 149.100286 -45.226986)
		(stroke
			(width 0.2)
			(type default)
		)
		(layer "In3.Cu")
	)
	(gr_line
		(start 149.561296 -11.20013)
		(end 149.561296 -9.800082)
		(stroke
			(width 0.2)
			(type default)
		)
		(layer "In3.Cu")
	)
	(gr_arc
		(start 149.561296 -9.800082)
		(mid 148.999956 -9.238742)
		(end 148.438616 -9.800082)
		(stroke
			(width 0.2)
			(type default)
		)
		(layer "In3.Cu")
	)
	(gr_line
		(start 149.561296 -3.999992)
		(end 149.561296 -2.600198)
		(stroke
			(width 0.2)
			(type default)
		)
		(layer "In3.Cu")
	)
	(gr_arc
		(start 149.561296 -2.600198)
		(mid 148.999956 -2.038858)
		(end 148.438616 -2.600198)
		(stroke
			(width 0.2)
			(type default)
		)
		(layer "In3.Cu")
	)
	(gr_line
		(start 149.57933 -36.320984)
		(end 149.814534 -35.21329)
		(stroke
			(width 0.2)
			(type default)
		)
		(layer "In3.Cu")
	)
	(gr_arc
		(start 149.814534 -35.21329)
		(mid 149.46997 -34.661921)
		(end 148.922486 -35.012884)
		(stroke
			(width 0.2)
			(type default)
		)
		(layer "In3.Cu")
	)
	(gr_line
		(start 149.84984 -55.596282)
		(end 150.087584 -54.478174)
		(stroke
			(width 0.2)
			(type default)
		)
		(layer "In3.Cu")
	)
	(gr_line
		(start 149.994874 -45.416978)
		(end 150.230078 -44.309284)
		(stroke
			(width 0.2)
			(type default)
		)
		(layer "In3.Cu")
	)
	(gr_arc
		(start 150.087584 -54.478174)
		(mid 149.735286 -53.935884)
		(end 149.192996 -54.288182)
		(stroke
			(width 0.2)
			(type default)
		)
		(layer "In3.Cu")
	)
	(gr_arc
		(start 150.230078 -44.309284)
		(mid 149.885514 -43.757915)
		(end 149.33803 -44.108878)
		(stroke
			(width 0.2)
			(type default)
		)
		(layer "In3.Cu")
	)
	(gr_arc
		(start 150.54707 -39.016178)
		(mid 150.899368 -39.558468)
		(end 151.441658 -39.20617)
		(stroke
			(width 0.2)
			(type default)
		)
		(layer "In3.Cu")
	)
	(gr_line
		(start 150.784814 -37.89807)
		(end 150.54707 -39.016178)
		(stroke
			(width 0.2)
			(type default)
		)
		(layer "In3.Cu")
	)
	(gr_line
		(start 151.441658 -39.20617)
		(end 151.676862 -38.098476)
		(stroke
			(width 0.2)
			(type default)
		)
		(layer "In3.Cu")
	)
	(gr_arc
		(start 151.676862 -38.098476)
		(mid 151.332298 -37.547107)
		(end 150.784814 -37.89807)
		(stroke
			(width 0.2)
			(type default)
		)
		(layer "In3.Cu")
	)
	(gr_line
		(start 154.696922 -73.302114)
		(end 157.5054 -76.110592)
		(stroke
			(width 0.381)
			(type default)
		)
		(layer "In3.Cu")
	)
	(gr_line
		(start 154.696922 -27.95397)
		(end 154.696922 -73.302114)
		(stroke
			(width 0.381)
			(type default)
		)
		(layer "In3.Cu")
	)
	(gr_line
		(start 156.107892 -26.543)
		(end 154.696922 -27.95397)
		(stroke
			(width 0.381)
			(type default)
		)
		(layer "In3.Cu")
	)
	(gr_line
		(start 157.11424 -95.08998)
		(end 138.38174 -95.08998)
		(stroke
			(width 0.381)
			(type default)
		)
		(layer "In3.Cu")
	)
	(gr_line
		(start 157.5054 -94.69882)
		(end 157.11424 -95.08998)
		(stroke
			(width 0.381)
			(type default)
		)
		(layer "In3.Cu")
	)
	(gr_line
		(start 157.5054 -76.9874)
		(end 157.943804 -76.548996)
		(stroke
			(width 0.381)
			(type default)
		)
		(layer "In3.Cu")
	)
	(gr_line
		(start 157.5054 -76.5556)
		(end 172.5168 -76.5556)
		(stroke
			(width 0.381)
			(type default)
		)
		(layer "In3.Cu")
	)
	(gr_line
		(start 157.5054 -76.110592)
		(end 157.5054 -94.69882)
		(stroke
			(width 0.381)
			(type default)
		)
		(layer "In3.Cu")
	)
	(gr_line
		(start 157.943804 -76.548996)
		(end 157.5054 -76.110592)
		(stroke
			(width 0.381)
			(type default)
		)
		(layer "In3.Cu")
	)
	(gr_line
		(start 164.973 -58.984642)
		(end 164.973 -41.731692)
		(stroke
			(width 0.381)
			(type default)
		)
		(layer "In3.Cu")
	)
	(gr_line
		(start 164.973 -41.731692)
		(end 165.455092 -41.2496)
		(stroke
			(width 0.381)
			(type default)
		)
		(layer "In3.Cu")
	)
	(gr_line
		(start 165.399974 -37.183568)
		(end 166.199566 -37.183568)
		(stroke
			(width 0.2)
			(type default)
		)
		(layer "In3.Cu")
	)
	(gr_arc
		(start 165.399974 -36.416488)
		(mid 165.016434 -36.800028)
		(end 165.399974 -37.183568)
		(stroke
			(width 0.2)
			(type default)
		)
		(layer "In3.Cu")
	)
	(gr_line
		(start 165.399974 -34.783522)
		(end 166.199566 -34.783522)
		(stroke
			(width 0.2)
			(type default)
		)
		(layer "In3.Cu")
	)
	(gr_arc
		(start 165.399974 -34.016442)
		(mid 165.016434 -34.399982)
		(end 165.399974 -34.783522)
		(stroke
			(width 0.2)
			(type default)
		)
		(layer "In3.Cu")
	)
	(gr_line
		(start 165.455092 -41.2496)
		(end 169.7228 -41.2496)
		(stroke
			(width 0.381)
			(type default)
		)
		(layer "In3.Cu")
	)
	(gr_arc
		(start 165.741858 -24.055578)
		(mid 166.125271 -24.439372)
		(end 166.508938 -24.055832)
		(stroke
			(width 0.2)
			(type default)
		)
		(layer "In3.Cu")
	)
	(gr_line
		(start 165.741858 -23.166832)
		(end 165.741858 -24.055578)
		(stroke
			(width 0.2)
			(type default)
		)
		(layer "In3.Cu")
	)
	(gr_arc
		(start 165.81628 -38.399974)
		(mid 166.19982 -38.783514)
		(end 166.58336 -38.399974)
		(stroke
			(width 0.2)
			(type default)
		)
		(layer "In3.Cu")
	)
	(gr_line
		(start 165.81628 -37.599874)
		(end 165.81628 -38.399974)
		(stroke
			(width 0.2)
			(type default)
		)
		(layer "In3.Cu")
	)
	(gr_arc
		(start 165.81628 -35.999928)
		(mid 166.19982 -36.383468)
		(end 166.58336 -35.999928)
		(stroke
			(width 0.2)
			(type default)
		)
		(layer "In3.Cu")
	)
	(gr_line
		(start 165.81628 -35.199828)
		(end 165.81628 -35.999928)
		(stroke
			(width 0.2)
			(type default)
		)
		(layer "In3.Cu")
	)
	(gr_arc
		(start 165.81628 -33.599882)
		(mid 166.19982 -33.983422)
		(end 166.58336 -33.599882)
		(stroke
			(width 0.2)
			(type default)
		)
		(layer "In3.Cu")
	)
	(gr_line
		(start 165.81628 -32.800036)
		(end 165.81628 -33.599882)
		(stroke
			(width 0.2)
			(type default)
		)
		(layer "In3.Cu")
	)
	(gr_arc
		(start 165.81628 -31.199836)
		(mid 166.19982 -31.583376)
		(end 166.58336 -31.199836)
		(stroke
			(width 0.2)
			(type default)
		)
		(layer "In3.Cu")
	)
	(gr_line
		(start 165.81628 -30.39999)
		(end 165.81628 -31.199836)
		(stroke
			(width 0.2)
			(type default)
		)
		(layer "In3.Cu")
	)
	(gr_arc
		(start 166.199566 -37.183568)
		(mid 166.58336 -36.800155)
		(end 166.19982 -36.416488)
		(stroke
			(width 0.2)
			(type default)
		)
		(layer "In3.Cu")
	)
	(gr_arc
		(start 166.199566 -34.783522)
		(mid 166.58336 -34.400109)
		(end 166.19982 -34.016442)
		(stroke
			(width 0.2)
			(type default)
		)
		(layer "In3.Cu")
	)
	(gr_line
		(start 166.19982 -36.416488)
		(end 165.399974 -36.416488)
		(stroke
			(width 0.2)
			(type default)
		)
		(layer "In3.Cu")
	)
	(gr_line
		(start 166.19982 -34.016442)
		(end 165.399974 -34.016442)
		(stroke
			(width 0.2)
			(type default)
		)
		(layer "In3.Cu")
	)
	(gr_line
		(start 166.19982 -29.98343)
		(end 166.999412 -29.983684)
		(stroke
			(width 0.2)
			(type default)
		)
		(layer "In3.Cu")
	)
	(gr_line
		(start 166.200074 -32.383476)
		(end 166.999666 -32.383476)
		(stroke
			(width 0.2)
			(type default)
		)
		(layer "In3.Cu")
	)
	(gr_arc
		(start 166.200074 -31.616396)
		(mid 165.816534 -31.999936)
		(end 166.200074 -32.383476)
		(stroke
			(width 0.2)
			(type default)
		)
		(layer "In3.Cu")
	)
	(gr_arc
		(start 166.200074 -29.21635)
		(mid 165.81628 -29.599763)
		(end 166.19982 -29.98343)
		(stroke
			(width 0.2)
			(type default)
		)
		(layer "In3.Cu")
	)
	(gr_line
		(start 166.508938 -24.055832)
		(end 166.508938 -23.166832)
		(stroke
			(width 0.2)
			(type default)
		)
		(layer "In3.Cu")
	)
	(gr_arc
		(start 166.508938 -23.166832)
		(mid 166.125398 -22.783292)
		(end 165.741858 -23.166832)
		(stroke
			(width 0.2)
			(type default)
		)
		(layer "In3.Cu")
	)
	(gr_line
		(start 166.58336 -38.399974)
		(end 166.58336 -37.600128)
		(stroke
			(width 0.2)
			(type default)
		)
		(layer "In3.Cu")
	)
	(gr_arc
		(start 166.58336 -37.600128)
		(mid 166.199947 -37.216334)
		(end 165.81628 -37.599874)
		(stroke
			(width 0.2)
			(type default)
		)
		(layer "In3.Cu")
	)
	(gr_line
		(start 166.58336 -35.999928)
		(end 166.58336 -35.200082)
		(stroke
			(width 0.2)
			(type default)
		)
		(layer "In3.Cu")
	)
	(gr_arc
		(start 166.58336 -35.200082)
		(mid 166.199947 -34.816288)
		(end 165.81628 -35.199828)
		(stroke
			(width 0.2)
			(type default)
		)
		(layer "In3.Cu")
	)
	(gr_line
		(start 166.58336 -33.599882)
		(end 166.58336 -32.80029)
		(stroke
			(width 0.2)
			(type default)
		)
		(layer "In3.Cu")
	)
	(gr_arc
		(start 166.58336 -32.80029)
		(mid 166.199947 -32.416496)
		(end 165.81628 -32.800036)
		(stroke
			(width 0.2)
			(type default)
		)
		(layer "In3.Cu")
	)
	(gr_line
		(start 166.58336 -31.199836)
		(end 166.58336 -30.400244)
		(stroke
			(width 0.2)
			(type default)
		)
		(layer "In3.Cu")
	)
	(gr_arc
		(start 166.58336 -30.400244)
		(mid 166.199947 -30.01645)
		(end 165.81628 -30.39999)
		(stroke
			(width 0.2)
			(type default)
		)
		(layer "In3.Cu")
	)
	(gr_arc
		(start 166.999412 -29.983684)
		(mid 167.383206 -29.600271)
		(end 166.999666 -29.216604)
		(stroke
			(width 0.2)
			(type default)
		)
		(layer "In3.Cu")
	)
	(gr_arc
		(start 166.999666 -32.383476)
		(mid 167.38346 -32.000063)
		(end 166.99992 -31.616396)
		(stroke
			(width 0.2)
			(type default)
		)
		(layer "In3.Cu")
	)
	(gr_line
		(start 166.999666 -29.216604)
		(end 166.200074 -29.21635)
		(stroke
			(width 0.2)
			(type default)
		)
		(layer "In3.Cu")
	)
	(gr_line
		(start 166.99992 -31.616396)
		(end 166.200074 -31.616396)
		(stroke
			(width 0.2)
			(type default)
		)
		(layer "In3.Cu")
	)
	(gr_line
		(start 167.441626 -30.400244)
		(end 167.44188 -31.199582)
		(stroke
			(width 0.2)
			(type default)
		)
		(layer "In3.Cu")
	)
	(gr_arc
		(start 167.44188 -31.199582)
		(mid 167.80002 -31.557976)
		(end 168.15816 -31.199582)
		(stroke
			(width 0.2)
			(type default)
		)
		(layer "In3.Cu")
	)
	(gr_arc
		(start 167.776398 -24.012652)
		(mid 168.159811 -24.396446)
		(end 168.543478 -24.012906)
		(stroke
			(width 0.2)
			(type default)
		)
		(layer "In3.Cu")
	)
	(gr_line
		(start 167.776398 -23.123906)
		(end 167.776398 -24.012652)
		(stroke
			(width 0.2)
			(type default)
		)
		(layer "In3.Cu")
	)
	(gr_line
		(start 167.99052 -143.38046)
		(end 167.353234 -144.017746)
		(stroke
			(width 0.381)
			(type default)
		)
		(layer "In3.Cu")
	)
	(gr_line
		(start 167.99052 -143.38046)
		(end 168.627552 -144.017492)
		(stroke
			(width 0.381)
			(type default)
		)
		(layer "In3.Cu")
	)
	(gr_line
		(start 167.9956 -106.505756)
		(end 167.9956 -144.3482)
		(stroke
			(width 0.381)
			(type default)
		)
		(layer "In3.Cu")
	)
	(gr_arc
		(start 168.157906 -30.39999)
		(mid 167.799639 -30.04185)
		(end 167.441626 -30.400244)
		(stroke
			(width 0.2)
			(type default)
		)
		(layer "In3.Cu")
	)
	(gr_line
		(start 168.15816 -31.199582)
		(end 168.157906 -30.39999)
		(stroke
			(width 0.2)
			(type default)
		)
		(layer "In3.Cu")
	)
	(gr_arc
		(start 168.241726 -31.199582)
		(mid 168.599739 -31.557976)
		(end 168.958006 -31.199836)
		(stroke
			(width 0.2)
			(type default)
		)
		(layer "In3.Cu")
	)
	(gr_line
		(start 168.241726 -30.39999)
		(end 168.241726 -31.199582)
		(stroke
			(width 0.2)
			(type default)
		)
		(layer "In3.Cu")
	)
	(gr_line
		(start 168.543478 -24.012906)
		(end 168.543478 -23.123906)
		(stroke
			(width 0.2)
			(type default)
		)
		(layer "In3.Cu")
	)
	(gr_arc
		(start 168.543478 -23.123906)
		(mid 168.159938 -22.740366)
		(end 167.776398 -23.123906)
		(stroke
			(width 0.2)
			(type default)
		)
		(layer "In3.Cu")
	)
	(gr_line
		(start 168.958006 -31.199836)
		(end 168.958006 -30.39999)
		(stroke
			(width 0.2)
			(type default)
		)
		(layer "In3.Cu")
	)
	(gr_arc
		(start 168.958006 -30.39999)
		(mid 168.599866 -30.04185)
		(end 168.241726 -30.39999)
		(stroke
			(width 0.2)
			(type default)
		)
		(layer "In3.Cu")
	)
	(gr_line
		(start 169.7228 -41.2496)
		(end 170.5356 -40.4368)
		(stroke
			(width 0.381)
			(type default)
		)
		(layer "In3.Cu")
	)
	(gr_arc
		(start 169.833544 -24.004016)
		(mid 170.216957 -24.38781)
		(end 170.600624 -24.00427)
		(stroke
			(width 0.2)
			(type default)
		)
		(layer "In3.Cu")
	)
	(gr_line
		(start 169.833544 -23.11527)
		(end 169.833544 -24.004016)
		(stroke
			(width 0.2)
			(type default)
		)
		(layer "In3.Cu")
	)
	(gr_line
		(start 169.841672 -30.400244)
		(end 169.841926 -31.199836)
		(stroke
			(width 0.2)
			(type default)
		)
		(layer "In3.Cu")
	)
	(gr_arc
		(start 169.841926 -31.199836)
		(mid 170.200066 -31.55823)
		(end 170.558206 -31.199836)
		(stroke
			(width 0.2)
			(type default)
		)
		(layer "In3.Cu")
	)
	(gr_line
		(start 170.5356 -40.4368)
		(end 170.5356 -34.833814)
		(stroke
			(width 0.381)
			(type default)
		)
		(layer "In3.Cu")
	)
	(gr_arc
		(start 170.542966 -34.816034)
		(mid 170.5375 -34.824184)
		(end 170.5356 -34.833814)
		(stroke
			(width 0.381)
			(type default)
		)
		(layer "In3.Cu")
	)
	(gr_line
		(start 170.542966 -34.816034)
		(end 171.3738 -33.9852)
		(stroke
			(width 0.381)
			(type default)
		)
		(layer "In3.Cu")
	)
	(gr_arc
		(start 170.557952 -30.39999)
		(mid 170.199685 -30.04185)
		(end 169.841672 -30.400244)
		(stroke
			(width 0.2)
			(type default)
		)
		(layer "In3.Cu")
	)
	(gr_line
		(start 170.558206 -31.199836)
		(end 170.557952 -30.39999)
		(stroke
			(width 0.2)
			(type default)
		)
		(layer "In3.Cu")
	)
	(gr_line
		(start 170.600624 -24.00427)
		(end 170.600624 -23.11527)
		(stroke
			(width 0.2)
			(type default)
		)
		(layer "In3.Cu")
	)
	(gr_arc
		(start 170.600624 -23.11527)
		(mid 170.217084 -22.73173)
		(end 169.833544 -23.11527)
		(stroke
			(width 0.2)
			(type default)
		)
		(layer "In3.Cu")
	)
	(gr_line
		(start 170.641772 -30.400244)
		(end 170.642026 -31.199836)
		(stroke
			(width 0.2)
			(type default)
		)
		(layer "In3.Cu")
	)
	(gr_arc
		(start 170.642026 -31.199836)
		(mid 171.000166 -31.55823)
		(end 171.358306 -31.199836)
		(stroke
			(width 0.2)
			(type default)
		)
		(layer "In3.Cu")
	)
	(gr_line
		(start 170.942 -26.5684)
		(end 171.380404 -27.006804)
		(stroke
			(width 0.381)
			(type default)
		)
		(layer "In3.Cu")
	)
	(gr_arc
		(start 171.358052 -30.39999)
		(mid 170.999785 -30.04185)
		(end 170.641772 -30.400244)
		(stroke
			(width 0.2)
			(type default)
		)
		(layer "In3.Cu")
	)
	(gr_line
		(start 171.358306 -31.199836)
		(end 171.358052 -30.39999)
		(stroke
			(width 0.2)
			(type default)
		)
		(layer "In3.Cu")
	)
	(gr_line
		(start 171.3738 -33.9852)
		(end 171.3738 -26.6192)
		(stroke
			(width 0.381)
			(type default)
		)
		(layer "In3.Cu")
	)
	(gr_line
		(start 171.380404 -27.006804)
		(end 171.786804 -26.600404)
		(stroke
			(width 0.381)
			(type default)
		)
		(layer "In3.Cu")
	)
	(gr_arc
		(start 171.88561 -24.00173)
		(mid 172.269023 -24.385524)
		(end 172.65269 -24.001984)
		(stroke
			(width 0.2)
			(type default)
		)
		(layer "In3.Cu")
	)
	(gr_line
		(start 171.88561 -23.112984)
		(end 171.88561 -24.00173)
		(stroke
			(width 0.2)
			(type default)
		)
		(layer "In3.Cu")
	)
	(gr_line
		(start 172.241718 -30.400244)
		(end 172.241972 -31.199836)
		(stroke
			(width 0.2)
			(type default)
		)
		(layer "In3.Cu")
	)
	(gr_arc
		(start 172.241972 -31.199836)
		(mid 172.600112 -31.55823)
		(end 172.958252 -31.199836)
		(stroke
			(width 0.2)
			(type default)
		)
		(layer "In3.Cu")
	)
	(gr_line
		(start 172.5168 -76.5556)
		(end 173.12894 -77.16774)
		(stroke
			(width 0.381)
			(type default)
		)
		(layer "In3.Cu")
	)
	(gr_line
		(start 172.65269 -24.001984)
		(end 172.65269 -23.112984)
		(stroke
			(width 0.2)
			(type default)
		)
		(layer "In3.Cu")
	)
	(gr_arc
		(start 172.65269 -23.112984)
		(mid 172.26915 -22.729444)
		(end 171.88561 -23.112984)
		(stroke
			(width 0.2)
			(type default)
		)
		(layer "In3.Cu")
	)
	(gr_arc
		(start 172.957998 -30.39999)
		(mid 172.599731 -30.04185)
		(end 172.241718 -30.400244)
		(stroke
			(width 0.2)
			(type default)
		)
		(layer "In3.Cu")
	)
	(gr_line
		(start 172.958252 -31.199836)
		(end 172.957998 -30.39999)
		(stroke
			(width 0.2)
			(type default)
		)
		(layer "In3.Cu")
	)
	(gr_line
		(start 173.041818 -30.400244)
		(end 173.042072 -31.199836)
		(stroke
			(width 0.2)
			(type default)
		)
		(layer "In3.Cu")
	)
	(gr_arc
		(start 173.042072 -31.199836)
		(mid 173.400212 -31.55823)
		(end 173.758352 -31.199836)
		(stroke
			(width 0.2)
			(type default)
		)
		(layer "In3.Cu")
	)
	(gr_line
		(start 173.12894 -101.372416)
		(end 167.9956 -106.505756)
		(stroke
			(width 0.381)
			(type default)
		)
		(layer "In3.Cu")
	)
	(gr_line
		(start 173.12894 -101.372416)
		(end 173.567344 -100.934012)
		(stroke
			(width 0.381)
			(type default)
		)
		(layer "In3.Cu")
	)
	(gr_line
		(start 173.12894 -100.933758)
		(end 173.129194 -100.934012)
		(stroke
			(width 0.381)
			(type default)
		)
		(layer "In3.Cu")
	)
	(gr_line
		(start 173.12894 -77.16774)
		(end 173.12894 -101.372416)
		(stroke
			(width 0.381)
			(type default)
		)
		(layer "In3.Cu")
	)
	(gr_line
		(start 173.129194 -100.934012)
		(end 186.340496 -100.934012)
		(stroke
			(width 0.381)
			(type default)
		)
		(layer "In3.Cu")
	)
	(gr_line
		(start 173.567344 -100.934012)
		(end 173.160944 -100.527612)
		(stroke
			(width 0.381)
			(type default)
		)
		(layer "In3.Cu")
	)
	(gr_arc
		(start 173.758098 -30.39999)
		(mid 173.399831 -30.04185)
		(end 173.041818 -30.400244)
		(stroke
			(width 0.2)
			(type default)
		)
		(layer "In3.Cu")
	)
	(gr_line
		(start 173.758352 -31.199836)
		(end 173.758098 -30.39999)
		(stroke
			(width 0.2)
			(type default)
		)
		(layer "In3.Cu")
	)
	(gr_arc
		(start 173.931326 -24.001222)
		(mid 174.314739 -24.385016)
		(end 174.698406 -24.001476)
		(stroke
			(width 0.2)
			(type default)
		)
		(layer "In3.Cu")
	)
	(gr_line
		(start 173.931326 -23.112476)
		(end 173.931326 -24.001222)
		(stroke
			(width 0.2)
			(type default)
		)
		(layer "In3.Cu")
	)
	(gr_line
		(start 174.641764 -30.400244)
		(end 174.642018 -31.199836)
		(stroke
			(width 0.2)
			(type default)
		)
		(layer "In3.Cu")
	)
	(gr_arc
		(start 174.642018 -31.199836)
		(mid 175.000158 -31.55823)
		(end 175.358298 -31.199836)
		(stroke
			(width 0.2)
			(type default)
		)
		(layer "In3.Cu")
	)
	(gr_line
		(start 174.698406 -24.001476)
		(end 174.698406 -23.112476)
		(stroke
			(width 0.2)
			(type default)
		)
		(layer "In3.Cu")
	)
	(gr_arc
		(start 174.698406 -23.112476)
		(mid 174.314866 -22.728936)
		(end 173.931326 -23.112476)
		(stroke
			(width 0.2)
			(type default)
		)
		(layer "In3.Cu")
	)
	(gr_arc
		(start 175.358044 -30.39999)
		(mid 174.999777 -30.04185)
		(end 174.641764 -30.400244)
		(stroke
			(width 0.2)
			(type default)
		)
		(layer "In3.Cu")
	)
	(gr_line
		(start 175.358298 -31.199836)
		(end 175.358044 -30.39999)
		(stroke
			(width 0.2)
			(type default)
		)
		(layer "In3.Cu")
	)
	(gr_arc
		(start 175.441864 -31.199836)
		(mid 175.799877 -31.55823)
		(end 176.158144 -31.20009)
		(stroke
			(width 0.2)
			(type default)
		)
		(layer "In3.Cu")
	)
	(gr_line
		(start 175.441864 -30.400244)
		(end 175.441864 -31.199836)
		(stroke
			(width 0.2)
			(type default)
		)
		(layer "In3.Cu")
	)
	(gr_arc
		(start 175.98517 -23.992078)
		(mid 176.368583 -24.375872)
		(end 176.75225 -23.992332)
		(stroke
			(width 0.2)
			(type default)
		)
		(layer "In3.Cu")
	)
	(gr_line
		(start 175.98517 -23.103332)
		(end 175.98517 -23.992078)
		(stroke
			(width 0.2)
			(type default)
		)
		(layer "In3.Cu")
	)
	(gr_line
		(start 176.158144 -31.20009)
		(end 176.158144 -30.400244)
		(stroke
			(width 0.2)
			(type default)
		)
		(layer "In3.Cu")
	)
	(gr_arc
		(start 176.158144 -30.400244)
		(mid 175.800004 -30.042104)
		(end 175.441864 -30.400244)
		(stroke
			(width 0.2)
			(type default)
		)
		(layer "In3.Cu")
	)
	(gr_line
		(start 176.75225 -23.992332)
		(end 176.75225 -23.103332)
		(stroke
			(width 0.2)
			(type default)
		)
		(layer "In3.Cu")
	)
	(gr_arc
		(start 176.75225 -23.103332)
		(mid 176.36871 -22.719792)
		(end 175.98517 -23.103332)
		(stroke
			(width 0.2)
			(type default)
		)
		(layer "In3.Cu")
	)
	(gr_line
		(start 177.3428 -26.543)
		(end 156.107892 -26.543)
		(stroke
			(width 0.381)
			(type default)
		)
		(layer "In3.Cu")
	)
	(gr_line
		(start 177.8254 -26.0604)
		(end 177.3428 -26.543)
		(stroke
			(width 0.381)
			(type default)
		)
		(layer "In3.Cu")
	)
	(gr_arc
		(start 178.023774 -24.005286)
		(mid 178.407187 -24.38908)
		(end 178.790854 -24.00554)
		(stroke
			(width 0.2)
			(type default)
		)
		(layer "In3.Cu")
	)
	(gr_line
		(start 178.023774 -23.11654)
		(end 178.023774 -24.005286)
		(stroke
			(width 0.2)
			(type default)
		)
		(layer "In3.Cu")
	)
	(gr_line
		(start 178.790854 -24.00554)
		(end 178.790854 -23.11654)
		(stroke
			(width 0.2)
			(type default)
		)
		(layer "In3.Cu")
	)
	(gr_arc
		(start 178.790854 -23.11654)
		(mid 178.407314 -22.733)
		(end 178.023774 -23.11654)
		(stroke
			(width 0.2)
			(type default)
		)
		(layer "In3.Cu")
	)
	(gr_arc
		(start 179.438554 -12.399772)
		(mid 179.999767 -12.961366)
		(end 180.561234 -12.400026)
		(stroke
			(width 0.2)
			(type default)
		)
		(layer "In3.Cu")
	)
	(gr_line
		(start 179.438554 -10.999978)
		(end 179.438554 -12.399772)
		(stroke
			(width 0.2)
			(type default)
		)
		(layer "In3.Cu")
	)
	(gr_arc
		(start 179.438554 -8.79983)
		(mid 179.999767 -9.361424)
		(end 180.561234 -8.800084)
		(stroke
			(width 0.2)
			(type default)
		)
		(layer "In3.Cu")
	)
	(gr_line
		(start 179.438554 -7.400036)
		(end 179.438554 -8.79983)
		(stroke
			(width 0.2)
			(type default)
		)
		(layer "In3.Cu")
	)
	(gr_arc
		(start 179.438554 -5.199888)
		(mid 179.999767 -5.761482)
		(end 180.561234 -5.200142)
		(stroke
			(width 0.2)
			(type default)
		)
		(layer "In3.Cu")
	)
	(gr_line
		(start 179.438554 -3.800094)
		(end 179.438554 -5.199888)
		(stroke
			(width 0.2)
			(type default)
		)
		(layer "In3.Cu")
	)
	(gr_arc
		(start 180.052472 -24.485092)
		(mid 180.435885 -24.868886)
		(end 180.819552 -24.485346)
		(stroke
			(width 0.2)
			(type default)
		)
		(layer "In3.Cu")
	)
	(gr_line
		(start 180.052472 -23.596346)
		(end 180.052472 -24.485092)
		(stroke
			(width 0.2)
			(type default)
		)
		(layer "In3.Cu")
	)
	(gr_line
		(start 180.561234 -12.400026)
		(end 180.561234 -10.999978)
		(stroke
			(width 0.2)
			(type default)
		)
		(layer "In3.Cu")
	)
	(gr_arc
		(start 180.561234 -10.999978)
		(mid 179.999894 -10.438638)
		(end 179.438554 -10.999978)
		(stroke
			(width 0.2)
			(type default)
		)
		(layer "In3.Cu")
	)
	(gr_line
		(start 180.561234 -8.800084)
		(end 180.561234 -7.400036)
		(stroke
			(width 0.2)
			(type default)
		)
		(layer "In3.Cu")
	)
	(gr_arc
		(start 180.561234 -7.400036)
		(mid 179.999894 -6.838696)
		(end 179.438554 -7.400036)
		(stroke
			(width 0.2)
			(type default)
		)
		(layer "In3.Cu")
	)
	(gr_line
		(start 180.561234 -5.200142)
		(end 180.561234 -3.800094)
		(stroke
			(width 0.2)
			(type default)
		)
		(layer "In3.Cu")
	)
	(gr_arc
		(start 180.561234 -3.800094)
		(mid 179.999894 -3.238754)
		(end 179.438554 -3.800094)
		(stroke
			(width 0.2)
			(type default)
		)
		(layer "In3.Cu")
	)
	(gr_line
		(start 180.819552 -24.485346)
		(end 180.819552 -23.596346)
		(stroke
			(width 0.2)
			(type default)
		)
		(layer "In3.Cu")
	)
	(gr_arc
		(start 180.819552 -23.596346)
		(mid 180.436012 -23.212806)
		(end 180.052472 -23.596346)
		(stroke
			(width 0.2)
			(type default)
		)
		(layer "In3.Cu")
	)
	(gr_arc
		(start 181.238652 -11.199876)
		(mid 181.799865 -11.76147)
		(end 182.361332 -11.20013)
		(stroke
			(width 0.2)
			(type default)
		)
		(layer "In3.Cu")
	)
	(gr_line
		(start 181.238652 -9.800082)
		(end 181.238652 -11.199876)
		(stroke
			(width 0.2)
			(type default)
		)
		(layer "In3.Cu")
	)
	(gr_arc
		(start 181.238652 -3.999738)
		(mid 181.799865 -4.561332)
		(end 182.361332 -3.999992)
		(stroke
			(width 0.2)
			(type default)
		)
		(layer "In3.Cu")
	)
	(gr_line
		(start 181.238652 -2.600198)
		(end 181.238652 -3.999738)
		(stroke
			(width 0.2)
			(type default)
		)
		(layer "In3.Cu")
	)
	(gr_line
		(start 182.361332 -11.20013)
		(end 182.361332 -9.800082)
		(stroke
			(width 0.2)
			(type default)
		)
		(layer "In3.Cu")
	)
	(gr_arc
		(start 182.361332 -9.800082)
		(mid 181.799992 -9.238742)
		(end 181.238652 -9.800082)
		(stroke
			(width 0.2)
			(type default)
		)
		(layer "In3.Cu")
	)
	(gr_line
		(start 182.361332 -3.999992)
		(end 182.361332 -2.600198)
		(stroke
			(width 0.2)
			(type default)
		)
		(layer "In3.Cu")
	)
	(gr_arc
		(start 182.361332 -2.600198)
		(mid 181.799992 -2.038858)
		(end 181.238652 -2.600198)
		(stroke
			(width 0.2)
			(type default)
		)
		(layer "In3.Cu")
	)
	(gr_arc
		(start 183.038496 -12.399772)
		(mid 183.599709 -12.961366)
		(end 184.161176 -12.400026)
		(stroke
			(width 0.2)
			(type default)
		)
		(layer "In3.Cu")
	)
	(gr_line
		(start 183.038496 -10.999978)
		(end 183.038496 -12.399772)
		(stroke
			(width 0.2)
			(type default)
		)
		(layer "In3.Cu")
	)
	(gr_arc
		(start 183.038496 -5.199888)
		(mid 183.599709 -5.761482)
		(end 184.161176 -5.200142)
		(stroke
			(width 0.2)
			(type default)
		)
		(layer "In3.Cu")
	)
	(gr_line
		(start 183.038496 -3.800094)
		(end 183.038496 -5.199888)
		(stroke
			(width 0.2)
			(type default)
		)
		(layer "In3.Cu")
	)
	(gr_line
		(start 184.161176 -12.400026)
		(end 184.161176 -10.999978)
		(stroke
			(width 0.2)
			(type default)
		)
		(layer "In3.Cu")
	)
	(gr_arc
		(start 184.161176 -10.999978)
		(mid 183.599836 -10.438638)
		(end 183.038496 -10.999978)
		(stroke
			(width 0.2)
			(type default)
		)
		(layer "In3.Cu")
	)
	(gr_line
		(start 184.161176 -5.200142)
		(end 184.161176 -3.800094)
		(stroke
			(width 0.2)
			(type default)
		)
		(layer "In3.Cu")
	)
	(gr_arc
		(start 184.161176 -3.800094)
		(mid 183.599836 -3.238754)
		(end 183.038496 -3.800094)
		(stroke
			(width 0.2)
			(type default)
		)
		(layer "In3.Cu")
	)
	(gr_arc
		(start 184.838594 -11.199876)
		(mid 185.399807 -11.76147)
		(end 185.961274 -11.20013)
		(stroke
			(width 0.2)
			(type default)
		)
		(layer "In3.Cu")
	)
	(gr_line
		(start 184.838594 -9.800082)
		(end 184.838594 -11.199876)
		(stroke
			(width 0.2)
			(type default)
		)
		(layer "In3.Cu")
	)
	(gr_arc
		(start 184.838594 -3.999738)
		(mid 185.399807 -4.561332)
		(end 185.961274 -3.999992)
		(stroke
			(width 0.2)
			(type default)
		)
		(layer "In3.Cu")
	)
	(gr_line
		(start 184.838594 -2.600198)
		(end 184.838594 -3.999738)
		(stroke
			(width 0.2)
			(type default)
		)
		(layer "In3.Cu")
	)
	(gr_line
		(start 185.9026 -100.934012)
		(end 186.309 -101.340412)
		(stroke
			(width 0.381)
			(type default)
		)
		(layer "In3.Cu")
	)
	(gr_line
		(start 185.961274 -11.20013)
		(end 185.961274 -9.800082)
		(stroke
			(width 0.2)
			(type default)
		)
		(layer "In3.Cu")
	)
	(gr_arc
		(start 185.961274 -9.800082)
		(mid 185.399934 -9.238742)
		(end 184.838594 -9.800082)
		(stroke
			(width 0.2)
			(type default)
		)
		(layer "In3.Cu")
	)
	(gr_line
		(start 185.961274 -3.999992)
		(end 185.961274 -2.600198)
		(stroke
			(width 0.2)
			(type default)
		)
		(layer "In3.Cu")
	)
	(gr_arc
		(start 185.961274 -2.600198)
		(mid 185.399934 -2.038858)
		(end 184.838594 -2.600198)
		(stroke
			(width 0.2)
			(type default)
		)
		(layer "In3.Cu")
	)
	(gr_line
		(start 186.309 -100.527612)
		(end 185.9026 -100.934012)
		(stroke
			(width 0.381)
			(type default)
		)
		(layer "In3.Cu")
	)
	(gr_line
		(start 186.340496 -100.934012)
		(end 186.34075 -100.933758)
		(stroke
			(width 0.381)
			(type default)
		)
		(layer "In3.Cu")
	)
	(gr_line
		(start 186.34075 -122.143774)
		(end 186.34075 -100.934266)
		(stroke
			(width 0.381)
			(type default)
		)
		(layer "In3.Cu")
	)
	(gr_line
		(start 186.34075 -100.934266)
		(end 186.340496 -100.934012)
		(stroke
			(width 0.381)
			(type default)
		)
		(layer "In3.Cu")
	)
	(gr_line
		(start 186.34075 -100.933758)
		(end 186.34075 -91.86545)
		(stroke
			(width 0.381)
			(type default)
		)
		(layer "In3.Cu")
	)
	(gr_line
		(start 186.34075 -91.86545)
		(end 186.69 -91.5162)
		(stroke
			(width 0.381)
			(type default)
		)
		(layer "In3.Cu")
	)
	(gr_arc
		(start 186.638438 -12.399772)
		(mid 187.199651 -12.961366)
		(end 187.761118 -12.400026)
		(stroke
			(width 0.2)
			(type default)
		)
		(layer "In3.Cu")
	)
	(gr_line
		(start 186.638438 -10.999978)
		(end 186.638438 -12.399772)
		(stroke
			(width 0.2)
			(type default)
		)
		(layer "In3.Cu")
	)
	(gr_arc
		(start 186.638438 -5.199888)
		(mid 187.199651 -5.761482)
		(end 187.761118 -5.200142)
		(stroke
			(width 0.2)
			(type default)
		)
		(layer "In3.Cu")
	)
	(gr_line
		(start 186.638438 -3.800094)
		(end 186.638438 -5.199888)
		(stroke
			(width 0.2)
			(type default)
		)
		(layer "In3.Cu")
	)
	(gr_line
		(start 186.69 -91.5162)
		(end 186.69 -80.701642)
		(stroke
			(width 0.381)
			(type default)
		)
		(layer "In3.Cu")
	)
	(gr_line
		(start 186.69 -80.701642)
		(end 164.973 -58.984642)
		(stroke
			(width 0.381)
			(type default)
		)
		(layer "In3.Cu")
	)
	(gr_line
		(start 186.751976 -122.555)
		(end 186.34075 -122.143774)
		(stroke
			(width 0.381)
			(type default)
		)
		(layer "In3.Cu")
	)
	(gr_line
		(start 187.761118 -12.400026)
		(end 187.761118 -10.999978)
		(stroke
			(width 0.2)
			(type default)
		)
		(layer "In3.Cu")
	)
	(gr_arc
		(start 187.761118 -10.999978)
		(mid 187.199778 -10.438638)
		(end 186.638438 -10.999978)
		(stroke
			(width 0.2)
			(type default)
		)
		(layer "In3.Cu")
	)
	(gr_line
		(start 187.761118 -5.200142)
		(end 187.761118 -3.800094)
		(stroke
			(width 0.2)
			(type default)
		)
		(layer "In3.Cu")
	)
	(gr_arc
		(start 187.761118 -3.800094)
		(mid 187.199778 -3.238754)
		(end 186.638438 -3.800094)
		(stroke
			(width 0.2)
			(type default)
		)
		(layer "In3.Cu")
	)
	(gr_arc
		(start 188.438536 -11.199876)
		(mid 188.999749 -11.76147)
		(end 189.561216 -11.20013)
		(stroke
			(width 0.2)
			(type default)
		)
		(layer "In3.Cu")
	)
	(gr_line
		(start 188.438536 -9.800082)
		(end 188.438536 -11.199876)
		(stroke
			(width 0.2)
			(type default)
		)
		(layer "In3.Cu")
	)
	(gr_arc
		(start 188.438536 -3.999738)
		(mid 188.999749 -4.561332)
		(end 189.561216 -3.999992)
		(stroke
			(width 0.2)
			(type default)
		)
		(layer "In3.Cu")
	)
	(gr_line
		(start 188.438536 -2.600198)
		(end 188.438536 -3.999738)
		(stroke
			(width 0.2)
			(type default)
		)
		(layer "In3.Cu")
	)
	(gr_line
		(start 189.561216 -11.20013)
		(end 189.561216 -9.800082)
		(stroke
			(width 0.2)
			(type default)
		)
		(layer "In3.Cu")
	)
	(gr_arc
		(start 189.561216 -9.800082)
		(mid 188.999876 -9.238742)
		(end 188.438536 -9.800082)
		(stroke
			(width 0.2)
			(type default)
		)
		(layer "In3.Cu")
	)
	(gr_line
		(start 189.561216 -3.999992)
		(end 189.561216 -2.600198)
		(stroke
			(width 0.2)
			(type default)
		)
		(layer "In3.Cu")
	)
	(gr_arc
		(start 189.561216 -2.600198)
		(mid 188.999876 -2.038858)
		(end 188.438536 -2.600198)
		(stroke
			(width 0.2)
			(type default)
		)
		(layer "In3.Cu")
	)
	(gr_arc
		(start 190.238634 -12.399772)
		(mid 190.799847 -12.961366)
		(end 191.361314 -12.400026)
		(stroke
			(width 0.2)
			(type default)
		)
		(layer "In3.Cu")
	)
	(gr_line
		(start 190.238634 -10.999978)
		(end 190.238634 -12.399772)
		(stroke
			(width 0.2)
			(type default)
		)
		(layer "In3.Cu")
	)
	(gr_arc
		(start 190.238634 -5.199888)
		(mid 190.799847 -5.761482)
		(end 191.361314 -5.200142)
		(stroke
			(width 0.2)
			(type default)
		)
		(layer "In3.Cu")
	)
	(gr_line
		(start 190.238634 -3.800094)
		(end 190.238634 -5.199888)
		(stroke
			(width 0.2)
			(type default)
		)
		(layer "In3.Cu")
	)
	(gr_line
		(start 191.361314 -12.400026)
		(end 191.361314 -10.999978)
		(stroke
			(width 0.2)
			(type default)
		)
		(layer "In3.Cu")
	)
	(gr_arc
		(start 191.361314 -10.999978)
		(mid 190.799974 -10.438638)
		(end 190.238634 -10.999978)
		(stroke
			(width 0.2)
			(type default)
		)
		(layer "In3.Cu")
	)
	(gr_line
		(start 191.361314 -5.200142)
		(end 191.361314 -3.800094)
		(stroke
			(width 0.2)
			(type default)
		)
		(layer "In3.Cu")
	)
	(gr_arc
		(start 191.361314 -3.800094)
		(mid 190.799974 -3.238754)
		(end 190.238634 -3.800094)
		(stroke
			(width 0.2)
			(type default)
		)
		(layer "In3.Cu")
	)
	(gr_arc
		(start 192.038478 -11.199876)
		(mid 192.599691 -11.76147)
		(end 193.161158 -11.20013)
		(stroke
			(width 0.2)
			(type default)
		)
		(layer "In3.Cu")
	)
	(gr_line
		(start 192.038478 -9.800082)
		(end 192.038478 -11.199876)
		(stroke
			(width 0.2)
			(type default)
		)
		(layer "In3.Cu")
	)
	(gr_arc
		(start 192.038478 -3.999738)
		(mid 192.599691 -4.561332)
		(end 193.161158 -3.999992)
		(stroke
			(width 0.2)
			(type default)
		)
		(layer "In3.Cu")
	)
	(gr_line
		(start 192.038478 -2.600198)
		(end 192.038478 -3.999738)
		(stroke
			(width 0.2)
			(type default)
		)
		(layer "In3.Cu")
	)
	(gr_line
		(start 193.161158 -11.20013)
		(end 193.161158 -9.800082)
		(stroke
			(width 0.2)
			(type default)
		)
		(layer "In3.Cu")
	)
	(gr_arc
		(start 193.161158 -9.800082)
		(mid 192.599818 -9.238742)
		(end 192.038478 -9.800082)
		(stroke
			(width 0.2)
			(type default)
		)
		(layer "In3.Cu")
	)
	(gr_line
		(start 193.161158 -3.999992)
		(end 193.161158 -2.600198)
		(stroke
			(width 0.2)
			(type default)
		)
		(layer "In3.Cu")
	)
	(gr_arc
		(start 193.161158 -2.600198)
		(mid 192.599818 -2.038858)
		(end 192.038478 -2.600198)
		(stroke
			(width 0.2)
			(type default)
		)
		(layer "In3.Cu")
	)
	(gr_line
		(start 208.000092 -144.999964)
		(end 127.00254 -144.999964)
		(stroke
			(width 2.54)
			(type default)
		)
		(layer "In3.Cu")
	)
	(gr_arc
		(start 208.000092 -144.999964)
		(mid 209.414297 -144.41418)
		(end 210.000088 -142.999968)
		(stroke
			(width 2.54)
			(type default)
		)
		(layer "In3.Cu")
	)
	(gr_line
		(start 208.468468 -122.555)
		(end 208.874868 -122.9614)
		(stroke
			(width 0.381)
			(type default)
		)
		(layer "In3.Cu")
	)
	(gr_line
		(start 208.486502 -26.0604)
		(end 208.892902 -26.4668)
		(stroke
			(width 0.381)
			(type default)
		)
		(layer "In3.Cu")
	)
	(gr_line
		(start 208.906872 -122.116596)
		(end 208.468468 -122.555)
		(stroke
			(width 0.381)
			(type default)
		)
		(layer "In3.Cu")
	)
	(gr_line
		(start 208.924906 -25.621996)
		(end 208.486502 -26.0604)
		(stroke
			(width 0.381)
			(type default)
		)
		(layer "In3.Cu")
	)
	(gr_line
		(start 210.000088 -122.555)
		(end 186.751976 -122.555)
		(stroke
			(width 0.381)
			(type default)
		)
		(layer "In3.Cu")
	)
	(gr_arc
		(start 210.000088 -1.999996)
		(mid 209.414301 -0.585791)
		(end 208.000092 0)
		(stroke
			(width 2.54)
			(type default)
		)
		(layer "In3.Cu")
	)
	(gr_line
		(start 210.000088 -1.999996)
		(end 210.000088 -142.999968)
		(stroke
			(width 2.54)
			(type default)
		)
		(layer "In3.Cu")
	)
	(gr_line
		(start 211.7344 -26.0604)
		(end 177.8254 -26.0604)
		(stroke
			(width 0.381)
			(type default)
		)
		(layer "In3.Cu")
	)
	(gr_line
		(start 211.7598 -26.035)
		(end 211.7344 -26.0604)
		(stroke
			(width 0.381)
			(type default)
		)
		(layer "In3.Cu")
	)
	(gr_line
		(start 0 -142.999968)
		(end 0 -1.999996)
		(stroke
			(width 2.54)
			(type default)
		)
		(layer "In4.Cu")
	)
	(gr_arc
		(start 0 -142.999968)
		(mid 0.585785 -144.414179)
		(end 1.999996 -144.999964)
		(stroke
			(width 2.54)
			(type default)
		)
		(layer "In4.Cu")
	)
	(gr_arc
		(start 1.999996 0)
		(mid 0.585785 -0.585785)
		(end 0 -1.999996)
		(stroke
			(width 2.54)
			(type default)
		)
		(layer "In4.Cu")
	)
	(gr_line
		(start 1.999996 0)
		(end 208.000092 0)
		(stroke
			(width 2.54)
			(type default)
		)
		(layer "In4.Cu")
	)
	(gr_line
		(start 6.2484 -87.5538)
		(end 6.2484 -81.026)
		(stroke
			(width 0.381)
			(type default)
		)
		(layer "In4.Cu")
	)
	(gr_line
		(start 6.2484 -81.026)
		(end 9.2964 -77.978)
		(stroke
			(width 0.381)
			(type default)
		)
		(layer "In4.Cu")
	)
	(gr_line
		(start 8.0264 -89.3318)
		(end 6.2484 -87.5538)
		(stroke
			(width 0.381)
			(type default)
		)
		(layer "In4.Cu")
	)
	(gr_line
		(start 9.2964 -77.978)
		(end 23.3934 -77.978)
		(stroke
			(width 0.381)
			(type default)
		)
		(layer "In4.Cu")
	)
	(gr_line
		(start 22.474682 -114.191796)
		(end 22.474682 -89.3318)
		(stroke
			(width 0.381)
			(type default)
		)
		(layer "In4.Cu")
	)
	(gr_line
		(start 22.474682 -89.705688)
		(end 22.144736 -89.375742)
		(stroke
			(width 0.381)
			(type default)
		)
		(layer "In4.Cu")
	)
	(gr_arc
		(start 22.474682 -89.705688)
		(mid 22.474936 -89.705942)
		(end 22.47519 -89.705688)
		(stroke
			(width 0.381)
			(type default)
		)
		(layer "In4.Cu")
	)
	(gr_line
		(start 22.474682 -89.3318)
		(end 8.0264 -89.3318)
		(stroke
			(width 0.381)
			(type default)
		)
		(layer "In4.Cu")
	)
	(gr_line
		(start 22.474682 -89.3318)
		(end 22.479 -89.3318)
		(stroke
			(width 0.381)
			(type default)
		)
		(layer "In4.Cu")
	)
	(gr_line
		(start 22.479 -89.3318)
		(end 22.474682 -89.336118)
		(stroke
			(width 0.381)
			(type default)
		)
		(layer "In4.Cu")
	)
	(gr_line
		(start 22.805136 -89.375742)
		(end 22.47519 -89.705688)
		(stroke
			(width 0.381)
			(type default)
		)
		(layer "In4.Cu")
	)
	(gr_line
		(start 23.3934 -77.978)
		(end 25.2476 -76.1238)
		(stroke
			(width 0.381)
			(type default)
		)
		(layer "In4.Cu")
	)
	(gr_line
		(start 23.920704 -115.637818)
		(end 22.474682 -114.191796)
		(stroke
			(width 0.381)
			(type default)
		)
		(layer "In4.Cu")
	)
	(gr_line
		(start 25.2476 -76.1238)
		(end 25.2476 -46.101)
		(stroke
			(width 0.381)
			(type default)
		)
		(layer "In4.Cu")
	)
	(gr_line
		(start 25.2476 -46.101)
		(end 30.7848 -40.5638)
		(stroke
			(width 0.381)
			(type default)
		)
		(layer "In4.Cu")
	)
	(gr_line
		(start 29.845 -75.946)
		(end 31.369 -77.47)
		(stroke
			(width 0.381)
			(type default)
		)
		(layer "In4.Cu")
	)
	(gr_line
		(start 29.845 -50.2158)
		(end 29.845 -75.946)
		(stroke
			(width 0.381)
			(type default)
		)
		(layer "In4.Cu")
	)
	(gr_line
		(start 30.7848 -40.5638)
		(end 30.7848 -25.146)
		(stroke
			(width 0.381)
			(type default)
		)
		(layer "In4.Cu")
	)
	(gr_line
		(start 30.7848 -25.146)
		(end 38.481 -17.4498)
		(stroke
			(width 0.381)
			(type default)
		)
		(layer "In4.Cu")
	)
	(gr_line
		(start 31.369 -77.47)
		(end 50.800254 -77.47)
		(stroke
			(width 0.381)
			(type default)
		)
		(layer "In4.Cu")
	)
	(gr_line
		(start 35.0266 -45.0342)
		(end 29.845 -50.2158)
		(stroke
			(width 0.381)
			(type default)
		)
		(layer "In4.Cu")
	)
	(gr_line
		(start 35.0266 -28.448)
		(end 35.0266 -45.0342)
		(stroke
			(width 0.381)
			(type default)
		)
		(layer "In4.Cu")
	)
	(gr_line
		(start 38.481 -17.4498)
		(end 59.2836 -17.4498)
		(stroke
			(width 0.381)
			(type default)
		)
		(layer "In4.Cu")
	)
	(gr_line
		(start 40.132 -23.3426)
		(end 35.0266 -28.448)
		(stroke
			(width 0.381)
			(type default)
		)
		(layer "In4.Cu")
	)
	(gr_line
		(start 45.36948 -115.637818)
		(end 45.699426 -115.967764)
		(stroke
			(width 0.381)
			(type default)
		)
		(layer "In4.Cu")
	)
	(gr_arc
		(start 45.36948 -115.63731)
		(mid 45.369226 -115.637564)
		(end 45.36948 -115.637818)
		(stroke
			(width 0.381)
			(type default)
		)
		(layer "In4.Cu")
	)
	(gr_line
		(start 45.389546 -143.820642)
		(end 45.719492 -143.490696)
		(stroke
			(width 0.381)
			(type default)
		)
		(layer "In4.Cu")
	)
	(gr_line
		(start 45.699426 -115.307364)
		(end 45.36948 -115.63731)
		(stroke
			(width 0.381)
			(type default)
		)
		(layer "In4.Cu")
	)
	(gr_line
		(start 45.719746 -115.637818)
		(end 23.920704 -115.637818)
		(stroke
			(width 0.381)
			(type default)
		)
		(layer "In4.Cu")
	)
	(gr_line
		(start 45.719746 -115.637818)
		(end 45.72 -115.638072)
		(stroke
			(width 0.381)
			(type default)
		)
		(layer "In4.Cu")
	)
	(gr_line
		(start 45.72 -144.2974)
		(end 45.847 -144.4244)
		(stroke
			(width 0.381)
			(type default)
		)
		(layer "In4.Cu")
	)
	(gr_arc
		(start 45.72 -143.490696)
		(mid 45.719746 -143.490442)
		(end 45.719492 -143.490696)
		(stroke
			(width 0.381)
			(type default)
		)
		(layer "In4.Cu")
	)
	(gr_line
		(start 45.72 -143.490696)
		(end 46.049946 -143.820642)
		(stroke
			(width 0.381)
			(type default)
		)
		(layer "In4.Cu")
	)
	(gr_line
		(start 45.72 -115.638072)
		(end 45.72 -144.2974)
		(stroke
			(width 0.381)
			(type default)
		)
		(layer "In4.Cu")
	)
	(gr_line
		(start 45.72 -115.637564)
		(end 45.719746 -115.637818)
		(stroke
			(width 0.381)
			(type default)
		)
		(layer "In4.Cu")
	)
	(gr_line
		(start 45.72 -106.173778)
		(end 45.72 -115.637564)
		(stroke
			(width 0.381)
			(type default)
		)
		(layer "In4.Cu")
	)
	(gr_line
		(start 46.806866 -105.086912)
		(end 45.72 -106.173778)
		(stroke
			(width 0.381)
			(type default)
		)
		(layer "In4.Cu")
	)
	(gr_line
		(start 50.3428 -77.4954)
		(end 50.3428 -77.47)
		(stroke
			(width 0.381)
			(type default)
		)
		(layer "In4.Cu")
	)
	(gr_line
		(start 50.3428 -77.47)
		(end 50.8 -77.0128)
		(stroke
			(width 0.381)
			(type default)
		)
		(layer "In4.Cu")
	)
	(gr_line
		(start 50.8 -77.9526)
		(end 50.3428 -77.4954)
		(stroke
			(width 0.381)
			(type default)
		)
		(layer "In4.Cu")
	)
	(gr_line
		(start 50.8 -77.469746)
		(end 50.799746 -77.47)
		(stroke
			(width 0.381)
			(type default)
		)
		(layer "In4.Cu")
	)
	(gr_line
		(start 50.8 -77.469746)
		(end 50.800254 -77.47)
		(stroke
			(width 0.381)
			(type default)
		)
		(layer "In4.Cu")
	)
	(gr_line
		(start 50.8 -55.372)
		(end 50.8 -77.469746)
		(stroke
			(width 0.381)
			(type default)
		)
		(layer "In4.Cu")
	)
	(gr_line
		(start 50.800254 -79.222854)
		(end 52.2986 -80.7212)
		(stroke
			(width 0.381)
			(type default)
		)
		(layer "In4.Cu")
	)
	(gr_line
		(start 50.800254 -77.47)
		(end 50.800254 -79.222854)
		(stroke
			(width 0.381)
			(type default)
		)
		(layer "In4.Cu")
	)
	(gr_line
		(start 52.2986 -80.7212)
		(end 85.876638 -80.7212)
		(stroke
			(width 0.381)
			(type default)
		)
		(layer "In4.Cu")
	)
	(gr_line
		(start 59.2836 -17.4498)
		(end 60.1218 -16.6116)
		(stroke
			(width 0.381)
			(type default)
		)
		(layer "In4.Cu")
	)
	(gr_line
		(start 59.352434 -46.819566)
		(end 50.8 -55.372)
		(stroke
			(width 0.381)
			(type default)
		)
		(layer "In4.Cu")
	)
	(gr_arc
		(start 59.352434 -46.819566)
		(mid 59.3579 -46.811416)
		(end 59.3598 -46.801786)
		(stroke
			(width 0.381)
			(type default)
		)
		(layer "In4.Cu")
	)
	(gr_line
		(start 59.3598 -34.173414)
		(end 59.3598 -46.801786)
		(stroke
			(width 0.381)
			(type default)
		)
		(layer "In4.Cu")
	)
	(gr_arc
		(start 59.367166 -34.155634)
		(mid 59.361769 -34.163806)
		(end 59.3598 -34.173414)
		(stroke
			(width 0.381)
			(type default)
		)
		(layer "In4.Cu")
	)
	(gr_line
		(start 59.8424 -33.6804)
		(end 59.367166 -34.155634)
		(stroke
			(width 0.381)
			(type default)
		)
		(layer "In4.Cu")
	)
	(gr_line
		(start 60.1218 -16.6116)
		(end 60.1218 -13.97)
		(stroke
			(width 0.381)
			(type default)
		)
		(layer "In4.Cu")
	)
	(gr_line
		(start 60.1218 -13.97)
		(end 61.495686 -12.596114)
		(stroke
			(width 0.381)
			(type default)
		)
		(layer "In4.Cu")
	)
	(gr_line
		(start 61.495686 -12.596114)
		(end 66.650108 -12.596114)
		(stroke
			(width 0.381)
			(type default)
		)
		(layer "In4.Cu")
	)
	(gr_line
		(start 63.754 -23.3426)
		(end 40.132 -23.3426)
		(stroke
			(width 0.381)
			(type default)
		)
		(layer "In4.Cu")
	)
	(gr_line
		(start 66.650108 -12.596114)
		(end 67.183 -13.129006)
		(stroke
			(width 0.381)
			(type default)
		)
		(layer "In4.Cu")
	)
	(gr_line
		(start 67.183 -19.9136)
		(end 63.754 -23.3426)
		(stroke
			(width 0.381)
			(type default)
		)
		(layer "In4.Cu")
	)
	(gr_line
		(start 67.183 -13.129006)
		(end 67.183 -19.9136)
		(stroke
			(width 0.381)
			(type default)
		)
		(layer "In4.Cu")
	)
	(gr_line
		(start 68.4276 -89.3318)
		(end 22.479 -89.3318)
		(stroke
			(width 0.381)
			(type default)
		)
		(layer "In4.Cu")
	)
	(gr_line
		(start 69.2912 -90.1954)
		(end 68.4276 -89.3318)
		(stroke
			(width 0.381)
			(type default)
		)
		(layer "In4.Cu")
	)
	(gr_line
		(start 72.3646 -60.5536)
		(end 73.855834 -62.044834)
		(stroke
			(width 0.381)
			(type default)
		)
		(layer "In4.Cu")
	)
	(gr_line
		(start 72.3646 -34.1376)
		(end 71.9328 -33.7058)
		(stroke
			(width 0.381)
			(type default)
		)
		(layer "In4.Cu")
	)
	(gr_line
		(start 72.3646 -34.1376)
		(end 72.7964 -33.7058)
		(stroke
			(width 0.381)
			(type default)
		)
		(layer "In4.Cu")
	)
	(gr_line
		(start 72.3646 -33.7058)
		(end 72.3646 -60.5536)
		(stroke
			(width 0.381)
			(type default)
		)
		(layer "In4.Cu")
	)
	(gr_line
		(start 73.855834 -62.044834)
		(end 97.706434 -62.044834)
		(stroke
			(width 0.381)
			(type default)
		)
		(layer "In4.Cu")
	)
	(gr_line
		(start 83.002374 -144.999964)
		(end 1.999996 -144.999964)
		(stroke
			(width 2.54)
			(type default)
		)
		(layer "In4.Cu")
	)
	(gr_arc
		(start 83.002374 -144.999964)
		(mid 84.41672 -144.414257)
		(end 85.002624 -142.999968)
		(stroke
			(width 2.54)
			(type default)
		)
		(layer "In4.Cu")
	)
	(gr_line
		(start 83.762088 -105.086912)
		(end 46.806866 -105.086912)
		(stroke
			(width 0.381)
			(type default)
		)
		(layer "In4.Cu")
	)
	(gr_line
		(start 85.002624 -132.26288)
		(end 85.002624 -142.999968)
		(stroke
			(width 2.54)
			(type default)
		)
		(layer "In4.Cu")
	)
	(gr_line
		(start 85.1408 -33.6804)
		(end 59.8424 -33.6804)
		(stroke
			(width 0.381)
			(type default)
		)
		(layer "In4.Cu")
	)
	(gr_arc
		(start 85.438742 -12.399772)
		(mid 85.999955 -12.961366)
		(end 86.561422 -12.400026)
		(stroke
			(width 0.2)
			(type default)
		)
		(layer "In4.Cu")
	)
	(gr_line
		(start 85.438742 -10.999978)
		(end 85.438742 -12.399772)
		(stroke
			(width 0.2)
			(type default)
		)
		(layer "In4.Cu")
	)
	(gr_arc
		(start 85.438742 -5.199888)
		(mid 85.999955 -5.761482)
		(end 86.561422 -5.200142)
		(stroke
			(width 0.2)
			(type default)
		)
		(layer "In4.Cu")
	)
	(gr_line
		(start 85.438742 -3.800094)
		(end 85.438742 -5.199888)
		(stroke
			(width 0.2)
			(type default)
		)
		(layer "In4.Cu")
	)
	(gr_line
		(start 85.876638 -80.7212)
		(end 87.036656 -79.561182)
		(stroke
			(width 0.381)
			(type default)
		)
		(layer "In4.Cu")
	)
	(gr_line
		(start 86.561422 -12.400026)
		(end 86.561422 -10.999978)
		(stroke
			(width 0.2)
			(type default)
		)
		(layer "In4.Cu")
	)
	(gr_arc
		(start 86.561422 -10.999978)
		(mid 86.000082 -10.438638)
		(end 85.438742 -10.999978)
		(stroke
			(width 0.2)
			(type default)
		)
		(layer "In4.Cu")
	)
	(gr_line
		(start 86.561422 -5.200142)
		(end 86.561422 -3.800094)
		(stroke
			(width 0.2)
			(type default)
		)
		(layer "In4.Cu")
	)
	(gr_arc
		(start 86.561422 -3.800094)
		(mid 86.000082 -3.238754)
		(end 85.438742 -3.800094)
		(stroke
			(width 0.2)
			(type default)
		)
		(layer "In4.Cu")
	)
	(gr_line
		(start 87.036656 -79.561182)
		(end 95.385636 -79.561182)
		(stroke
			(width 0.381)
			(type default)
		)
		(layer "In4.Cu")
	)
	(gr_arc
		(start 87.23884 -11.199876)
		(mid 87.800053 -11.76147)
		(end 88.36152 -11.20013)
		(stroke
			(width 0.2)
			(type default)
		)
		(layer "In4.Cu")
	)
	(gr_line
		(start 87.23884 -9.800082)
		(end 87.23884 -11.199876)
		(stroke
			(width 0.2)
			(type default)
		)
		(layer "In4.Cu")
	)
	(gr_arc
		(start 87.23884 -3.999738)
		(mid 87.800053 -4.561332)
		(end 88.36152 -3.999992)
		(stroke
			(width 0.2)
			(type default)
		)
		(layer "In4.Cu")
	)
	(gr_line
		(start 87.23884 -2.600198)
		(end 87.23884 -3.999738)
		(stroke
			(width 0.2)
			(type default)
		)
		(layer "In4.Cu")
	)
	(gr_line
		(start 88.36152 -11.20013)
		(end 88.36152 -9.800082)
		(stroke
			(width 0.2)
			(type default)
		)
		(layer "In4.Cu")
	)
	(gr_arc
		(start 88.36152 -9.800082)
		(mid 87.80018 -9.238742)
		(end 87.23884 -9.800082)
		(stroke
			(width 0.2)
			(type default)
		)
		(layer "In4.Cu")
	)
	(gr_line
		(start 88.36152 -3.999992)
		(end 88.36152 -2.600198)
		(stroke
			(width 0.2)
			(type default)
		)
		(layer "In4.Cu")
	)
	(gr_arc
		(start 88.36152 -2.600198)
		(mid 87.80018 -2.038858)
		(end 87.23884 -2.600198)
		(stroke
			(width 0.2)
			(type default)
		)
		(layer "In4.Cu")
	)
	(gr_line
		(start 88.5952 -30.226)
		(end 85.1408 -33.6804)
		(stroke
			(width 0.381)
			(type default)
		)
		(layer "In4.Cu")
	)
	(gr_arc
		(start 89.038684 -12.399772)
		(mid 89.599897 -12.961366)
		(end 90.161364 -12.400026)
		(stroke
			(width 0.2)
			(type default)
		)
		(layer "In4.Cu")
	)
	(gr_line
		(start 89.038684 -10.999978)
		(end 89.038684 -12.399772)
		(stroke
			(width 0.2)
			(type default)
		)
		(layer "In4.Cu")
	)
	(gr_arc
		(start 89.038684 -5.199888)
		(mid 89.599897 -5.761482)
		(end 90.161364 -5.200142)
		(stroke
			(width 0.2)
			(type default)
		)
		(layer "In4.Cu")
	)
	(gr_line
		(start 89.038684 -3.800094)
		(end 89.038684 -5.199888)
		(stroke
			(width 0.2)
			(type default)
		)
		(layer "In4.Cu")
	)
	(gr_arc
		(start 89.212674 -127.325628)
		(mid 86.197998 -129.018598)
		(end 85.002624 -132.26288)
		(stroke
			(width 2.54)
			(type default)
		)
		(layer "In4.Cu")
	)
	(gr_line
		(start 90.161364 -12.400026)
		(end 90.161364 -10.999978)
		(stroke
			(width 0.2)
			(type default)
		)
		(layer "In4.Cu")
	)
	(gr_arc
		(start 90.161364 -10.999978)
		(mid 89.600024 -10.438638)
		(end 89.038684 -10.999978)
		(stroke
			(width 0.2)
			(type default)
		)
		(layer "In4.Cu")
	)
	(gr_line
		(start 90.161364 -5.200142)
		(end 90.161364 -3.800094)
		(stroke
			(width 0.2)
			(type default)
		)
		(layer "In4.Cu")
	)
	(gr_arc
		(start 90.161364 -3.800094)
		(mid 89.600024 -3.238754)
		(end 89.038684 -3.800094)
		(stroke
			(width 0.2)
			(type default)
		)
		(layer "In4.Cu")
	)
	(gr_arc
		(start 90.838782 -11.199876)
		(mid 91.399995 -11.76147)
		(end 91.961462 -11.20013)
		(stroke
			(width 0.2)
			(type default)
		)
		(layer "In4.Cu")
	)
	(gr_line
		(start 90.838782 -9.800082)
		(end 90.838782 -11.199876)
		(stroke
			(width 0.2)
			(type default)
		)
		(layer "In4.Cu")
	)
	(gr_arc
		(start 90.838782 -3.999738)
		(mid 91.399995 -4.561332)
		(end 91.961462 -3.999992)
		(stroke
			(width 0.2)
			(type default)
		)
		(layer "In4.Cu")
	)
	(gr_line
		(start 90.838782 -2.600198)
		(end 90.838782 -3.999738)
		(stroke
			(width 0.2)
			(type default)
		)
		(layer "In4.Cu")
	)
	(gr_line
		(start 90.932 -97.917)
		(end 83.762088 -105.086912)
		(stroke
			(width 0.381)
			(type default)
		)
		(layer "In4.Cu")
	)
	(gr_line
		(start 91.961462 -11.20013)
		(end 91.961462 -9.800082)
		(stroke
			(width 0.2)
			(type default)
		)
		(layer "In4.Cu")
	)
	(gr_arc
		(start 91.961462 -9.800082)
		(mid 91.400122 -9.238742)
		(end 90.838782 -9.800082)
		(stroke
			(width 0.2)
			(type default)
		)
		(layer "In4.Cu")
	)
	(gr_line
		(start 91.961462 -3.999992)
		(end 91.961462 -2.600198)
		(stroke
			(width 0.2)
			(type default)
		)
		(layer "In4.Cu")
	)
	(gr_arc
		(start 91.961462 -2.600198)
		(mid 91.400122 -2.038858)
		(end 90.838782 -2.600198)
		(stroke
			(width 0.2)
			(type default)
		)
		(layer "In4.Cu")
	)
	(gr_arc
		(start 92.638626 -12.399772)
		(mid 93.199839 -12.961366)
		(end 93.761306 -12.400026)
		(stroke
			(width 0.2)
			(type default)
		)
		(layer "In4.Cu")
	)
	(gr_line
		(start 92.638626 -10.999978)
		(end 92.638626 -12.399772)
		(stroke
			(width 0.2)
			(type default)
		)
		(layer "In4.Cu")
	)
	(gr_arc
		(start 92.638626 -5.199888)
		(mid 93.199839 -5.761482)
		(end 93.761306 -5.200142)
		(stroke
			(width 0.2)
			(type default)
		)
		(layer "In4.Cu")
	)
	(gr_line
		(start 92.638626 -3.800094)
		(end 92.638626 -5.199888)
		(stroke
			(width 0.2)
			(type default)
		)
		(layer "In4.Cu")
	)
	(gr_line
		(start 93.761306 -12.400026)
		(end 93.761306 -10.999978)
		(stroke
			(width 0.2)
			(type default)
		)
		(layer "In4.Cu")
	)
	(gr_arc
		(start 93.761306 -10.999978)
		(mid 93.199966 -10.438638)
		(end 92.638626 -10.999978)
		(stroke
			(width 0.2)
			(type default)
		)
		(layer "In4.Cu")
	)
	(gr_line
		(start 93.761306 -5.200142)
		(end 93.761306 -3.800094)
		(stroke
			(width 0.2)
			(type default)
		)
		(layer "In4.Cu")
	)
	(gr_arc
		(start 93.761306 -3.800094)
		(mid 93.199966 -3.238754)
		(end 92.638626 -3.800094)
		(stroke
			(width 0.2)
			(type default)
		)
		(layer "In4.Cu")
	)
	(gr_arc
		(start 94.438724 -11.199876)
		(mid 94.999937 -11.76147)
		(end 95.561404 -11.20013)
		(stroke
			(width 0.2)
			(type default)
		)
		(layer "In4.Cu")
	)
	(gr_line
		(start 94.438724 -9.800082)
		(end 94.438724 -11.199876)
		(stroke
			(width 0.2)
			(type default)
		)
		(layer "In4.Cu")
	)
	(gr_arc
		(start 94.438724 -3.999738)
		(mid 94.999937 -4.561332)
		(end 95.561404 -3.999992)
		(stroke
			(width 0.2)
			(type default)
		)
		(layer "In4.Cu")
	)
	(gr_line
		(start 94.438724 -2.600198)
		(end 94.438724 -3.999738)
		(stroke
			(width 0.2)
			(type default)
		)
		(layer "In4.Cu")
	)
	(gr_line
		(start 95.385636 -79.561182)
		(end 96.545654 -80.7212)
		(stroke
			(width 0.381)
			(type default)
		)
		(layer "In4.Cu")
	)
	(gr_line
		(start 95.561404 -11.20013)
		(end 95.561404 -9.800082)
		(stroke
			(width 0.2)
			(type default)
		)
		(layer "In4.Cu")
	)
	(gr_arc
		(start 95.561404 -9.800082)
		(mid 95.000064 -9.238742)
		(end 94.438724 -9.800082)
		(stroke
			(width 0.2)
			(type default)
		)
		(layer "In4.Cu")
	)
	(gr_line
		(start 95.561404 -3.999992)
		(end 95.561404 -2.600198)
		(stroke
			(width 0.2)
			(type default)
		)
		(layer "In4.Cu")
	)
	(gr_arc
		(start 95.561404 -2.600198)
		(mid 95.000064 -2.038858)
		(end 94.438724 -2.600198)
		(stroke
			(width 0.2)
			(type default)
		)
		(layer "In4.Cu")
	)
	(gr_arc
		(start 96.238822 -12.399772)
		(mid 96.800035 -12.961366)
		(end 97.361502 -12.400026)
		(stroke
			(width 0.2)
			(type default)
		)
		(layer "In4.Cu")
	)
	(gr_line
		(start 96.238822 -10.999978)
		(end 96.238822 -12.399772)
		(stroke
			(width 0.2)
			(type default)
		)
		(layer "In4.Cu")
	)
	(gr_arc
		(start 96.238822 -5.199888)
		(mid 96.800035 -5.761482)
		(end 97.361502 -5.200142)
		(stroke
			(width 0.2)
			(type default)
		)
		(layer "In4.Cu")
	)
	(gr_line
		(start 96.238822 -3.800094)
		(end 96.238822 -5.199888)
		(stroke
			(width 0.2)
			(type default)
		)
		(layer "In4.Cu")
	)
	(gr_line
		(start 96.545654 -80.7212)
		(end 98.2726 -80.7212)
		(stroke
			(width 0.381)
			(type default)
		)
		(layer "In4.Cu")
	)
	(gr_line
		(start 97.361502 -12.400026)
		(end 97.361502 -10.999978)
		(stroke
			(width 0.2)
			(type default)
		)
		(layer "In4.Cu")
	)
	(gr_arc
		(start 97.361502 -10.999978)
		(mid 96.800162 -10.438638)
		(end 96.238822 -10.999978)
		(stroke
			(width 0.2)
			(type default)
		)
		(layer "In4.Cu")
	)
	(gr_line
		(start 97.361502 -5.200142)
		(end 97.361502 -3.800094)
		(stroke
			(width 0.2)
			(type default)
		)
		(layer "In4.Cu")
	)
	(gr_arc
		(start 97.361502 -3.800094)
		(mid 96.800162 -3.238754)
		(end 96.238822 -3.800094)
		(stroke
			(width 0.2)
			(type default)
		)
		(layer "In4.Cu")
	)
	(gr_line
		(start 97.499932 -126.000002)
		(end 89.212674 -127.325628)
		(stroke
			(width 2.54)
			(type default)
		)
		(layer "In4.Cu")
	)
	(gr_line
		(start 97.7138 -64.9986)
		(end 97.7138 -58.455814)
		(stroke
			(width 0.381)
			(type default)
		)
		(layer "In4.Cu")
	)
	(gr_line
		(start 97.7138 -58.455814)
		(end 99.603814 -56.5658)
		(stroke
			(width 0.381)
			(type default)
		)
		(layer "In4.Cu")
	)
	(gr_arc
		(start 98.038666 -11.199876)
		(mid 98.599879 -11.76147)
		(end 99.161346 -11.20013)
		(stroke
			(width 0.2)
			(type default)
		)
		(layer "In4.Cu")
	)
	(gr_line
		(start 98.038666 -9.800082)
		(end 98.038666 -11.199876)
		(stroke
			(width 0.2)
			(type default)
		)
		(layer "In4.Cu")
	)
	(gr_arc
		(start 98.038666 -3.999738)
		(mid 98.599879 -4.561332)
		(end 99.161346 -3.999992)
		(stroke
			(width 0.2)
			(type default)
		)
		(layer "In4.Cu")
	)
	(gr_line
		(start 98.038666 -2.600198)
		(end 98.038666 -3.999738)
		(stroke
			(width 0.2)
			(type default)
		)
		(layer "In4.Cu")
	)
	(gr_line
		(start 98.2218 -65.5066)
		(end 97.7138 -64.9986)
		(stroke
			(width 0.381)
			(type default)
		)
		(layer "In4.Cu")
	)
	(gr_line
		(start 98.2726 -80.7212)
		(end 98.5266 -80.4672)
		(stroke
			(width 0.381)
			(type default)
		)
		(layer "In4.Cu")
	)
	(gr_line
		(start 98.5266 -80.4672)
		(end 105.261664 -80.4672)
		(stroke
			(width 0.381)
			(type default)
		)
		(layer "In4.Cu")
	)
	(gr_arc
		(start 98.641916 -54.99989)
		(mid 98.999929 -55.358284)
		(end 99.358196 -55.000144)
		(stroke
			(width 0.2)
			(type default)
		)
		(layer "In4.Cu")
	)
	(gr_line
		(start 98.641916 -54.000146)
		(end 98.641916 -54.99989)
		(stroke
			(width 0.2)
			(type default)
		)
		(layer "In4.Cu")
	)
	(gr_line
		(start 99.161346 -11.20013)
		(end 99.161346 -9.800082)
		(stroke
			(width 0.2)
			(type default)
		)
		(layer "In4.Cu")
	)
	(gr_arc
		(start 99.161346 -9.800082)
		(mid 98.600006 -9.238742)
		(end 98.038666 -9.800082)
		(stroke
			(width 0.2)
			(type default)
		)
		(layer "In4.Cu")
	)
	(gr_line
		(start 99.161346 -3.999992)
		(end 99.161346 -2.600198)
		(stroke
			(width 0.2)
			(type default)
		)
		(layer "In4.Cu")
	)
	(gr_arc
		(start 99.161346 -2.600198)
		(mid 98.600006 -2.038858)
		(end 98.038666 -2.600198)
		(stroke
			(width 0.2)
			(type default)
		)
		(layer "In4.Cu")
	)
	(gr_line
		(start 99.358196 -55.000144)
		(end 99.358196 -54.000146)
		(stroke
			(width 0.2)
			(type default)
		)
		(layer "In4.Cu")
	)
	(gr_arc
		(start 99.358196 -54.000146)
		(mid 99.000056 -53.642006)
		(end 98.641916 -54.000146)
		(stroke
			(width 0.2)
			(type default)
		)
		(layer "In4.Cu")
	)
	(gr_line
		(start 99.603814 -56.5658)
		(end 105.05948 -56.5658)
		(stroke
			(width 0.381)
			(type default)
		)
		(layer "In4.Cu")
	)
	(gr_arc
		(start 99.641914 -51.999896)
		(mid 99.999927 -52.35829)
		(end 100.358194 -52.00015)
		(stroke
			(width 0.2)
			(type default)
		)
		(layer "In4.Cu")
	)
	(gr_line
		(start 99.641914 -51.000152)
		(end 99.641914 -51.999896)
		(stroke
			(width 0.2)
			(type default)
		)
		(layer "In4.Cu")
	)
	(gr_arc
		(start 99.838764 -12.399772)
		(mid 100.399977 -12.961366)
		(end 100.961444 -12.400026)
		(stroke
			(width 0.2)
			(type default)
		)
		(layer "In4.Cu")
	)
	(gr_line
		(start 99.838764 -10.999978)
		(end 99.838764 -12.399772)
		(stroke
			(width 0.2)
			(type default)
		)
		(layer "In4.Cu")
	)
	(gr_arc
		(start 99.838764 -5.199888)
		(mid 100.399977 -5.761482)
		(end 100.961444 -5.200142)
		(stroke
			(width 0.2)
			(type default)
		)
		(layer "In4.Cu")
	)
	(gr_line
		(start 99.838764 -3.800094)
		(end 99.838764 -5.199888)
		(stroke
			(width 0.2)
			(type default)
		)
		(layer "In4.Cu")
	)
	(gr_line
		(start 100.358194 -52.00015)
		(end 100.358194 -51.000152)
		(stroke
			(width 0.2)
			(type default)
		)
		(layer "In4.Cu")
	)
	(gr_arc
		(start 100.358194 -51.000152)
		(mid 100.000054 -50.642012)
		(end 99.641914 -51.000152)
		(stroke
			(width 0.2)
			(type default)
		)
		(layer "In4.Cu")
	)
	(gr_arc
		(start 100.641912 -55.999888)
		(mid 100.999925 -56.358282)
		(end 101.358192 -56.000142)
		(stroke
			(width 0.2)
			(type default)
		)
		(layer "In4.Cu")
	)
	(gr_line
		(start 100.641912 -55.000144)
		(end 100.641912 -55.999888)
		(stroke
			(width 0.2)
			(type default)
		)
		(layer "In4.Cu")
	)
	(gr_arc
		(start 100.641912 -52.999894)
		(mid 100.999925 -53.358288)
		(end 101.358192 -53.000148)
		(stroke
			(width 0.2)
			(type default)
		)
		(layer "In4.Cu")
	)
	(gr_line
		(start 100.641912 -52.00015)
		(end 100.641912 -52.999894)
		(stroke
			(width 0.2)
			(type default)
		)
		(layer "In4.Cu")
	)
	(gr_line
		(start 100.961444 -12.400026)
		(end 100.961444 -10.999978)
		(stroke
			(width 0.2)
			(type default)
		)
		(layer "In4.Cu")
	)
	(gr_arc
		(start 100.961444 -10.999978)
		(mid 100.400104 -10.438638)
		(end 99.838764 -10.999978)
		(stroke
			(width 0.2)
			(type default)
		)
		(layer "In4.Cu")
	)
	(gr_line
		(start 100.961444 -5.200142)
		(end 100.961444 -3.800094)
		(stroke
			(width 0.2)
			(type default)
		)
		(layer "In4.Cu")
	)
	(gr_arc
		(start 100.961444 -3.800094)
		(mid 100.400104 -3.238754)
		(end 99.838764 -3.800094)
		(stroke
			(width 0.2)
			(type default)
		)
		(layer "In4.Cu")
	)
	(gr_line
		(start 101.358192 -56.000142)
		(end 101.358192 -55.000144)
		(stroke
			(width 0.2)
			(type default)
		)
		(layer "In4.Cu")
	)
	(gr_arc
		(start 101.358192 -55.000144)
		(mid 101.000052 -54.642004)
		(end 100.641912 -55.000144)
		(stroke
			(width 0.2)
			(type default)
		)
		(layer "In4.Cu")
	)
	(gr_line
		(start 101.358192 -53.000148)
		(end 101.358192 -52.00015)
		(stroke
			(width 0.2)
			(type default)
		)
		(layer "In4.Cu")
	)
	(gr_arc
		(start 101.358192 -52.00015)
		(mid 101.000052 -51.64201)
		(end 100.641912 -52.00015)
		(stroke
			(width 0.2)
			(type default)
		)
		(layer "In4.Cu")
	)
	(gr_arc
		(start 101.638862 -11.199876)
		(mid 102.200075 -11.76147)
		(end 102.761542 -11.20013)
		(stroke
			(width 0.2)
			(type default)
		)
		(layer "In4.Cu")
	)
	(gr_line
		(start 101.638862 -9.800082)
		(end 101.638862 -11.199876)
		(stroke
			(width 0.2)
			(type default)
		)
		(layer "In4.Cu")
	)
	(gr_arc
		(start 101.638862 -3.999738)
		(mid 102.200075 -4.561332)
		(end 102.761542 -3.999992)
		(stroke
			(width 0.2)
			(type default)
		)
		(layer "In4.Cu")
	)
	(gr_line
		(start 101.638862 -2.600198)
		(end 101.638862 -3.999738)
		(stroke
			(width 0.2)
			(type default)
		)
		(layer "In4.Cu")
	)
	(gr_arc
		(start 101.64191 -55.999888)
		(mid 101.999923 -56.358282)
		(end 102.35819 -56.000142)
		(stroke
			(width 0.2)
			(type default)
		)
		(layer "In4.Cu")
	)
	(gr_line
		(start 101.64191 -55.000144)
		(end 101.64191 -55.999888)
		(stroke
			(width 0.2)
			(type default)
		)
		(layer "In4.Cu")
	)
	(gr_arc
		(start 101.64191 -51.999896)
		(mid 101.999923 -52.35829)
		(end 102.35819 -52.00015)
		(stroke
			(width 0.2)
			(type default)
		)
		(layer "In4.Cu")
	)
	(gr_line
		(start 101.64191 -51.000152)
		(end 101.64191 -51.999896)
		(stroke
			(width 0.2)
			(type default)
		)
		(layer "In4.Cu")
	)
	(gr_arc
		(start 102.266496 -115.990878)
		(mid 102.491032 -116.733574)
		(end 103.233728 -116.509038)
		(stroke
			(width 0.2)
			(type default)
		)
		(layer "In4.Cu")
	)
	(gr_line
		(start 102.266496 -115.990624)
		(end 102.266496 -115.990878)
		(stroke
			(width 0.2)
			(type default)
		)
		(layer "In4.Cu")
	)
	(gr_arc
		(start 102.266496 -112.191038)
		(mid 102.491032 -112.933734)
		(end 103.233728 -112.709198)
		(stroke
			(width 0.2)
			(type default)
		)
		(layer "In4.Cu")
	)
	(gr_line
		(start 102.266496 -112.190784)
		(end 102.266496 -112.191038)
		(stroke
			(width 0.2)
			(type default)
		)
		(layer "In4.Cu")
	)
	(gr_line
		(start 102.311454 -108.415074)
		(end 102.311962 -108.415328)
		(stroke
			(width 0.2)
			(type default)
		)
		(layer "In4.Cu")
	)
	(gr_line
		(start 102.311454 -108.41482)
		(end 102.311454 -108.415074)
		(stroke
			(width 0.2)
			(type default)
		)
		(layer "In4.Cu")
	)
	(gr_line
		(start 102.311454 -104.61498)
		(end 102.311962 -104.615234)
		(stroke
			(width 0.2)
			(type default)
		)
		(layer "In4.Cu")
	)
	(gr_line
		(start 102.311454 -104.614726)
		(end 102.311454 -104.61498)
		(stroke
			(width 0.2)
			(type default)
		)
		(layer "In4.Cu")
	)
	(gr_arc
		(start 102.311962 -108.415328)
		(mid 102.515416 -109.088174)
		(end 103.188262 -108.88472)
		(stroke
			(width 0.2)
			(type default)
		)
		(layer "In4.Cu")
	)
	(gr_arc
		(start 102.311962 -104.615234)
		(mid 102.515416 -105.28808)
		(end 103.188262 -105.084626)
		(stroke
			(width 0.2)
			(type default)
		)
		(layer "In4.Cu")
	)
	(gr_line
		(start 102.35819 -56.000142)
		(end 102.35819 -55.000144)
		(stroke
			(width 0.2)
			(type default)
		)
		(layer "In4.Cu")
	)
	(gr_arc
		(start 102.35819 -55.000144)
		(mid 102.00005 -54.642004)
		(end 101.64191 -55.000144)
		(stroke
			(width 0.2)
			(type default)
		)
		(layer "In4.Cu")
	)
	(gr_line
		(start 102.35819 -52.00015)
		(end 102.35819 -51.000152)
		(stroke
			(width 0.2)
			(type default)
		)
		(layer "In4.Cu")
	)
	(gr_arc
		(start 102.35819 -51.000152)
		(mid 102.00005 -50.642012)
		(end 101.64191 -51.000152)
		(stroke
			(width 0.2)
			(type default)
		)
		(layer "In4.Cu")
	)
	(gr_arc
		(start 102.641908 -55.999888)
		(mid 102.999921 -56.358282)
		(end 103.358188 -56.000142)
		(stroke
			(width 0.2)
			(type default)
		)
		(layer "In4.Cu")
	)
	(gr_line
		(start 102.641908 -55.000144)
		(end 102.641908 -55.999888)
		(stroke
			(width 0.2)
			(type default)
		)
		(layer "In4.Cu")
	)
	(gr_arc
		(start 102.641908 -52.999894)
		(mid 102.999921 -53.358288)
		(end 103.358188 -53.000148)
		(stroke
			(width 0.2)
			(type default)
		)
		(layer "In4.Cu")
	)
	(gr_line
		(start 102.641908 -52.00015)
		(end 102.641908 -52.999894)
		(stroke
			(width 0.2)
			(type default)
		)
		(layer "In4.Cu")
	)
	(gr_line
		(start 102.761542 -11.20013)
		(end 102.761542 -9.800082)
		(stroke
			(width 0.2)
			(type default)
		)
		(layer "In4.Cu")
	)
	(gr_arc
		(start 102.761542 -9.800082)
		(mid 102.200202 -9.238742)
		(end 101.638862 -9.800082)
		(stroke
			(width 0.2)
			(type default)
		)
		(layer "In4.Cu")
	)
	(gr_line
		(start 102.761542 -3.999992)
		(end 102.761542 -2.600198)
		(stroke
			(width 0.2)
			(type default)
		)
		(layer "In4.Cu")
	)
	(gr_arc
		(start 102.761542 -2.600198)
		(mid 102.200202 -2.038858)
		(end 101.638862 -2.600198)
		(stroke
			(width 0.2)
			(type default)
		)
		(layer "In4.Cu")
	)
	(gr_line
		(start 103.016304 -114.59083)
		(end 102.266496 -115.990624)
		(stroke
			(width 0.2)
			(type default)
		)
		(layer "In4.Cu")
	)
	(gr_line
		(start 103.016304 -110.79099)
		(end 102.266496 -112.190784)
		(stroke
			(width 0.2)
			(type default)
		)
		(layer "In4.Cu")
	)
	(gr_line
		(start 103.061008 -107.015026)
		(end 102.311454 -108.41482)
		(stroke
			(width 0.2)
			(type default)
		)
		(layer "In4.Cu")
	)
	(gr_line
		(start 103.061008 -103.215186)
		(end 102.311454 -104.614726)
		(stroke
			(width 0.2)
			(type default)
		)
		(layer "In4.Cu")
	)
	(gr_line
		(start 103.06177 -107.01528)
		(end 103.061008 -107.015026)
		(stroke
			(width 0.2)
			(type default)
		)
		(layer "In4.Cu")
	)
	(gr_line
		(start 103.06177 -103.21544)
		(end 103.061008 -103.215186)
		(stroke
			(width 0.2)
			(type default)
		)
		(layer "In4.Cu")
	)
	(gr_line
		(start 103.188262 -108.88472)
		(end 103.189024 -108.884974)
		(stroke
			(width 0.2)
			(type default)
		)
		(layer "In4.Cu")
	)
	(gr_line
		(start 103.188262 -105.084626)
		(end 103.189024 -105.08488)
		(stroke
			(width 0.2)
			(type default)
		)
		(layer "In4.Cu")
	)
	(gr_line
		(start 103.189024 -108.884974)
		(end 103.938832 -107.484926)
		(stroke
			(width 0.2)
			(type default)
		)
		(layer "In4.Cu")
	)
	(gr_line
		(start 103.189024 -105.08488)
		(end 103.938832 -103.685086)
		(stroke
			(width 0.2)
			(type default)
		)
		(layer "In4.Cu")
	)
	(gr_line
		(start 103.233728 -116.509038)
		(end 103.983536 -115.10899)
		(stroke
			(width 0.2)
			(type default)
		)
		(layer "In4.Cu")
	)
	(gr_line
		(start 103.233728 -112.709198)
		(end 103.983536 -111.30915)
		(stroke
			(width 0.2)
			(type default)
		)
		(layer "In4.Cu")
	)
	(gr_line
		(start 103.358188 -56.000142)
		(end 103.358188 -55.000144)
		(stroke
			(width 0.2)
			(type default)
		)
		(layer "In4.Cu")
	)
	(gr_arc
		(start 103.358188 -55.000144)
		(mid 103.000048 -54.642004)
		(end 102.641908 -55.000144)
		(stroke
			(width 0.2)
			(type default)
		)
		(layer "In4.Cu")
	)
	(gr_line
		(start 103.358188 -53.000148)
		(end 103.358188 -52.00015)
		(stroke
			(width 0.2)
			(type default)
		)
		(layer "In4.Cu")
	)
	(gr_arc
		(start 103.358188 -52.00015)
		(mid 103.000048 -51.64201)
		(end 102.641908 -52.00015)
		(stroke
			(width 0.2)
			(type default)
		)
		(layer "In4.Cu")
	)
	(gr_arc
		(start 103.438706 -12.399772)
		(mid 103.999919 -12.961366)
		(end 104.561386 -12.400026)
		(stroke
			(width 0.2)
			(type default)
		)
		(layer "In4.Cu")
	)
	(gr_line
		(start 103.438706 -10.999978)
		(end 103.438706 -12.399772)
		(stroke
			(width 0.2)
			(type default)
		)
		(layer "In4.Cu")
	)
	(gr_arc
		(start 103.438706 -5.199888)
		(mid 103.999919 -5.761482)
		(end 104.561386 -5.200142)
		(stroke
			(width 0.2)
			(type default)
		)
		(layer "In4.Cu")
	)
	(gr_line
		(start 103.438706 -3.800094)
		(end 103.438706 -5.199888)
		(stroke
			(width 0.2)
			(type default)
		)
		(layer "In4.Cu")
	)
	(gr_arc
		(start 103.641906 -55.999888)
		(mid 103.999919 -56.358282)
		(end 104.358186 -56.000142)
		(stroke
			(width 0.2)
			(type default)
		)
		(layer "In4.Cu")
	)
	(gr_line
		(start 103.641906 -55.000144)
		(end 103.641906 -55.999888)
		(stroke
			(width 0.2)
			(type default)
		)
		(layer "In4.Cu")
	)
	(gr_arc
		(start 103.641906 -51.999896)
		(mid 103.999919 -52.35829)
		(end 104.358186 -52.00015)
		(stroke
			(width 0.2)
			(type default)
		)
		(layer "In4.Cu")
	)
	(gr_line
		(start 103.641906 -51.000152)
		(end 103.641906 -51.999896)
		(stroke
			(width 0.2)
			(type default)
		)
		(layer "In4.Cu")
	)
	(gr_arc
		(start 103.93807 -107.484672)
		(mid 103.734616 -106.811826)
		(end 103.06177 -107.01528)
		(stroke
			(width 0.2)
			(type default)
		)
		(layer "In4.Cu")
	)
	(gr_arc
		(start 103.93807 -103.684832)
		(mid 103.734616 -103.011986)
		(end 103.06177 -103.21544)
		(stroke
			(width 0.2)
			(type default)
		)
		(layer "In4.Cu")
	)
	(gr_line
		(start 103.938832 -107.484926)
		(end 103.93807 -107.484672)
		(stroke
			(width 0.2)
			(type default)
		)
		(layer "In4.Cu")
	)
	(gr_line
		(start 103.938832 -103.685086)
		(end 103.93807 -103.684832)
		(stroke
			(width 0.2)
			(type default)
		)
		(layer "In4.Cu")
	)
	(gr_arc
		(start 103.983536 -115.10899)
		(mid 103.759 -114.366294)
		(end 103.016304 -114.59083)
		(stroke
			(width 0.2)
			(type default)
		)
		(layer "In4.Cu")
	)
	(gr_arc
		(start 103.983536 -111.30915)
		(mid 103.759 -110.566454)
		(end 103.016304 -110.79099)
		(stroke
			(width 0.2)
			(type default)
		)
		(layer "In4.Cu")
	)
	(gr_line
		(start 104.358186 -56.000142)
		(end 104.358186 -55.000144)
		(stroke
			(width 0.2)
			(type default)
		)
		(layer "In4.Cu")
	)
	(gr_arc
		(start 104.358186 -55.000144)
		(mid 104.000046 -54.642004)
		(end 103.641906 -55.000144)
		(stroke
			(width 0.2)
			(type default)
		)
		(layer "In4.Cu")
	)
	(gr_line
		(start 104.358186 -52.00015)
		(end 104.358186 -51.000152)
		(stroke
			(width 0.2)
			(type default)
		)
		(layer "In4.Cu")
	)
	(gr_arc
		(start 104.358186 -51.000152)
		(mid 104.000046 -50.642012)
		(end 103.641906 -51.000152)
		(stroke
			(width 0.2)
			(type default)
		)
		(layer "In4.Cu")
	)
	(gr_arc
		(start 104.516428 -115.990624)
		(mid 104.740809 -116.733627)
		(end 105.48366 -116.509038)
		(stroke
			(width 0.2)
			(type default)
		)
		(layer "In4.Cu")
	)
	(gr_arc
		(start 104.516428 -112.190784)
		(mid 104.740809 -112.933787)
		(end 105.48366 -112.709198)
		(stroke
			(width 0.2)
			(type default)
		)
		(layer "In4.Cu")
	)
	(gr_line
		(start 104.561386 -108.415074)
		(end 104.561894 -108.415328)
		(stroke
			(width 0.2)
			(type default)
		)
		(layer "In4.Cu")
	)
	(gr_line
		(start 104.561386 -108.41482)
		(end 104.561386 -108.415074)
		(stroke
			(width 0.2)
			(type default)
		)
		(layer "In4.Cu")
	)
	(gr_line
		(start 104.561386 -104.61498)
		(end 104.561894 -104.615234)
		(stroke
			(width 0.2)
			(type default)
		)
		(layer "In4.Cu")
	)
	(gr_line
		(start 104.561386 -104.614472)
		(end 104.561386 -104.61498)
		(stroke
			(width 0.2)
			(type default)
		)
		(layer "In4.Cu")
	)
	(gr_line
		(start 104.561386 -12.400026)
		(end 104.561386 -10.999978)
		(stroke
			(width 0.2)
			(type default)
		)
		(layer "In4.Cu")
	)
	(gr_arc
		(start 104.561386 -10.999978)
		(mid 104.000046 -10.438638)
		(end 103.438706 -10.999978)
		(stroke
			(width 0.2)
			(type default)
		)
		(layer "In4.Cu")
	)
	(gr_line
		(start 104.561386 -5.200142)
		(end 104.561386 -3.800094)
		(stroke
			(width 0.2)
			(type default)
		)
		(layer "In4.Cu")
	)
	(gr_arc
		(start 104.561386 -3.800094)
		(mid 104.000046 -3.238754)
		(end 103.438706 -3.800094)
		(stroke
			(width 0.2)
			(type default)
		)
		(layer "In4.Cu")
	)
	(gr_arc
		(start 104.561894 -108.415328)
		(mid 104.765348 -109.088174)
		(end 105.438194 -108.88472)
		(stroke
			(width 0.2)
			(type default)
		)
		(layer "In4.Cu")
	)
	(gr_arc
		(start 104.561894 -104.615234)
		(mid 104.765348 -105.28808)
		(end 105.438194 -105.084626)
		(stroke
			(width 0.2)
			(type default)
		)
		(layer "In4.Cu")
	)
	(gr_arc
		(start 104.641904 -55.999888)
		(mid 104.999917 -56.358282)
		(end 105.358184 -56.000142)
		(stroke
			(width 0.2)
			(type default)
		)
		(layer "In4.Cu")
	)
	(gr_line
		(start 104.641904 -55.000144)
		(end 104.641904 -55.999888)
		(stroke
			(width 0.2)
			(type default)
		)
		(layer "In4.Cu")
	)
	(gr_arc
		(start 104.641904 -52.999894)
		(mid 104.999917 -53.358288)
		(end 105.358184 -53.000148)
		(stroke
			(width 0.2)
			(type default)
		)
		(layer "In4.Cu")
	)
	(gr_line
		(start 104.641904 -52.00015)
		(end 104.641904 -52.999894)
		(stroke
			(width 0.2)
			(type default)
		)
		(layer "In4.Cu")
	)
	(gr_line
		(start 105.05948 -56.5658)
		(end 108.99648 -60.5028)
		(stroke
			(width 0.381)
			(type default)
		)
		(layer "In4.Cu")
	)
	(gr_arc
		(start 105.238804 -11.199876)
		(mid 105.800017 -11.76147)
		(end 106.361484 -11.20013)
		(stroke
			(width 0.2)
			(type default)
		)
		(layer "In4.Cu")
	)
	(gr_line
		(start 105.238804 -9.800082)
		(end 105.238804 -11.199876)
		(stroke
			(width 0.2)
			(type default)
		)
		(layer "In4.Cu")
	)
	(gr_arc
		(start 105.238804 -3.999738)
		(mid 105.800017 -4.561332)
		(end 106.361484 -3.999992)
		(stroke
			(width 0.2)
			(type default)
		)
		(layer "In4.Cu")
	)
	(gr_line
		(start 105.238804 -2.600198)
		(end 105.238804 -3.999738)
		(stroke
			(width 0.2)
			(type default)
		)
		(layer "In4.Cu")
	)
	(gr_line
		(start 105.261664 -80.4672)
		(end 105.46969 -80.259174)
		(stroke
			(width 0.381)
			(type default)
		)
		(layer "In4.Cu")
	)
	(gr_line
		(start 105.26649 -114.59083)
		(end 104.516428 -115.990624)
		(stroke
			(width 0.2)
			(type default)
		)
		(layer "In4.Cu")
	)
	(gr_line
		(start 105.26649 -110.79099)
		(end 104.516428 -112.190784)
		(stroke
			(width 0.2)
			(type default)
		)
		(layer "In4.Cu")
	)
	(gr_line
		(start 105.311194 -107.014772)
		(end 104.561386 -108.41482)
		(stroke
			(width 0.2)
			(type default)
		)
		(layer "In4.Cu")
	)
	(gr_line
		(start 105.311194 -103.214932)
		(end 104.561386 -104.614472)
		(stroke
			(width 0.2)
			(type default)
		)
		(layer "In4.Cu")
	)
	(gr_line
		(start 105.311956 -107.01528)
		(end 105.311194 -107.014772)
		(stroke
			(width 0.2)
			(type default)
		)
		(layer "In4.Cu")
	)
	(gr_line
		(start 105.311956 -103.21544)
		(end 105.311194 -103.214932)
		(stroke
			(width 0.2)
			(type default)
		)
		(layer "In4.Cu")
	)
	(gr_line
		(start 105.358184 -56.000142)
		(end 105.358184 -55.000144)
		(stroke
			(width 0.2)
			(type default)
		)
		(layer "In4.Cu")
	)
	(gr_arc
		(start 105.358184 -55.000144)
		(mid 105.000044 -54.642004)
		(end 104.641904 -55.000144)
		(stroke
			(width 0.2)
			(type default)
		)
		(layer "In4.Cu")
	)
	(gr_line
		(start 105.358184 -53.000148)
		(end 105.358184 -52.00015)
		(stroke
			(width 0.2)
			(type default)
		)
		(layer "In4.Cu")
	)
	(gr_arc
		(start 105.358184 -52.00015)
		(mid 105.000044 -51.64201)
		(end 104.641904 -52.00015)
		(stroke
			(width 0.2)
			(type default)
		)
		(layer "In4.Cu")
	)
	(gr_line
		(start 105.438194 -108.88472)
		(end 105.438956 -108.885228)
		(stroke
			(width 0.2)
			(type default)
		)
		(layer "In4.Cu")
	)
	(gr_line
		(start 105.438194 -105.084626)
		(end 105.438956 -105.085134)
		(stroke
			(width 0.2)
			(type default)
		)
		(layer "In4.Cu")
	)
	(gr_line
		(start 105.438956 -108.885228)
		(end 106.189018 -107.48518)
		(stroke
			(width 0.2)
			(type default)
		)
		(layer "In4.Cu")
	)
	(gr_line
		(start 105.438956 -105.085134)
		(end 106.189018 -103.68534)
		(stroke
			(width 0.2)
			(type default)
		)
		(layer "In4.Cu")
	)
	(gr_line
		(start 105.46969 -80.259174)
		(end 105.46969 -79.770986)
		(stroke
			(width 0.381)
			(type default)
		)
		(layer "In4.Cu")
	)
	(gr_line
		(start 105.46969 -79.770986)
		(end 105.832656 -79.40802)
		(stroke
			(width 0.381)
			(type default)
		)
		(layer "In4.Cu")
	)
	(gr_line
		(start 105.48366 -116.509038)
		(end 106.233722 -115.10899)
		(stroke
			(width 0.2)
			(type default)
		)
		(layer "In4.Cu")
	)
	(gr_line
		(start 105.48366 -112.709198)
		(end 106.233722 -111.30915)
		(stroke
			(width 0.2)
			(type default)
		)
		(layer "In4.Cu")
	)
	(gr_arc
		(start 105.641902 -55.999888)
		(mid 105.999915 -56.358282)
		(end 106.358182 -56.000142)
		(stroke
			(width 0.2)
			(type default)
		)
		(layer "In4.Cu")
	)
	(gr_line
		(start 105.641902 -55.000144)
		(end 105.641902 -55.999888)
		(stroke
			(width 0.2)
			(type default)
		)
		(layer "In4.Cu")
	)
	(gr_arc
		(start 105.641902 -51.999896)
		(mid 105.999915 -52.35829)
		(end 106.358182 -52.00015)
		(stroke
			(width 0.2)
			(type default)
		)
		(layer "In4.Cu")
	)
	(gr_line
		(start 105.641902 -51.000152)
		(end 105.641902 -51.999896)
		(stroke
			(width 0.2)
			(type default)
		)
		(layer "In4.Cu")
	)
	(gr_line
		(start 105.832656 -79.40802)
		(end 106.328972 -79.40802)
		(stroke
			(width 0.381)
			(type default)
		)
		(layer "In4.Cu")
	)
	(gr_arc
		(start 106.188256 -107.484672)
		(mid 105.984802 -106.811826)
		(end 105.311956 -107.01528)
		(stroke
			(width 0.2)
			(type default)
		)
		(layer "In4.Cu")
	)
	(gr_arc
		(start 106.188256 -103.684832)
		(mid 105.984802 -103.011986)
		(end 105.311956 -103.21544)
		(stroke
			(width 0.2)
			(type default)
		)
		(layer "In4.Cu")
	)
	(gr_line
		(start 106.189018 -107.48518)
		(end 106.188256 -107.484672)
		(stroke
			(width 0.2)
			(type default)
		)
		(layer "In4.Cu")
	)
	(gr_line
		(start 106.189018 -103.68534)
		(end 106.188256 -103.684832)
		(stroke
			(width 0.2)
			(type default)
		)
		(layer "In4.Cu")
	)
	(gr_arc
		(start 106.233722 -115.10899)
		(mid 106.009186 -114.366294)
		(end 105.26649 -114.59083)
		(stroke
			(width 0.2)
			(type default)
		)
		(layer "In4.Cu")
	)
	(gr_arc
		(start 106.233722 -111.30915)
		(mid 106.009186 -110.566454)
		(end 105.26649 -110.79099)
		(stroke
			(width 0.2)
			(type default)
		)
		(layer "In4.Cu")
	)
	(gr_line
		(start 106.328972 -79.40802)
		(end 106.4768 -79.260192)
		(stroke
			(width 0.381)
			(type default)
		)
		(layer "In4.Cu")
	)
	(gr_line
		(start 106.358182 -56.000142)
		(end 106.358182 -55.000144)
		(stroke
			(width 0.2)
			(type default)
		)
		(layer "In4.Cu")
	)
	(gr_arc
		(start 106.358182 -55.000144)
		(mid 106.000042 -54.642004)
		(end 105.641902 -55.000144)
		(stroke
			(width 0.2)
			(type default)
		)
		(layer "In4.Cu")
	)
	(gr_line
		(start 106.358182 -52.00015)
		(end 106.358182 -51.000152)
		(stroke
			(width 0.2)
			(type default)
		)
		(layer "In4.Cu")
	)
	(gr_arc
		(start 106.358182 -51.000152)
		(mid 106.000042 -50.642012)
		(end 105.641902 -51.000152)
		(stroke
			(width 0.2)
			(type default)
		)
		(layer "In4.Cu")
	)
	(gr_line
		(start 106.361484 -11.20013)
		(end 106.361484 -9.800082)
		(stroke
			(width 0.2)
			(type default)
		)
		(layer "In4.Cu")
	)
	(gr_arc
		(start 106.361484 -9.800082)
		(mid 105.800144 -9.238742)
		(end 105.238804 -9.800082)
		(stroke
			(width 0.2)
			(type default)
		)
		(layer "In4.Cu")
	)
	(gr_line
		(start 106.361484 -3.999992)
		(end 106.361484 -2.600198)
		(stroke
			(width 0.2)
			(type default)
		)
		(layer "In4.Cu")
	)
	(gr_arc
		(start 106.361484 -2.600198)
		(mid 105.800144 -2.038858)
		(end 105.238804 -2.600198)
		(stroke
			(width 0.2)
			(type default)
		)
		(layer "In4.Cu")
	)
	(gr_line
		(start 106.4768 -79.260192)
		(end 106.4768 -72.117966)
		(stroke
			(width 0.381)
			(type default)
		)
		(layer "In4.Cu")
	)
	(gr_line
		(start 106.4768 -72.117966)
		(end 107.153202 -71.441564)
		(stroke
			(width 0.381)
			(type default)
		)
		(layer "In4.Cu")
	)
	(gr_arc
		(start 106.6419 -55.999888)
		(mid 106.999913 -56.358282)
		(end 107.35818 -56.000142)
		(stroke
			(width 0.2)
			(type default)
		)
		(layer "In4.Cu")
	)
	(gr_line
		(start 106.6419 -55.000144)
		(end 106.6419 -55.999888)
		(stroke
			(width 0.2)
			(type default)
		)
		(layer "In4.Cu")
	)
	(gr_arc
		(start 106.6419 -52.999894)
		(mid 106.999913 -53.358288)
		(end 107.35818 -53.000148)
		(stroke
			(width 0.2)
			(type default)
		)
		(layer "In4.Cu")
	)
	(gr_line
		(start 106.6419 -52.00015)
		(end 106.6419 -52.999894)
		(stroke
			(width 0.2)
			(type default)
		)
		(layer "In4.Cu")
	)
	(gr_arc
		(start 107.038648 -12.399772)
		(mid 107.599861 -12.961366)
		(end 108.161328 -12.400026)
		(stroke
			(width 0.2)
			(type default)
		)
		(layer "In4.Cu")
	)
	(gr_line
		(start 107.038648 -10.999978)
		(end 107.038648 -12.399772)
		(stroke
			(width 0.2)
			(type default)
		)
		(layer "In4.Cu")
	)
	(gr_arc
		(start 107.038648 -5.199888)
		(mid 107.599861 -5.761482)
		(end 108.161328 -5.200142)
		(stroke
			(width 0.2)
			(type default)
		)
		(layer "In4.Cu")
	)
	(gr_line
		(start 107.038648 -3.800094)
		(end 107.038648 -5.199888)
		(stroke
			(width 0.2)
			(type default)
		)
		(layer "In4.Cu")
	)
	(gr_line
		(start 107.153202 -71.441564)
		(end 118.321836 -71.441564)
		(stroke
			(width 0.381)
			(type default)
		)
		(layer "In4.Cu")
	)
	(gr_line
		(start 107.35818 -56.000142)
		(end 107.35818 -55.000144)
		(stroke
			(width 0.2)
			(type default)
		)
		(layer "In4.Cu")
	)
	(gr_arc
		(start 107.35818 -55.000144)
		(mid 107.00004 -54.642004)
		(end 106.6419 -55.000144)
		(stroke
			(width 0.2)
			(type default)
		)
		(layer "In4.Cu")
	)
	(gr_line
		(start 107.35818 -53.000148)
		(end 107.35818 -52.00015)
		(stroke
			(width 0.2)
			(type default)
		)
		(layer "In4.Cu")
	)
	(gr_arc
		(start 107.35818 -52.00015)
		(mid 107.00004 -51.64201)
		(end 106.6419 -52.00015)
		(stroke
			(width 0.2)
			(type default)
		)
		(layer "In4.Cu")
	)
	(gr_arc
		(start 107.641898 -55.999888)
		(mid 107.999911 -56.358282)
		(end 108.358178 -56.000142)
		(stroke
			(width 0.2)
			(type default)
		)
		(layer "In4.Cu")
	)
	(gr_line
		(start 107.641898 -55.000144)
		(end 107.641898 -55.999888)
		(stroke
			(width 0.2)
			(type default)
		)
		(layer "In4.Cu")
	)
	(gr_arc
		(start 107.641898 -51.999896)
		(mid 107.999911 -52.35829)
		(end 108.358178 -52.00015)
		(stroke
			(width 0.2)
			(type default)
		)
		(layer "In4.Cu")
	)
	(gr_line
		(start 107.641898 -51.000152)
		(end 107.641898 -51.999896)
		(stroke
			(width 0.2)
			(type default)
		)
		(layer "In4.Cu")
	)
	(gr_line
		(start 108.161328 -12.400026)
		(end 108.161328 -10.999978)
		(stroke
			(width 0.2)
			(type default)
		)
		(layer "In4.Cu")
	)
	(gr_arc
		(start 108.161328 -10.999978)
		(mid 107.599988 -10.438638)
		(end 107.038648 -10.999978)
		(stroke
			(width 0.2)
			(type default)
		)
		(layer "In4.Cu")
	)
	(gr_line
		(start 108.161328 -5.200142)
		(end 108.161328 -3.800094)
		(stroke
			(width 0.2)
			(type default)
		)
		(layer "In4.Cu")
	)
	(gr_arc
		(start 108.161328 -3.800094)
		(mid 107.599988 -3.238754)
		(end 107.038648 -3.800094)
		(stroke
			(width 0.2)
			(type default)
		)
		(layer "In4.Cu")
	)
	(gr_line
		(start 108.358178 -56.000142)
		(end 108.358178 -55.000144)
		(stroke
			(width 0.2)
			(type default)
		)
		(layer "In4.Cu")
	)
	(gr_arc
		(start 108.358178 -55.000144)
		(mid 108.000038 -54.642004)
		(end 107.641898 -55.000144)
		(stroke
			(width 0.2)
			(type default)
		)
		(layer "In4.Cu")
	)
	(gr_line
		(start 108.358178 -52.00015)
		(end 108.358178 -51.000152)
		(stroke
			(width 0.2)
			(type default)
		)
		(layer "In4.Cu")
	)
	(gr_arc
		(start 108.358178 -51.000152)
		(mid 108.000038 -50.642012)
		(end 107.641898 -51.000152)
		(stroke
			(width 0.2)
			(type default)
		)
		(layer "In4.Cu")
	)
	(gr_arc
		(start 108.641896 -55.999888)
		(mid 108.999909 -56.358282)
		(end 109.358176 -56.000142)
		(stroke
			(width 0.2)
			(type default)
		)
		(layer "In4.Cu")
	)
	(gr_line
		(start 108.641896 -55.000144)
		(end 108.641896 -55.999888)
		(stroke
			(width 0.2)
			(type default)
		)
		(layer "In4.Cu")
	)
	(gr_arc
		(start 108.641896 -52.999894)
		(mid 108.999909 -53.358288)
		(end 109.358176 -53.000148)
		(stroke
			(width 0.2)
			(type default)
		)
		(layer "In4.Cu")
	)
	(gr_line
		(start 108.641896 -52.00015)
		(end 108.641896 -52.999894)
		(stroke
			(width 0.2)
			(type default)
		)
		(layer "In4.Cu")
	)
	(gr_arc
		(start 108.838746 -11.199876)
		(mid 109.399959 -11.76147)
		(end 109.961426 -11.20013)
		(stroke
			(width 0.2)
			(type default)
		)
		(layer "In4.Cu")
	)
	(gr_line
		(start 108.838746 -9.800082)
		(end 108.838746 -11.199876)
		(stroke
			(width 0.2)
			(type default)
		)
		(layer "In4.Cu")
	)
	(gr_arc
		(start 108.838746 -3.999738)
		(mid 109.399959 -4.561332)
		(end 109.961426 -3.999992)
		(stroke
			(width 0.2)
			(type default)
		)
		(layer "In4.Cu")
	)
	(gr_line
		(start 108.838746 -2.600198)
		(end 108.838746 -3.999738)
		(stroke
			(width 0.2)
			(type default)
		)
		(layer "In4.Cu")
	)
	(gr_line
		(start 108.99648 -60.5028)
		(end 122.0978 -60.5028)
		(stroke
			(width 0.381)
			(type default)
		)
		(layer "In4.Cu")
	)
	(gr_line
		(start 109.358176 -56.000142)
		(end 109.358176 -55.000144)
		(stroke
			(width 0.2)
			(type default)
		)
		(layer "In4.Cu")
	)
	(gr_arc
		(start 109.358176 -55.000144)
		(mid 109.000036 -54.642004)
		(end 108.641896 -55.000144)
		(stroke
			(width 0.2)
			(type default)
		)
		(layer "In4.Cu")
	)
	(gr_line
		(start 109.358176 -53.000148)
		(end 109.358176 -52.00015)
		(stroke
			(width 0.2)
			(type default)
		)
		(layer "In4.Cu")
	)
	(gr_arc
		(start 109.358176 -52.00015)
		(mid 109.000036 -51.64201)
		(end 108.641896 -52.00015)
		(stroke
			(width 0.2)
			(type default)
		)
		(layer "In4.Cu")
	)
	(gr_arc
		(start 109.641894 -55.999888)
		(mid 109.999907 -56.358282)
		(end 110.358174 -56.000142)
		(stroke
			(width 0.2)
			(type default)
		)
		(layer "In4.Cu")
	)
	(gr_line
		(start 109.641894 -55.000144)
		(end 109.641894 -55.999888)
		(stroke
			(width 0.2)
			(type default)
		)
		(layer "In4.Cu")
	)
	(gr_arc
		(start 109.641894 -51.999896)
		(mid 109.999907 -52.35829)
		(end 110.358174 -52.00015)
		(stroke
			(width 0.2)
			(type default)
		)
		(layer "In4.Cu")
	)
	(gr_line
		(start 109.641894 -51.000152)
		(end 109.641894 -51.999896)
		(stroke
			(width 0.2)
			(type default)
		)
		(layer "In4.Cu")
	)
	(gr_line
		(start 109.8042 -65.5066)
		(end 98.2218 -65.5066)
		(stroke
			(width 0.381)
			(type default)
		)
		(layer "In4.Cu")
	)
	(gr_line
		(start 109.961426 -11.20013)
		(end 109.961426 -9.800082)
		(stroke
			(width 0.2)
			(type default)
		)
		(layer "In4.Cu")
	)
	(gr_arc
		(start 109.961426 -9.800082)
		(mid 109.400086 -9.238742)
		(end 108.838746 -9.800082)
		(stroke
			(width 0.2)
			(type default)
		)
		(layer "In4.Cu")
	)
	(gr_line
		(start 109.961426 -3.999992)
		(end 109.961426 -2.600198)
		(stroke
			(width 0.2)
			(type default)
		)
		(layer "In4.Cu")
	)
	(gr_arc
		(start 109.961426 -2.600198)
		(mid 109.400086 -2.038858)
		(end 108.838746 -2.600198)
		(stroke
			(width 0.2)
			(type default)
		)
		(layer "In4.Cu")
	)
	(gr_line
		(start 110.358174 -56.000142)
		(end 110.358174 -55.000144)
		(stroke
			(width 0.2)
			(type default)
		)
		(layer "In4.Cu")
	)
	(gr_arc
		(start 110.358174 -55.000144)
		(mid 110.000034 -54.642004)
		(end 109.641894 -55.000144)
		(stroke
			(width 0.2)
			(type default)
		)
		(layer "In4.Cu")
	)
	(gr_line
		(start 110.358174 -52.00015)
		(end 110.358174 -51.000152)
		(stroke
			(width 0.2)
			(type default)
		)
		(layer "In4.Cu")
	)
	(gr_arc
		(start 110.358174 -51.000152)
		(mid 110.000034 -50.642012)
		(end 109.641894 -51.000152)
		(stroke
			(width 0.2)
			(type default)
		)
		(layer "In4.Cu")
	)
	(gr_arc
		(start 110.638844 -12.399772)
		(mid 111.200057 -12.961366)
		(end 111.761524 -12.400026)
		(stroke
			(width 0.2)
			(type default)
		)
		(layer "In4.Cu")
	)
	(gr_line
		(start 110.638844 -10.999978)
		(end 110.638844 -12.399772)
		(stroke
			(width 0.2)
			(type default)
		)
		(layer "In4.Cu")
	)
	(gr_arc
		(start 110.638844 -5.199888)
		(mid 111.200057 -5.761482)
		(end 111.761524 -5.200142)
		(stroke
			(width 0.2)
			(type default)
		)
		(layer "In4.Cu")
	)
	(gr_line
		(start 110.638844 -3.800094)
		(end 110.638844 -5.199888)
		(stroke
			(width 0.2)
			(type default)
		)
		(layer "In4.Cu")
	)
	(gr_arc
		(start 110.641892 -55.999888)
		(mid 110.999905 -56.358282)
		(end 111.358172 -56.000142)
		(stroke
			(width 0.2)
			(type default)
		)
		(layer "In4.Cu")
	)
	(gr_line
		(start 110.641892 -55.000144)
		(end 110.641892 -55.999888)
		(stroke
			(width 0.2)
			(type default)
		)
		(layer "In4.Cu")
	)
	(gr_arc
		(start 110.641892 -52.999894)
		(mid 110.999905 -53.358288)
		(end 111.358172 -53.000148)
		(stroke
			(width 0.2)
			(type default)
		)
		(layer "In4.Cu")
	)
	(gr_line
		(start 110.641892 -52.00015)
		(end 110.641892 -52.999894)
		(stroke
			(width 0.2)
			(type default)
		)
		(layer "In4.Cu")
	)
	(gr_line
		(start 110.9218 -64.389)
		(end 109.8042 -65.5066)
		(stroke
			(width 0.381)
			(type default)
		)
		(layer "In4.Cu")
	)
	(gr_line
		(start 111.358172 -56.000142)
		(end 111.358172 -55.000144)
		(stroke
			(width 0.2)
			(type default)
		)
		(layer "In4.Cu")
	)
	(gr_arc
		(start 111.358172 -55.000144)
		(mid 111.000032 -54.642004)
		(end 110.641892 -55.000144)
		(stroke
			(width 0.2)
			(type default)
		)
		(layer "In4.Cu")
	)
	(gr_line
		(start 111.358172 -53.000148)
		(end 111.358172 -52.00015)
		(stroke
			(width 0.2)
			(type default)
		)
		(layer "In4.Cu")
	)
	(gr_arc
		(start 111.358172 -52.00015)
		(mid 111.000032 -51.64201)
		(end 110.641892 -52.00015)
		(stroke
			(width 0.2)
			(type default)
		)
		(layer "In4.Cu")
	)
	(gr_line
		(start 111.379 -97.917)
		(end 90.932 -97.917)
		(stroke
			(width 0.381)
			(type default)
		)
		(layer "In4.Cu")
	)
	(gr_arc
		(start 111.64189 -55.999888)
		(mid 111.999903 -56.358282)
		(end 112.35817 -56.000142)
		(stroke
			(width 0.2)
			(type default)
		)
		(layer "In4.Cu")
	)
	(gr_line
		(start 111.64189 -55.000144)
		(end 111.64189 -55.999888)
		(stroke
			(width 0.2)
			(type default)
		)
		(layer "In4.Cu")
	)
	(gr_arc
		(start 111.64189 -51.999896)
		(mid 111.999903 -52.35829)
		(end 112.35817 -52.00015)
		(stroke
			(width 0.2)
			(type default)
		)
		(layer "In4.Cu")
	)
	(gr_line
		(start 111.64189 -51.000152)
		(end 111.64189 -51.999896)
		(stroke
			(width 0.2)
			(type default)
		)
		(layer "In4.Cu")
	)
	(gr_line
		(start 111.761524 -12.400026)
		(end 111.761524 -10.999978)
		(stroke
			(width 0.2)
			(type default)
		)
		(layer "In4.Cu")
	)
	(gr_arc
		(start 111.761524 -10.999978)
		(mid 111.200184 -10.438638)
		(end 110.638844 -10.999978)
		(stroke
			(width 0.2)
			(type default)
		)
		(layer "In4.Cu")
	)
	(gr_line
		(start 111.761524 -5.200142)
		(end 111.761524 -3.800094)
		(stroke
			(width 0.2)
			(type default)
		)
		(layer "In4.Cu")
	)
	(gr_arc
		(start 111.761524 -3.800094)
		(mid 111.200184 -3.238754)
		(end 110.638844 -3.800094)
		(stroke
			(width 0.2)
			(type default)
		)
		(layer "In4.Cu")
	)
	(gr_line
		(start 112.35817 -56.000142)
		(end 112.35817 -55.000144)
		(stroke
			(width 0.2)
			(type default)
		)
		(layer "In4.Cu")
	)
	(gr_arc
		(start 112.35817 -55.000144)
		(mid 112.00003 -54.642004)
		(end 111.64189 -55.000144)
		(stroke
			(width 0.2)
			(type default)
		)
		(layer "In4.Cu")
	)
	(gr_line
		(start 112.35817 -52.00015)
		(end 112.35817 -51.000152)
		(stroke
			(width 0.2)
			(type default)
		)
		(layer "In4.Cu")
	)
	(gr_arc
		(start 112.35817 -51.000152)
		(mid 112.00003 -50.642012)
		(end 111.64189 -51.000152)
		(stroke
			(width 0.2)
			(type default)
		)
		(layer "In4.Cu")
	)
	(gr_arc
		(start 112.438688 -11.199876)
		(mid 112.999901 -11.76147)
		(end 113.561368 -11.20013)
		(stroke
			(width 0.2)
			(type default)
		)
		(layer "In4.Cu")
	)
	(gr_line
		(start 112.438688 -9.800082)
		(end 112.438688 -11.199876)
		(stroke
			(width 0.2)
			(type default)
		)
		(layer "In4.Cu")
	)
	(gr_arc
		(start 112.438688 -3.999738)
		(mid 112.999901 -4.561332)
		(end 113.561368 -3.999992)
		(stroke
			(width 0.2)
			(type default)
		)
		(layer "In4.Cu")
	)
	(gr_line
		(start 112.438688 -2.600198)
		(end 112.438688 -3.999738)
		(stroke
			(width 0.2)
			(type default)
		)
		(layer "In4.Cu")
	)
	(gr_line
		(start 112.499902 -126.000002)
		(end 97.499932 -126.000002)
		(stroke
			(width 2.54)
			(type default)
		)
		(layer "In4.Cu")
	)
	(gr_arc
		(start 112.641888 -55.999888)
		(mid 112.999901 -56.358282)
		(end 113.358168 -56.000142)
		(stroke
			(width 0.2)
			(type default)
		)
		(layer "In4.Cu")
	)
	(gr_line
		(start 112.641888 -55.000144)
		(end 112.641888 -55.999888)
		(stroke
			(width 0.2)
			(type default)
		)
		(layer "In4.Cu")
	)
	(gr_arc
		(start 112.641888 -52.999894)
		(mid 112.999901 -53.358288)
		(end 113.358168 -53.000148)
		(stroke
			(width 0.2)
			(type default)
		)
		(layer "In4.Cu")
	)
	(gr_line
		(start 112.641888 -52.00015)
		(end 112.641888 -52.999894)
		(stroke
			(width 0.2)
			(type default)
		)
		(layer "In4.Cu")
	)
	(gr_line
		(start 113.358168 -56.000142)
		(end 113.358168 -55.000144)
		(stroke
			(width 0.2)
			(type default)
		)
		(layer "In4.Cu")
	)
	(gr_arc
		(start 113.358168 -55.000144)
		(mid 113.000028 -54.642004)
		(end 112.641888 -55.000144)
		(stroke
			(width 0.2)
			(type default)
		)
		(layer "In4.Cu")
	)
	(gr_line
		(start 113.358168 -53.000148)
		(end 113.358168 -52.00015)
		(stroke
			(width 0.2)
			(type default)
		)
		(layer "In4.Cu")
	)
	(gr_arc
		(start 113.358168 -52.00015)
		(mid 113.000028 -51.64201)
		(end 112.641888 -52.00015)
		(stroke
			(width 0.2)
			(type default)
		)
		(layer "In4.Cu")
	)
	(gr_line
		(start 113.561368 -11.20013)
		(end 113.561368 -9.800082)
		(stroke
			(width 0.2)
			(type default)
		)
		(layer "In4.Cu")
	)
	(gr_arc
		(start 113.561368 -9.800082)
		(mid 113.000028 -9.238742)
		(end 112.438688 -9.800082)
		(stroke
			(width 0.2)
			(type default)
		)
		(layer "In4.Cu")
	)
	(gr_line
		(start 113.561368 -3.999992)
		(end 113.561368 -2.600198)
		(stroke
			(width 0.2)
			(type default)
		)
		(layer "In4.Cu")
	)
	(gr_arc
		(start 113.561368 -2.600198)
		(mid 113.000028 -2.038858)
		(end 112.438688 -2.600198)
		(stroke
			(width 0.2)
			(type default)
		)
		(layer "In4.Cu")
	)
	(gr_arc
		(start 113.641886 -55.999888)
		(mid 113.999899 -56.358282)
		(end 114.358166 -56.000142)
		(stroke
			(width 0.2)
			(type default)
		)
		(layer "In4.Cu")
	)
	(gr_line
		(start 113.641886 -55.000144)
		(end 113.641886 -55.999888)
		(stroke
			(width 0.2)
			(type default)
		)
		(layer "In4.Cu")
	)
	(gr_arc
		(start 113.641886 -51.999896)
		(mid 113.999899 -52.35829)
		(end 114.358166 -52.00015)
		(stroke
			(width 0.2)
			(type default)
		)
		(layer "In4.Cu")
	)
	(gr_line
		(start 113.641886 -51.000152)
		(end 113.641886 -51.999896)
		(stroke
			(width 0.2)
			(type default)
		)
		(layer "In4.Cu")
	)
	(gr_arc
		(start 114.238786 -12.399772)
		(mid 114.799999 -12.961366)
		(end 115.361466 -12.400026)
		(stroke
			(width 0.2)
			(type default)
		)
		(layer "In4.Cu")
	)
	(gr_line
		(start 114.238786 -10.999978)
		(end 114.238786 -12.399772)
		(stroke
			(width 0.2)
			(type default)
		)
		(layer "In4.Cu")
	)
	(gr_arc
		(start 114.238786 -5.199888)
		(mid 114.799999 -5.761482)
		(end 115.361466 -5.200142)
		(stroke
			(width 0.2)
			(type default)
		)
		(layer "In4.Cu")
	)
	(gr_line
		(start 114.238786 -3.800094)
		(end 114.238786 -5.199888)
		(stroke
			(width 0.2)
			(type default)
		)
		(layer "In4.Cu")
	)
	(gr_line
		(start 114.358166 -56.000142)
		(end 114.358166 -55.000144)
		(stroke
			(width 0.2)
			(type default)
		)
		(layer "In4.Cu")
	)
	(gr_arc
		(start 114.358166 -55.000144)
		(mid 114.000026 -54.642004)
		(end 113.641886 -55.000144)
		(stroke
			(width 0.2)
			(type default)
		)
		(layer "In4.Cu")
	)
	(gr_line
		(start 114.358166 -52.00015)
		(end 114.358166 -51.000152)
		(stroke
			(width 0.2)
			(type default)
		)
		(layer "In4.Cu")
	)
	(gr_arc
		(start 114.358166 -51.000152)
		(mid 114.000026 -50.642012)
		(end 113.641886 -51.000152)
		(stroke
			(width 0.2)
			(type default)
		)
		(layer "In4.Cu")
	)
	(gr_line
		(start 114.5032 -90.1954)
		(end 69.2912 -90.1954)
		(stroke
			(width 0.381)
			(type default)
		)
		(layer "In4.Cu")
	)
	(gr_line
		(start 114.808 -101.346)
		(end 111.379 -97.917)
		(stroke
			(width 0.381)
			(type default)
		)
		(layer "In4.Cu")
	)
	(gr_line
		(start 115.361466 -12.400026)
		(end 115.361466 -10.999978)
		(stroke
			(width 0.2)
			(type default)
		)
		(layer "In4.Cu")
	)
	(gr_arc
		(start 115.361466 -10.999978)
		(mid 114.800126 -10.438638)
		(end 114.238786 -10.999978)
		(stroke
			(width 0.2)
			(type default)
		)
		(layer "In4.Cu")
	)
	(gr_line
		(start 115.361466 -5.200142)
		(end 115.361466 -3.800094)
		(stroke
			(width 0.2)
			(type default)
		)
		(layer "In4.Cu")
	)
	(gr_arc
		(start 115.361466 -3.800094)
		(mid 114.800126 -3.238754)
		(end 114.238786 -3.800094)
		(stroke
			(width 0.2)
			(type default)
		)
		(layer "In4.Cu")
	)
	(gr_arc
		(start 115.641882 -55.999888)
		(mid 115.999895 -56.358282)
		(end 116.358162 -56.000142)
		(stroke
			(width 0.2)
			(type default)
		)
		(layer "In4.Cu")
	)
	(gr_line
		(start 115.641882 -55.000144)
		(end 115.641882 -55.999888)
		(stroke
			(width 0.2)
			(type default)
		)
		(layer "In4.Cu")
	)
	(gr_arc
		(start 115.641882 -52.999894)
		(mid 115.999895 -53.358288)
		(end 116.358162 -53.000148)
		(stroke
			(width 0.2)
			(type default)
		)
		(layer "In4.Cu")
	)
	(gr_line
		(start 115.641882 -52.00015)
		(end 115.641882 -52.999894)
		(stroke
			(width 0.2)
			(type default)
		)
		(layer "In4.Cu")
	)
	(gr_arc
		(start 116.03863 -11.199876)
		(mid 116.599843 -11.76147)
		(end 117.16131 -11.20013)
		(stroke
			(width 0.2)
			(type default)
		)
		(layer "In4.Cu")
	)
	(gr_line
		(start 116.03863 -9.800082)
		(end 116.03863 -11.199876)
		(stroke
			(width 0.2)
			(type default)
		)
		(layer "In4.Cu")
	)
	(gr_arc
		(start 116.03863 -3.999738)
		(mid 116.599843 -4.561332)
		(end 117.16131 -3.999992)
		(stroke
			(width 0.2)
			(type default)
		)
		(layer "In4.Cu")
	)
	(gr_line
		(start 116.03863 -2.600198)
		(end 116.03863 -3.999738)
		(stroke
			(width 0.2)
			(type default)
		)
		(layer "In4.Cu")
	)
	(gr_line
		(start 116.358162 -56.000142)
		(end 116.358162 -55.000144)
		(stroke
			(width 0.2)
			(type default)
		)
		(layer "In4.Cu")
	)
	(gr_arc
		(start 116.358162 -55.000144)
		(mid 116.000022 -54.642004)
		(end 115.641882 -55.000144)
		(stroke
			(width 0.2)
			(type default)
		)
		(layer "In4.Cu")
	)
	(gr_line
		(start 116.358162 -53.000148)
		(end 116.358162 -52.00015)
		(stroke
			(width 0.2)
			(type default)
		)
		(layer "In4.Cu")
	)
	(gr_arc
		(start 116.358162 -52.00015)
		(mid 116.000022 -51.64201)
		(end 115.641882 -52.00015)
		(stroke
			(width 0.2)
			(type default)
		)
		(layer "In4.Cu")
	)
	(gr_arc
		(start 116.64188 -55.999888)
		(mid 116.999893 -56.358282)
		(end 117.35816 -56.000142)
		(stroke
			(width 0.2)
			(type default)
		)
		(layer "In4.Cu")
	)
	(gr_line
		(start 116.64188 -55.000144)
		(end 116.64188 -55.999888)
		(stroke
			(width 0.2)
			(type default)
		)
		(layer "In4.Cu")
	)
	(gr_arc
		(start 116.64188 -51.999896)
		(mid 116.999893 -52.35829)
		(end 117.35816 -52.00015)
		(stroke
			(width 0.2)
			(type default)
		)
		(layer "In4.Cu")
	)
	(gr_line
		(start 116.64188 -51.000152)
		(end 116.64188 -51.999896)
		(stroke
			(width 0.2)
			(type default)
		)
		(layer "In4.Cu")
	)
	(gr_line
		(start 117.16131 -11.20013)
		(end 117.16131 -9.800082)
		(stroke
			(width 0.2)
			(type default)
		)
		(layer "In4.Cu")
	)
	(gr_arc
		(start 117.16131 -9.800082)
		(mid 116.59997 -9.238742)
		(end 116.03863 -9.800082)
		(stroke
			(width 0.2)
			(type default)
		)
		(layer "In4.Cu")
	)
	(gr_line
		(start 117.16131 -3.999992)
		(end 117.16131 -2.600198)
		(stroke
			(width 0.2)
			(type default)
		)
		(layer "In4.Cu")
	)
	(gr_arc
		(start 117.16131 -2.600198)
		(mid 116.59997 -2.038858)
		(end 116.03863 -2.600198)
		(stroke
			(width 0.2)
			(type default)
		)
		(layer "In4.Cu")
	)
	(gr_line
		(start 117.35816 -56.000142)
		(end 117.35816 -55.000144)
		(stroke
			(width 0.2)
			(type default)
		)
		(layer "In4.Cu")
	)
	(gr_arc
		(start 117.35816 -55.000144)
		(mid 117.00002 -54.642004)
		(end 116.64188 -55.000144)
		(stroke
			(width 0.2)
			(type default)
		)
		(layer "In4.Cu")
	)
	(gr_line
		(start 117.35816 -52.00015)
		(end 117.35816 -51.000152)
		(stroke
			(width 0.2)
			(type default)
		)
		(layer "In4.Cu")
	)
	(gr_arc
		(start 117.35816 -51.000152)
		(mid 117.00002 -50.642012)
		(end 116.64188 -51.000152)
		(stroke
			(width 0.2)
			(type default)
		)
		(layer "In4.Cu")
	)
	(gr_arc
		(start 117.641878 -55.999888)
		(mid 117.999891 -56.358282)
		(end 118.358158 -56.000142)
		(stroke
			(width 0.2)
			(type default)
		)
		(layer "In4.Cu")
	)
	(gr_line
		(start 117.641878 -55.000144)
		(end 117.641878 -55.999888)
		(stroke
			(width 0.2)
			(type default)
		)
		(layer "In4.Cu")
	)
	(gr_arc
		(start 117.641878 -52.999894)
		(mid 117.999891 -53.358288)
		(end 118.358158 -53.000148)
		(stroke
			(width 0.2)
			(type default)
		)
		(layer "In4.Cu")
	)
	(gr_line
		(start 117.641878 -52.00015)
		(end 117.641878 -52.999894)
		(stroke
			(width 0.2)
			(type default)
		)
		(layer "In4.Cu")
	)
	(gr_arc
		(start 117.838728 -12.399772)
		(mid 118.399941 -12.961366)
		(end 118.961408 -12.400026)
		(stroke
			(width 0.2)
			(type default)
		)
		(layer "In4.Cu")
	)
	(gr_line
		(start 117.838728 -10.999978)
		(end 117.838728 -12.399772)
		(stroke
			(width 0.2)
			(type default)
		)
		(layer "In4.Cu")
	)
	(gr_arc
		(start 117.838728 -5.199888)
		(mid 118.399941 -5.761482)
		(end 118.961408 -5.200142)
		(stroke
			(width 0.2)
			(type default)
		)
		(layer "In4.Cu")
	)
	(gr_line
		(start 117.838728 -3.800094)
		(end 117.838728 -5.199888)
		(stroke
			(width 0.2)
			(type default)
		)
		(layer "In4.Cu")
	)
	(gr_line
		(start 118.0592 -64.389)
		(end 110.9218 -64.389)
		(stroke
			(width 0.381)
			(type default)
		)
		(layer "In4.Cu")
	)
	(gr_line
		(start 118.321836 -71.441564)
		(end 118.6434 -71.12)
		(stroke
			(width 0.381)
			(type default)
		)
		(layer "In4.Cu")
	)
	(gr_line
		(start 118.358158 -56.000142)
		(end 118.358158 -55.000144)
		(stroke
			(width 0.2)
			(type default)
		)
		(layer "In4.Cu")
	)
	(gr_arc
		(start 118.358158 -55.000144)
		(mid 118.000018 -54.642004)
		(end 117.641878 -55.000144)
		(stroke
			(width 0.2)
			(type default)
		)
		(layer "In4.Cu")
	)
	(gr_line
		(start 118.358158 -53.000148)
		(end 118.358158 -52.00015)
		(stroke
			(width 0.2)
			(type default)
		)
		(layer "In4.Cu")
	)
	(gr_arc
		(start 118.358158 -52.00015)
		(mid 118.000018 -51.64201)
		(end 117.641878 -52.00015)
		(stroke
			(width 0.2)
			(type default)
		)
		(layer "In4.Cu")
	)
	(gr_arc
		(start 118.641876 -55.999888)
		(mid 118.999889 -56.358282)
		(end 119.358156 -56.000142)
		(stroke
			(width 0.2)
			(type default)
		)
		(layer "In4.Cu")
	)
	(gr_line
		(start 118.641876 -55.000144)
		(end 118.641876 -55.999888)
		(stroke
			(width 0.2)
			(type default)
		)
		(layer "In4.Cu")
	)
	(gr_arc
		(start 118.641876 -51.999896)
		(mid 118.999889 -52.35829)
		(end 119.358156 -52.00015)
		(stroke
			(width 0.2)
			(type default)
		)
		(layer "In4.Cu")
	)
	(gr_line
		(start 118.641876 -51.000152)
		(end 118.641876 -51.999896)
		(stroke
			(width 0.2)
			(type default)
		)
		(layer "In4.Cu")
	)
	(gr_line
		(start 118.6434 -71.12)
		(end 118.6434 -64.9732)
		(stroke
			(width 0.381)
			(type default)
		)
		(layer "In4.Cu")
	)
	(gr_line
		(start 118.6434 -64.9732)
		(end 118.0592 -64.389)
		(stroke
			(width 0.381)
			(type default)
		)
		(layer "In4.Cu")
	)
	(gr_line
		(start 118.961408 -12.400026)
		(end 118.961408 -10.999978)
		(stroke
			(width 0.2)
			(type default)
		)
		(layer "In4.Cu")
	)
	(gr_arc
		(start 118.961408 -10.999978)
		(mid 118.400068 -10.438638)
		(end 117.838728 -10.999978)
		(stroke
			(width 0.2)
			(type default)
		)
		(layer "In4.Cu")
	)
	(gr_line
		(start 118.961408 -5.200142)
		(end 118.961408 -3.800094)
		(stroke
			(width 0.2)
			(type default)
		)
		(layer "In4.Cu")
	)
	(gr_arc
		(start 118.961408 -3.800094)
		(mid 118.400068 -3.238754)
		(end 117.838728 -3.800094)
		(stroke
			(width 0.2)
			(type default)
		)
		(layer "In4.Cu")
	)
	(gr_line
		(start 119.358156 -56.000142)
		(end 119.358156 -55.000144)
		(stroke
			(width 0.2)
			(type default)
		)
		(layer "In4.Cu")
	)
	(gr_arc
		(start 119.358156 -55.000144)
		(mid 119.000016 -54.642004)
		(end 118.641876 -55.000144)
		(stroke
			(width 0.2)
			(type default)
		)
		(layer "In4.Cu")
	)
	(gr_line
		(start 119.358156 -52.00015)
		(end 119.358156 -51.000152)
		(stroke
			(width 0.2)
			(type default)
		)
		(layer "In4.Cu")
	)
	(gr_arc
		(start 119.358156 -51.000152)
		(mid 119.000016 -50.642012)
		(end 118.641876 -51.000152)
		(stroke
			(width 0.2)
			(type default)
		)
		(layer "In4.Cu")
	)
	(gr_arc
		(start 119.638826 -11.199876)
		(mid 120.200039 -11.76147)
		(end 120.761506 -11.20013)
		(stroke
			(width 0.2)
			(type default)
		)
		(layer "In4.Cu")
	)
	(gr_line
		(start 119.638826 -9.800082)
		(end 119.638826 -11.199876)
		(stroke
			(width 0.2)
			(type default)
		)
		(layer "In4.Cu")
	)
	(gr_arc
		(start 119.638826 -3.999738)
		(mid 120.200039 -4.561332)
		(end 120.761506 -3.999992)
		(stroke
			(width 0.2)
			(type default)
		)
		(layer "In4.Cu")
	)
	(gr_line
		(start 119.638826 -2.600198)
		(end 119.638826 -3.999738)
		(stroke
			(width 0.2)
			(type default)
		)
		(layer "In4.Cu")
	)
	(gr_arc
		(start 119.641874 -55.999888)
		(mid 119.999887 -56.358282)
		(end 120.358154 -56.000142)
		(stroke
			(width 0.2)
			(type default)
		)
		(layer "In4.Cu")
	)
	(gr_line
		(start 119.641874 -55.000144)
		(end 119.641874 -55.999888)
		(stroke
			(width 0.2)
			(type default)
		)
		(layer "In4.Cu")
	)
	(gr_arc
		(start 119.641874 -52.999894)
		(mid 119.999887 -53.358288)
		(end 120.358154 -53.000148)
		(stroke
			(width 0.2)
			(type default)
		)
		(layer "In4.Cu")
	)
	(gr_line
		(start 119.641874 -52.00015)
		(end 119.641874 -52.999894)
		(stroke
			(width 0.2)
			(type default)
		)
		(layer "In4.Cu")
	)
	(gr_line
		(start 119.941594 -95.633794)
		(end 114.5032 -90.1954)
		(stroke
			(width 0.381)
			(type default)
		)
		(layer "In4.Cu")
	)
	(gr_line
		(start 120.358154 -56.000142)
		(end 120.358154 -55.000144)
		(stroke
			(width 0.2)
			(type default)
		)
		(layer "In4.Cu")
	)
	(gr_arc
		(start 120.358154 -55.000144)
		(mid 120.000014 -54.642004)
		(end 119.641874 -55.000144)
		(stroke
			(width 0.2)
			(type default)
		)
		(layer "In4.Cu")
	)
	(gr_line
		(start 120.358154 -53.000148)
		(end 120.358154 -52.00015)
		(stroke
			(width 0.2)
			(type default)
		)
		(layer "In4.Cu")
	)
	(gr_arc
		(start 120.358154 -52.00015)
		(mid 120.000014 -51.64201)
		(end 119.641874 -52.00015)
		(stroke
			(width 0.2)
			(type default)
		)
		(layer "In4.Cu")
	)
	(gr_arc
		(start 120.641872 -55.999888)
		(mid 120.999885 -56.358282)
		(end 121.358152 -56.000142)
		(stroke
			(width 0.2)
			(type default)
		)
		(layer "In4.Cu")
	)
	(gr_line
		(start 120.641872 -55.000144)
		(end 120.641872 -55.999888)
		(stroke
			(width 0.2)
			(type default)
		)
		(layer "In4.Cu")
	)
	(gr_arc
		(start 120.641872 -51.999896)
		(mid 120.999885 -52.35829)
		(end 121.358152 -52.00015)
		(stroke
			(width 0.2)
			(type default)
		)
		(layer "In4.Cu")
	)
	(gr_line
		(start 120.641872 -51.000152)
		(end 120.641872 -51.999896)
		(stroke
			(width 0.2)
			(type default)
		)
		(layer "In4.Cu")
	)
	(gr_line
		(start 120.761506 -11.20013)
		(end 120.761506 -9.800082)
		(stroke
			(width 0.2)
			(type default)
		)
		(layer "In4.Cu")
	)
	(gr_arc
		(start 120.761506 -9.800082)
		(mid 120.200166 -9.238742)
		(end 119.638826 -9.800082)
		(stroke
			(width 0.2)
			(type default)
		)
		(layer "In4.Cu")
	)
	(gr_line
		(start 120.761506 -3.999992)
		(end 120.761506 -2.600198)
		(stroke
			(width 0.2)
			(type default)
		)
		(layer "In4.Cu")
	)
	(gr_arc
		(start 120.761506 -2.600198)
		(mid 120.200166 -2.038858)
		(end 119.638826 -2.600198)
		(stroke
			(width 0.2)
			(type default)
		)
		(layer "In4.Cu")
	)
	(gr_line
		(start 120.79224 -127.32639)
		(end 112.499902 -126.000002)
		(stroke
			(width 2.54)
			(type default)
		)
		(layer "In4.Cu")
	)
	(gr_line
		(start 121.358152 -56.000142)
		(end 121.358152 -55.000144)
		(stroke
			(width 0.2)
			(type default)
		)
		(layer "In4.Cu")
	)
	(gr_arc
		(start 121.358152 -55.000144)
		(mid 121.000012 -54.642004)
		(end 120.641872 -55.000144)
		(stroke
			(width 0.2)
			(type default)
		)
		(layer "In4.Cu")
	)
	(gr_line
		(start 121.358152 -52.00015)
		(end 121.358152 -51.000152)
		(stroke
			(width 0.2)
			(type default)
		)
		(layer "In4.Cu")
	)
	(gr_arc
		(start 121.358152 -51.000152)
		(mid 121.000012 -50.642012)
		(end 120.641872 -51.000152)
		(stroke
			(width 0.2)
			(type default)
		)
		(layer "In4.Cu")
	)
	(gr_arc
		(start 121.43867 -12.399772)
		(mid 121.999883 -12.961366)
		(end 122.56135 -12.400026)
		(stroke
			(width 0.2)
			(type default)
		)
		(layer "In4.Cu")
	)
	(gr_line
		(start 121.43867 -10.999978)
		(end 121.43867 -12.399772)
		(stroke
			(width 0.2)
			(type default)
		)
		(layer "In4.Cu")
	)
	(gr_arc
		(start 121.43867 -5.199888)
		(mid 121.999883 -5.761482)
		(end 122.56135 -5.200142)
		(stroke
			(width 0.2)
			(type default)
		)
		(layer "In4.Cu")
	)
	(gr_line
		(start 121.43867 -3.800094)
		(end 121.43867 -5.199888)
		(stroke
			(width 0.2)
			(type default)
		)
		(layer "In4.Cu")
	)
	(gr_arc
		(start 121.64187 -55.999888)
		(mid 121.999883 -56.358282)
		(end 122.35815 -56.000142)
		(stroke
			(width 0.2)
			(type default)
		)
		(layer "In4.Cu")
	)
	(gr_line
		(start 121.64187 -55.000144)
		(end 121.64187 -55.999888)
		(stroke
			(width 0.2)
			(type default)
		)
		(layer "In4.Cu")
	)
	(gr_arc
		(start 121.64187 -52.999894)
		(mid 121.999883 -53.358288)
		(end 122.35815 -53.000148)
		(stroke
			(width 0.2)
			(type default)
		)
		(layer "In4.Cu")
	)
	(gr_line
		(start 121.64187 -52.00015)
		(end 121.64187 -52.999894)
		(stroke
			(width 0.2)
			(type default)
		)
		(layer "In4.Cu")
	)
	(gr_line
		(start 122.0978 -60.5028)
		(end 122.496834 -60.901834)
		(stroke
			(width 0.381)
			(type default)
		)
		(layer "In4.Cu")
	)
	(gr_line
		(start 122.35815 -56.000142)
		(end 122.35815 -55.000144)
		(stroke
			(width 0.2)
			(type default)
		)
		(layer "In4.Cu")
	)
	(gr_arc
		(start 122.35815 -55.000144)
		(mid 122.00001 -54.642004)
		(end 121.64187 -55.000144)
		(stroke
			(width 0.2)
			(type default)
		)
		(layer "In4.Cu")
	)
	(gr_line
		(start 122.35815 -53.000148)
		(end 122.35815 -52.00015)
		(stroke
			(width 0.2)
			(type default)
		)
		(layer "In4.Cu")
	)
	(gr_arc
		(start 122.35815 -52.00015)
		(mid 122.00001 -51.64201)
		(end 121.64187 -52.00015)
		(stroke
			(width 0.2)
			(type default)
		)
		(layer "In4.Cu")
	)
	(gr_line
		(start 122.5042 -70.97776)
		(end 124.491242 -72.964802)
		(stroke
			(width 0.381)
			(type default)
		)
		(layer "In4.Cu")
	)
	(gr_arc
		(start 122.5042 -60.919614)
		(mid 122.502233 -60.910014)
		(end 122.496834 -60.901834)
		(stroke
			(width 0.381)
			(type default)
		)
		(layer "In4.Cu")
	)
	(gr_line
		(start 122.5042 -60.919614)
		(end 122.5042 -70.97776)
		(stroke
			(width 0.381)
			(type default)
		)
		(layer "In4.Cu")
	)
	(gr_line
		(start 122.56135 -12.400026)
		(end 122.56135 -10.999978)
		(stroke
			(width 0.2)
			(type default)
		)
		(layer "In4.Cu")
	)
	(gr_arc
		(start 122.56135 -10.999978)
		(mid 122.00001 -10.438638)
		(end 121.43867 -10.999978)
		(stroke
			(width 0.2)
			(type default)
		)
		(layer "In4.Cu")
	)
	(gr_line
		(start 122.56135 -5.200142)
		(end 122.56135 -3.800094)
		(stroke
			(width 0.2)
			(type default)
		)
		(layer "In4.Cu")
	)
	(gr_arc
		(start 122.56135 -3.800094)
		(mid 122.00001 -3.238754)
		(end 121.43867 -3.800094)
		(stroke
			(width 0.2)
			(type default)
		)
		(layer "In4.Cu")
	)
	(gr_arc
		(start 122.641868 -55.999888)
		(mid 122.999881 -56.358282)
		(end 123.358148 -56.000142)
		(stroke
			(width 0.2)
			(type default)
		)
		(layer "In4.Cu")
	)
	(gr_line
		(start 122.641868 -55.000144)
		(end 122.641868 -55.999888)
		(stroke
			(width 0.2)
			(type default)
		)
		(layer "In4.Cu")
	)
	(gr_arc
		(start 122.641868 -51.999896)
		(mid 122.999881 -52.35829)
		(end 123.358148 -52.00015)
		(stroke
			(width 0.2)
			(type default)
		)
		(layer "In4.Cu")
	)
	(gr_line
		(start 122.641868 -51.000152)
		(end 122.641868 -51.999896)
		(stroke
			(width 0.2)
			(type default)
		)
		(layer "In4.Cu")
	)
	(gr_arc
		(start 123.238768 -11.199876)
		(mid 123.799981 -11.76147)
		(end 124.361448 -11.20013)
		(stroke
			(width 0.2)
			(type default)
		)
		(layer "In4.Cu")
	)
	(gr_line
		(start 123.238768 -9.800082)
		(end 123.238768 -11.199876)
		(stroke
			(width 0.2)
			(type default)
		)
		(layer "In4.Cu")
	)
	(gr_arc
		(start 123.238768 -3.999738)
		(mid 123.799981 -4.561332)
		(end 124.361448 -3.999992)
		(stroke
			(width 0.2)
			(type default)
		)
		(layer "In4.Cu")
	)
	(gr_line
		(start 123.238768 -2.600198)
		(end 123.238768 -3.999738)
		(stroke
			(width 0.2)
			(type default)
		)
		(layer "In4.Cu")
	)
	(gr_line
		(start 123.358148 -56.000142)
		(end 123.358148 -55.000144)
		(stroke
			(width 0.2)
			(type default)
		)
		(layer "In4.Cu")
	)
	(gr_arc
		(start 123.358148 -55.000144)
		(mid 123.000008 -54.642004)
		(end 122.641868 -55.000144)
		(stroke
			(width 0.2)
			(type default)
		)
		(layer "In4.Cu")
	)
	(gr_line
		(start 123.358148 -52.00015)
		(end 123.358148 -51.000152)
		(stroke
			(width 0.2)
			(type default)
		)
		(layer "In4.Cu")
	)
	(gr_arc
		(start 123.358148 -51.000152)
		(mid 123.000008 -50.642012)
		(end 122.641868 -51.000152)
		(stroke
			(width 0.2)
			(type default)
		)
		(layer "In4.Cu")
	)
	(gr_arc
		(start 123.641866 -55.999888)
		(mid 123.999879 -56.358282)
		(end 124.358146 -56.000142)
		(stroke
			(width 0.2)
			(type default)
		)
		(layer "In4.Cu")
	)
	(gr_line
		(start 123.641866 -55.000144)
		(end 123.641866 -55.999888)
		(stroke
			(width 0.2)
			(type default)
		)
		(layer "In4.Cu")
	)
	(gr_arc
		(start 123.641866 -52.999894)
		(mid 123.999879 -53.358288)
		(end 124.358146 -53.000148)
		(stroke
			(width 0.2)
			(type default)
		)
		(layer "In4.Cu")
	)
	(gr_line
		(start 123.641866 -52.00015)
		(end 123.641866 -52.999894)
		(stroke
			(width 0.2)
			(type default)
		)
		(layer "In4.Cu")
	)
	(gr_arc
		(start 124.225558 -47.001684)
		(mid 124.682631 -47.459138)
		(end 125.139958 -47.001938)
		(stroke
			(width 0.2)
			(type default)
		)
		(layer "In4.Cu")
	)
	(gr_line
		(start 124.225558 -45.858938)
		(end 124.225558 -47.001684)
		(stroke
			(width 0.2)
			(type default)
		)
		(layer "In4.Cu")
	)
	(gr_line
		(start 124.358146 -56.000142)
		(end 124.358146 -55.000144)
		(stroke
			(width 0.2)
			(type default)
		)
		(layer "In4.Cu")
	)
	(gr_arc
		(start 124.358146 -55.000144)
		(mid 124.000006 -54.642004)
		(end 123.641866 -55.000144)
		(stroke
			(width 0.2)
			(type default)
		)
		(layer "In4.Cu")
	)
	(gr_line
		(start 124.358146 -53.000148)
		(end 124.358146 -52.00015)
		(stroke
			(width 0.2)
			(type default)
		)
		(layer "In4.Cu")
	)
	(gr_arc
		(start 124.358146 -52.00015)
		(mid 124.000006 -51.64201)
		(end 123.641866 -52.00015)
		(stroke
			(width 0.2)
			(type default)
		)
		(layer "In4.Cu")
	)
	(gr_line
		(start 124.361448 -11.20013)
		(end 124.361448 -9.800082)
		(stroke
			(width 0.2)
			(type default)
		)
		(layer "In4.Cu")
	)
	(gr_arc
		(start 124.361448 -9.800082)
		(mid 123.800108 -9.238742)
		(end 123.238768 -9.800082)
		(stroke
			(width 0.2)
			(type default)
		)
		(layer "In4.Cu")
	)
	(gr_line
		(start 124.361448 -3.999992)
		(end 124.361448 -2.600198)
		(stroke
			(width 0.2)
			(type default)
		)
		(layer "In4.Cu")
	)
	(gr_arc
		(start 124.361448 -2.600198)
		(mid 123.800108 -2.038858)
		(end 123.238768 -2.600198)
		(stroke
			(width 0.2)
			(type default)
		)
		(layer "In4.Cu")
	)
	(gr_line
		(start 124.491242 -77.078586)
		(end 124.882656 -77.47)
		(stroke
			(width 0.381)
			(type default)
		)
		(layer "In4.Cu")
	)
	(gr_line
		(start 124.491242 -72.964802)
		(end 124.491242 -77.078586)
		(stroke
			(width 0.381)
			(type default)
		)
		(layer "In4.Cu")
	)
	(gr_line
		(start 124.882656 -77.47)
		(end 140.97 -77.47)
		(stroke
			(width 0.381)
			(type default)
		)
		(layer "In4.Cu")
	)
	(gr_line
		(start 125.002544 -142.999968)
		(end 125.002544 -132.263642)
		(stroke
			(width 2.54)
			(type default)
		)
		(layer "In4.Cu")
	)
	(gr_arc
		(start 125.002544 -142.999968)
		(mid 125.58832 -144.414185)
		(end 127.00254 -144.999964)
		(stroke
			(width 2.54)
			(type default)
		)
		(layer "In4.Cu")
	)
	(gr_arc
		(start 125.002544 -132.263642)
		(mid 123.807045 -129.019301)
		(end 120.79224 -127.32639)
		(stroke
			(width 2.54)
			(type default)
		)
		(layer "In4.Cu")
	)
	(gr_arc
		(start 125.038866 -12.399772)
		(mid 125.600079 -12.961366)
		(end 126.161546 -12.400026)
		(stroke
			(width 0.2)
			(type default)
		)
		(layer "In4.Cu")
	)
	(gr_line
		(start 125.038866 -10.999978)
		(end 125.038866 -12.399772)
		(stroke
			(width 0.2)
			(type default)
		)
		(layer "In4.Cu")
	)
	(gr_arc
		(start 125.038866 -5.199888)
		(mid 125.600079 -5.761482)
		(end 126.161546 -5.200142)
		(stroke
			(width 0.2)
			(type default)
		)
		(layer "In4.Cu")
	)
	(gr_line
		(start 125.038866 -3.800094)
		(end 125.038866 -5.199888)
		(stroke
			(width 0.2)
			(type default)
		)
		(layer "In4.Cu")
	)
	(gr_line
		(start 125.139958 -47.001938)
		(end 125.139958 -45.858938)
		(stroke
			(width 0.2)
			(type default)
		)
		(layer "In4.Cu")
	)
	(gr_arc
		(start 125.139958 -45.858938)
		(mid 124.682758 -45.401738)
		(end 124.225558 -45.858938)
		(stroke
			(width 0.2)
			(type default)
		)
		(layer "In4.Cu")
	)
	(gr_line
		(start 126.000002 -77.35824)
		(end 127 -77.35824)
		(stroke
			(width 0.2)
			(type default)
		)
		(layer "In4.Cu")
	)
	(gr_line
		(start 126.000002 -76.358242)
		(end 127 -76.358242)
		(stroke
			(width 0.2)
			(type default)
		)
		(layer "In4.Cu")
	)
	(gr_line
		(start 126.000002 -75.358244)
		(end 127 -75.358244)
		(stroke
			(width 0.2)
			(type default)
		)
		(layer "In4.Cu")
	)
	(gr_line
		(start 126.000002 -74.358246)
		(end 127 -74.358246)
		(stroke
			(width 0.2)
			(type default)
		)
		(layer "In4.Cu")
	)
	(gr_line
		(start 126.000002 -73.358248)
		(end 127 -73.358248)
		(stroke
			(width 0.2)
			(type default)
		)
		(layer "In4.Cu")
	)
	(gr_line
		(start 126.000002 -72.35825)
		(end 127 -72.35825)
		(stroke
			(width 0.2)
			(type default)
		)
		(layer "In4.Cu")
	)
	(gr_line
		(start 126.000002 -71.358252)
		(end 127 -71.358252)
		(stroke
			(width 0.2)
			(type default)
		)
		(layer "In4.Cu")
	)
	(gr_line
		(start 126.000002 -70.358254)
		(end 127 -70.358254)
		(stroke
			(width 0.2)
			(type default)
		)
		(layer "In4.Cu")
	)
	(gr_line
		(start 126.000002 -69.358256)
		(end 127 -69.358256)
		(stroke
			(width 0.2)
			(type default)
		)
		(layer "In4.Cu")
	)
	(gr_line
		(start 126.000002 -68.358258)
		(end 127 -68.358258)
		(stroke
			(width 0.2)
			(type default)
		)
		(layer "In4.Cu")
	)
	(gr_line
		(start 126.000002 -66.358262)
		(end 127 -66.358262)
		(stroke
			(width 0.2)
			(type default)
		)
		(layer "In4.Cu")
	)
	(gr_line
		(start 126.000002 -65.358264)
		(end 127 -65.358264)
		(stroke
			(width 0.2)
			(type default)
		)
		(layer "In4.Cu")
	)
	(gr_line
		(start 126.000002 -64.358266)
		(end 127 -64.358266)
		(stroke
			(width 0.2)
			(type default)
		)
		(layer "In4.Cu")
	)
	(gr_line
		(start 126.000002 -63.358268)
		(end 127 -63.358268)
		(stroke
			(width 0.2)
			(type default)
		)
		(layer "In4.Cu")
	)
	(gr_line
		(start 126.000002 -62.35827)
		(end 127 -62.35827)
		(stroke
			(width 0.2)
			(type default)
		)
		(layer "In4.Cu")
	)
	(gr_line
		(start 126.000002 -61.358272)
		(end 127 -61.358272)
		(stroke
			(width 0.2)
			(type default)
		)
		(layer "In4.Cu")
	)
	(gr_line
		(start 126.000002 -60.358274)
		(end 127 -60.358274)
		(stroke
			(width 0.2)
			(type default)
		)
		(layer "In4.Cu")
	)
	(gr_line
		(start 126.000002 -59.358276)
		(end 127 -59.358276)
		(stroke
			(width 0.2)
			(type default)
		)
		(layer "In4.Cu")
	)
	(gr_line
		(start 126.000002 -58.358278)
		(end 127 -58.358278)
		(stroke
			(width 0.2)
			(type default)
		)
		(layer "In4.Cu")
	)
	(gr_line
		(start 126.000002 -57.35828)
		(end 127 -57.35828)
		(stroke
			(width 0.2)
			(type default)
		)
		(layer "In4.Cu")
	)
	(gr_line
		(start 126.000002 -56.358282)
		(end 127 -56.358282)
		(stroke
			(width 0.2)
			(type default)
		)
		(layer "In4.Cu")
	)
	(gr_line
		(start 126.000002 -55.358284)
		(end 127 -55.358284)
		(stroke
			(width 0.2)
			(type default)
		)
		(layer "In4.Cu")
	)
	(gr_line
		(start 126.000002 -54.358286)
		(end 127 -54.358286)
		(stroke
			(width 0.2)
			(type default)
		)
		(layer "In4.Cu")
	)
	(gr_arc
		(start 126.000256 -76.64196)
		(mid 125.641862 -76.999973)
		(end 126.000002 -77.35824)
		(stroke
			(width 0.2)
			(type default)
		)
		(layer "In4.Cu")
	)
	(gr_arc
		(start 126.000256 -75.641962)
		(mid 125.641862 -75.999975)
		(end 126.000002 -76.358242)
		(stroke
			(width 0.2)
			(type default)
		)
		(layer "In4.Cu")
	)
	(gr_arc
		(start 126.000256 -74.641964)
		(mid 125.641862 -74.999977)
		(end 126.000002 -75.358244)
		(stroke
			(width 0.2)
			(type default)
		)
		(layer "In4.Cu")
	)
	(gr_arc
		(start 126.000256 -73.641966)
		(mid 125.641862 -73.999979)
		(end 126.000002 -74.358246)
		(stroke
			(width 0.2)
			(type default)
		)
		(layer "In4.Cu")
	)
	(gr_arc
		(start 126.000256 -72.641968)
		(mid 125.641862 -72.999981)
		(end 126.000002 -73.358248)
		(stroke
			(width 0.2)
			(type default)
		)
		(layer "In4.Cu")
	)
	(gr_arc
		(start 126.000256 -71.64197)
		(mid 125.641862 -71.999983)
		(end 126.000002 -72.35825)
		(stroke
			(width 0.2)
			(type default)
		)
		(layer "In4.Cu")
	)
	(gr_arc
		(start 126.000256 -70.641972)
		(mid 125.641862 -70.999985)
		(end 126.000002 -71.358252)
		(stroke
			(width 0.2)
			(type default)
		)
		(layer "In4.Cu")
	)
	(gr_arc
		(start 126.000256 -69.641974)
		(mid 125.641862 -69.999987)
		(end 126.000002 -70.358254)
		(stroke
			(width 0.2)
			(type default)
		)
		(layer "In4.Cu")
	)
	(gr_arc
		(start 126.000256 -68.641976)
		(mid 125.641862 -68.999989)
		(end 126.000002 -69.358256)
		(stroke
			(width 0.2)
			(type default)
		)
		(layer "In4.Cu")
	)
	(gr_arc
		(start 126.000256 -67.641978)
		(mid 125.641862 -67.999991)
		(end 126.000002 -68.358258)
		(stroke
			(width 0.2)
			(type default)
		)
		(layer "In4.Cu")
	)
	(gr_arc
		(start 126.000256 -65.641982)
		(mid 125.641862 -65.999995)
		(end 126.000002 -66.358262)
		(stroke
			(width 0.2)
			(type default)
		)
		(layer "In4.Cu")
	)
	(gr_arc
		(start 126.000256 -64.641984)
		(mid 125.641862 -64.999997)
		(end 126.000002 -65.358264)
		(stroke
			(width 0.2)
			(type default)
		)
		(layer "In4.Cu")
	)
	(gr_arc
		(start 126.000256 -63.641986)
		(mid 125.641862 -63.999999)
		(end 126.000002 -64.358266)
		(stroke
			(width 0.2)
			(type default)
		)
		(layer "In4.Cu")
	)
	(gr_arc
		(start 126.000256 -62.641988)
		(mid 125.641862 -63.000001)
		(end 126.000002 -63.358268)
		(stroke
			(width 0.2)
			(type default)
		)
		(layer "In4.Cu")
	)
	(gr_arc
		(start 126.000256 -61.64199)
		(mid 125.641862 -62.000003)
		(end 126.000002 -62.35827)
		(stroke
			(width 0.2)
			(type default)
		)
		(layer "In4.Cu")
	)
	(gr_arc
		(start 126.000256 -60.641992)
		(mid 125.641862 -61.000005)
		(end 126.000002 -61.358272)
		(stroke
			(width 0.2)
			(type default)
		)
		(layer "In4.Cu")
	)
	(gr_arc
		(start 126.000256 -59.641994)
		(mid 125.641862 -60.000007)
		(end 126.000002 -60.358274)
		(stroke
			(width 0.2)
			(type default)
		)
		(layer "In4.Cu")
	)
	(gr_arc
		(start 126.000256 -58.641996)
		(mid 125.641862 -59.000009)
		(end 126.000002 -59.358276)
		(stroke
			(width 0.2)
			(type default)
		)
		(layer "In4.Cu")
	)
	(gr_arc
		(start 126.000256 -57.641998)
		(mid 125.641862 -58.000011)
		(end 126.000002 -58.358278)
		(stroke
			(width 0.2)
			(type default)
		)
		(layer "In4.Cu")
	)
	(gr_arc
		(start 126.000256 -56.642)
		(mid 125.641862 -57.000013)
		(end 126.000002 -57.35828)
		(stroke
			(width 0.2)
			(type default)
		)
		(layer "In4.Cu")
	)
	(gr_arc
		(start 126.000256 -55.642002)
		(mid 125.641862 -56.000015)
		(end 126.000002 -56.358282)
		(stroke
			(width 0.2)
			(type default)
		)
		(layer "In4.Cu")
	)
	(gr_arc
		(start 126.000256 -54.642004)
		(mid 125.641862 -55.000017)
		(end 126.000002 -55.358284)
		(stroke
			(width 0.2)
			(type default)
		)
		(layer "In4.Cu")
	)
	(gr_arc
		(start 126.000256 -53.642006)
		(mid 125.641862 -54.000019)
		(end 126.000002 -54.358286)
		(stroke
			(width 0.2)
			(type default)
		)
		(layer "In4.Cu")
	)
	(gr_line
		(start 126.161546 -12.400026)
		(end 126.161546 -10.999978)
		(stroke
			(width 0.2)
			(type default)
		)
		(layer "In4.Cu")
	)
	(gr_arc
		(start 126.161546 -10.999978)
		(mid 125.600206 -10.438638)
		(end 125.038866 -10.999978)
		(stroke
			(width 0.2)
			(type default)
		)
		(layer "In4.Cu")
	)
	(gr_line
		(start 126.161546 -5.200142)
		(end 126.161546 -3.800094)
		(stroke
			(width 0.2)
			(type default)
		)
		(layer "In4.Cu")
	)
	(gr_arc
		(start 126.161546 -3.800094)
		(mid 125.600206 -3.238754)
		(end 125.038866 -3.800094)
		(stroke
			(width 0.2)
			(type default)
		)
		(layer "In4.Cu")
	)
	(gr_arc
		(start 126.619508 -46.986952)
		(mid 127.076581 -47.444406)
		(end 127.533908 -46.987206)
		(stroke
			(width 0.2)
			(type default)
		)
		(layer "In4.Cu")
	)
	(gr_line
		(start 126.619508 -45.844206)
		(end 126.619508 -46.986952)
		(stroke
			(width 0.2)
			(type default)
		)
		(layer "In4.Cu")
	)
	(gr_arc
		(start 126.83871 -11.199876)
		(mid 127.399923 -11.76147)
		(end 127.96139 -11.20013)
		(stroke
			(width 0.2)
			(type default)
		)
		(layer "In4.Cu")
	)
	(gr_line
		(start 126.83871 -9.800082)
		(end 126.83871 -11.199876)
		(stroke
			(width 0.2)
			(type default)
		)
		(layer "In4.Cu")
	)
	(gr_arc
		(start 126.83871 -3.999738)
		(mid 127.399923 -4.561332)
		(end 127.96139 -3.999992)
		(stroke
			(width 0.2)
			(type default)
		)
		(layer "In4.Cu")
	)
	(gr_line
		(start 126.83871 -2.600198)
		(end 126.83871 -3.999738)
		(stroke
			(width 0.2)
			(type default)
		)
		(layer "In4.Cu")
	)
	(gr_arc
		(start 127 -77.35824)
		(mid 127.35814 -77.0001)
		(end 127 -76.64196)
		(stroke
			(width 0.2)
			(type default)
		)
		(layer "In4.Cu")
	)
	(gr_line
		(start 127 -76.64196)
		(end 126.000256 -76.64196)
		(stroke
			(width 0.2)
			(type default)
		)
		(layer "In4.Cu")
	)
	(gr_arc
		(start 127 -76.358242)
		(mid 127.35814 -76.000102)
		(end 127 -75.641962)
		(stroke
			(width 0.2)
			(type default)
		)
		(layer "In4.Cu")
	)
	(gr_line
		(start 127 -75.641962)
		(end 126.000256 -75.641962)
		(stroke
			(width 0.2)
			(type default)
		)
		(layer "In4.Cu")
	)
	(gr_arc
		(start 127 -75.358244)
		(mid 127.35814 -75.000104)
		(end 127 -74.641964)
		(stroke
			(width 0.2)
			(type default)
		)
		(layer "In4.Cu")
	)
	(gr_line
		(start 127 -74.641964)
		(end 126.000256 -74.641964)
		(stroke
			(width 0.2)
			(type default)
		)
		(layer "In4.Cu")
	)
	(gr_arc
		(start 127 -74.358246)
		(mid 127.35814 -74.000106)
		(end 127 -73.641966)
		(stroke
			(width 0.2)
			(type default)
		)
		(layer "In4.Cu")
	)
	(gr_line
		(start 127 -73.641966)
		(end 126.000256 -73.641966)
		(stroke
			(width 0.2)
			(type default)
		)
		(layer "In4.Cu")
	)
	(gr_arc
		(start 127 -73.358248)
		(mid 127.35814 -73.000108)
		(end 127 -72.641968)
		(stroke
			(width 0.2)
			(type default)
		)
		(layer "In4.Cu")
	)
	(gr_line
		(start 127 -72.641968)
		(end 126.000256 -72.641968)
		(stroke
			(width 0.2)
			(type default)
		)
		(layer "In4.Cu")
	)
	(gr_arc
		(start 127 -72.35825)
		(mid 127.35814 -72.00011)
		(end 127 -71.64197)
		(stroke
			(width 0.2)
			(type default)
		)
		(layer "In4.Cu")
	)
	(gr_line
		(start 127 -71.64197)
		(end 126.000256 -71.64197)
		(stroke
			(width 0.2)
			(type default)
		)
		(layer "In4.Cu")
	)
	(gr_arc
		(start 127 -71.358252)
		(mid 127.35814 -71.000112)
		(end 127 -70.641972)
		(stroke
			(width 0.2)
			(type default)
		)
		(layer "In4.Cu")
	)
	(gr_line
		(start 127 -70.641972)
		(end 126.000256 -70.641972)
		(stroke
			(width 0.2)
			(type default)
		)
		(layer "In4.Cu")
	)
	(gr_arc
		(start 127 -70.358254)
		(mid 127.35814 -70.000114)
		(end 127 -69.641974)
		(stroke
			(width 0.2)
			(type default)
		)
		(layer "In4.Cu")
	)
	(gr_line
		(start 127 -69.641974)
		(end 126.000256 -69.641974)
		(stroke
			(width 0.2)
			(type default)
		)
		(layer "In4.Cu")
	)
	(gr_arc
		(start 127 -69.358256)
		(mid 127.35814 -69.000116)
		(end 127 -68.641976)
		(stroke
			(width 0.2)
			(type default)
		)
		(layer "In4.Cu")
	)
	(gr_line
		(start 127 -68.641976)
		(end 126.000256 -68.641976)
		(stroke
			(width 0.2)
			(type default)
		)
		(layer "In4.Cu")
	)
	(gr_arc
		(start 127 -68.358258)
		(mid 127.35814 -68.000118)
		(end 127 -67.641978)
		(stroke
			(width 0.2)
			(type default)
		)
		(layer "In4.Cu")
	)
	(gr_line
		(start 127 -67.641978)
		(end 126.000256 -67.641978)
		(stroke
			(width 0.2)
			(type default)
		)
		(layer "In4.Cu")
	)
	(gr_arc
		(start 127 -66.358262)
		(mid 127.35814 -66.000122)
		(end 127 -65.641982)
		(stroke
			(width 0.2)
			(type default)
		)
		(layer "In4.Cu")
	)
	(gr_line
		(start 127 -65.641982)
		(end 126.000256 -65.641982)
		(stroke
			(width 0.2)
			(type default)
		)
		(layer "In4.Cu")
	)
	(gr_arc
		(start 127 -65.358264)
		(mid 127.35814 -65.000124)
		(end 127 -64.641984)
		(stroke
			(width 0.2)
			(type default)
		)
		(layer "In4.Cu")
	)
	(gr_line
		(start 127 -64.641984)
		(end 126.000256 -64.641984)
		(stroke
			(width 0.2)
			(type default)
		)
		(layer "In4.Cu")
	)
	(gr_arc
		(start 127 -64.358266)
		(mid 127.35814 -64.000126)
		(end 127 -63.641986)
		(stroke
			(width 0.2)
			(type default)
		)
		(layer "In4.Cu")
	)
	(gr_line
		(start 127 -63.641986)
		(end 126.000256 -63.641986)
		(stroke
			(width 0.2)
			(type default)
		)
		(layer "In4.Cu")
	)
	(gr_arc
		(start 127 -63.358268)
		(mid 127.35814 -63.000128)
		(end 127 -62.641988)
		(stroke
			(width 0.2)
			(type default)
		)
		(layer "In4.Cu")
	)
	(gr_line
		(start 127 -62.641988)
		(end 126.000256 -62.641988)
		(stroke
			(width 0.2)
			(type default)
		)
		(layer "In4.Cu")
	)
	(gr_arc
		(start 127 -62.35827)
		(mid 127.35814 -62.00013)
		(end 127 -61.64199)
		(stroke
			(width 0.2)
			(type default)
		)
		(layer "In4.Cu")
	)
	(gr_line
		(start 127 -61.64199)
		(end 126.000256 -61.64199)
		(stroke
			(width 0.2)
			(type default)
		)
		(layer "In4.Cu")
	)
	(gr_arc
		(start 127 -61.358272)
		(mid 127.35814 -61.000132)
		(end 127 -60.641992)
		(stroke
			(width 0.2)
			(type default)
		)
		(layer "In4.Cu")
	)
	(gr_line
		(start 127 -60.641992)
		(end 126.000256 -60.641992)
		(stroke
			(width 0.2)
			(type default)
		)
		(layer "In4.Cu")
	)
	(gr_arc
		(start 127 -60.358274)
		(mid 127.35814 -60.000134)
		(end 127 -59.641994)
		(stroke
			(width 0.2)
			(type default)
		)
		(layer "In4.Cu")
	)
	(gr_line
		(start 127 -59.641994)
		(end 126.000256 -59.641994)
		(stroke
			(width 0.2)
			(type default)
		)
		(layer "In4.Cu")
	)
	(gr_arc
		(start 127 -59.358276)
		(mid 127.35814 -59.000136)
		(end 127 -58.641996)
		(stroke
			(width 0.2)
			(type default)
		)
		(layer "In4.Cu")
	)
	(gr_line
		(start 127 -58.641996)
		(end 126.000256 -58.641996)
		(stroke
			(width 0.2)
			(type default)
		)
		(layer "In4.Cu")
	)
	(gr_arc
		(start 127 -58.358278)
		(mid 127.35814 -58.000138)
		(end 127 -57.641998)
		(stroke
			(width 0.2)
			(type default)
		)
		(layer "In4.Cu")
	)
	(gr_line
		(start 127 -57.641998)
		(end 126.000256 -57.641998)
		(stroke
			(width 0.2)
			(type default)
		)
		(layer "In4.Cu")
	)
	(gr_arc
		(start 127 -57.35828)
		(mid 127.35814 -57.00014)
		(end 127 -56.642)
		(stroke
			(width 0.2)
			(type default)
		)
		(layer "In4.Cu")
	)
	(gr_line
		(start 127 -56.642)
		(end 126.000256 -56.642)
		(stroke
			(width 0.2)
			(type default)
		)
		(layer "In4.Cu")
	)
	(gr_arc
		(start 127 -56.358282)
		(mid 127.35814 -56.000142)
		(end 127 -55.642002)
		(stroke
			(width 0.2)
			(type default)
		)
		(layer "In4.Cu")
	)
	(gr_line
		(start 127 -55.642002)
		(end 126.000256 -55.642002)
		(stroke
			(width 0.2)
			(type default)
		)
		(layer "In4.Cu")
	)
	(gr_arc
		(start 127 -55.358284)
		(mid 127.35814 -55.000144)
		(end 127 -54.642004)
		(stroke
			(width 0.2)
			(type default)
		)
		(layer "In4.Cu")
	)
	(gr_line
		(start 127 -54.642004)
		(end 126.000256 -54.642004)
		(stroke
			(width 0.2)
			(type default)
		)
		(layer "In4.Cu")
	)
	(gr_arc
		(start 127 -54.358286)
		(mid 127.35814 -54.000146)
		(end 127 -53.642006)
		(stroke
			(width 0.2)
			(type default)
		)
		(layer "In4.Cu")
	)
	(gr_line
		(start 127 -53.642006)
		(end 126.000256 -53.642006)
		(stroke
			(width 0.2)
			(type default)
		)
		(layer "In4.Cu")
	)
	(gr_line
		(start 127 -53.358288)
		(end 127.999998 -53.358288)
		(stroke
			(width 0.2)
			(type default)
		)
		(layer "In4.Cu")
	)
	(gr_arc
		(start 127.000254 -52.642008)
		(mid 126.64186 -53.000021)
		(end 127 -53.358288)
		(stroke
			(width 0.2)
			(type default)
		)
		(layer "In4.Cu")
	)
	(gr_line
		(start 127.533908 -46.987206)
		(end 127.533908 -45.844206)
		(stroke
			(width 0.2)
			(type default)
		)
		(layer "In4.Cu")
	)
	(gr_arc
		(start 127.533908 -45.844206)
		(mid 127.076708 -45.387006)
		(end 126.619508 -45.844206)
		(stroke
			(width 0.2)
			(type default)
		)
		(layer "In4.Cu")
	)
	(gr_line
		(start 127.96139 -11.20013)
		(end 127.96139 -9.800082)
		(stroke
			(width 0.2)
			(type default)
		)
		(layer "In4.Cu")
	)
	(gr_arc
		(start 127.96139 -9.800082)
		(mid 127.40005 -9.238742)
		(end 126.83871 -9.800082)
		(stroke
			(width 0.2)
			(type default)
		)
		(layer "In4.Cu")
	)
	(gr_line
		(start 127.96139 -3.999992)
		(end 127.96139 -2.600198)
		(stroke
			(width 0.2)
			(type default)
		)
		(layer "In4.Cu")
	)
	(gr_arc
		(start 127.96139 -2.600198)
		(mid 127.40005 -2.038858)
		(end 126.83871 -2.600198)
		(stroke
			(width 0.2)
			(type default)
		)
		(layer "In4.Cu")
	)
	(gr_arc
		(start 127.999998 -53.358288)
		(mid 128.358138 -53.000148)
		(end 127.999998 -52.642008)
		(stroke
			(width 0.2)
			(type default)
		)
		(layer "In4.Cu")
	)
	(gr_line
		(start 127.999998 -52.642008)
		(end 127.000254 -52.642008)
		(stroke
			(width 0.2)
			(type default)
		)
		(layer "In4.Cu")
	)
	(gr_line
		(start 128.043432 -101.346)
		(end 114.808 -101.346)
		(stroke
			(width 0.381)
			(type default)
		)
		(layer "In4.Cu")
	)
	(gr_arc
		(start 128.638808 -12.399772)
		(mid 129.200021 -12.961366)
		(end 129.761488 -12.400026)
		(stroke
			(width 0.2)
			(type default)
		)
		(layer "In4.Cu")
	)
	(gr_line
		(start 128.638808 -10.999978)
		(end 128.638808 -12.399772)
		(stroke
			(width 0.2)
			(type default)
		)
		(layer "In4.Cu")
	)
	(gr_arc
		(start 128.638808 -5.199888)
		(mid 129.200021 -5.761482)
		(end 129.761488 -5.200142)
		(stroke
			(width 0.2)
			(type default)
		)
		(layer "In4.Cu")
	)
	(gr_line
		(start 128.638808 -3.800094)
		(end 128.638808 -5.199888)
		(stroke
			(width 0.2)
			(type default)
		)
		(layer "In4.Cu")
	)
	(gr_line
		(start 128.999996 -72.35825)
		(end 129.999994 -72.35825)
		(stroke
			(width 0.2)
			(type default)
		)
		(layer "In4.Cu")
	)
	(gr_line
		(start 128.999996 -70.358254)
		(end 129.999994 -70.358254)
		(stroke
			(width 0.2)
			(type default)
		)
		(layer "In4.Cu")
	)
	(gr_line
		(start 128.999996 -68.358258)
		(end 129.999994 -68.358258)
		(stroke
			(width 0.2)
			(type default)
		)
		(layer "In4.Cu")
	)
	(gr_line
		(start 128.999996 -65.358264)
		(end 129.999994 -65.358264)
		(stroke
			(width 0.2)
			(type default)
		)
		(layer "In4.Cu")
	)
	(gr_line
		(start 128.999996 -63.358268)
		(end 129.999994 -63.358268)
		(stroke
			(width 0.2)
			(type default)
		)
		(layer "In4.Cu")
	)
	(gr_line
		(start 128.999996 -61.358272)
		(end 129.999994 -61.358272)
		(stroke
			(width 0.2)
			(type default)
		)
		(layer "In4.Cu")
	)
	(gr_arc
		(start 129.00025 -71.64197)
		(mid 128.641856 -71.999983)
		(end 128.999996 -72.35825)
		(stroke
			(width 0.2)
			(type default)
		)
		(layer "In4.Cu")
	)
	(gr_arc
		(start 129.00025 -69.641974)
		(mid 128.641856 -69.999987)
		(end 128.999996 -70.358254)
		(stroke
			(width 0.2)
			(type default)
		)
		(layer "In4.Cu")
	)
	(gr_arc
		(start 129.00025 -67.641978)
		(mid 128.641856 -67.999991)
		(end 128.999996 -68.358258)
		(stroke
			(width 0.2)
			(type default)
		)
		(layer "In4.Cu")
	)
	(gr_arc
		(start 129.00025 -64.641984)
		(mid 128.641856 -64.999997)
		(end 128.999996 -65.358264)
		(stroke
			(width 0.2)
			(type default)
		)
		(layer "In4.Cu")
	)
	(gr_arc
		(start 129.00025 -62.641988)
		(mid 128.641856 -63.000001)
		(end 128.999996 -63.358268)
		(stroke
			(width 0.2)
			(type default)
		)
		(layer "In4.Cu")
	)
	(gr_arc
		(start 129.00025 -60.641992)
		(mid 128.641856 -61.000005)
		(end 128.999996 -61.358272)
		(stroke
			(width 0.2)
			(type default)
		)
		(layer "In4.Cu")
	)
	(gr_arc
		(start 129.191258 -46.97222)
		(mid 129.648331 -47.429674)
		(end 130.105658 -46.972474)
		(stroke
			(width 0.2)
			(type default)
		)
		(layer "In4.Cu")
	)
	(gr_line
		(start 129.191258 -45.829474)
		(end 129.191258 -46.97222)
		(stroke
			(width 0.2)
			(type default)
		)
		(layer "In4.Cu")
	)
	(gr_line
		(start 129.761488 -12.400026)
		(end 129.761488 -10.999978)
		(stroke
			(width 0.2)
			(type default)
		)
		(layer "In4.Cu")
	)
	(gr_arc
		(start 129.761488 -10.999978)
		(mid 129.200148 -10.438638)
		(end 128.638808 -10.999978)
		(stroke
			(width 0.2)
			(type default)
		)
		(layer "In4.Cu")
	)
	(gr_line
		(start 129.761488 -5.200142)
		(end 129.761488 -3.800094)
		(stroke
			(width 0.2)
			(type default)
		)
		(layer "In4.Cu")
	)
	(gr_arc
		(start 129.761488 -3.800094)
		(mid 129.200148 -3.238754)
		(end 128.638808 -3.800094)
		(stroke
			(width 0.2)
			(type default)
		)
		(layer "In4.Cu")
	)
	(gr_line
		(start 129.999994 -73.358248)
		(end 130.999992 -73.358248)
		(stroke
			(width 0.2)
			(type default)
		)
		(layer "In4.Cu")
	)
	(gr_arc
		(start 129.999994 -72.35825)
		(mid 130.358134 -72.00011)
		(end 129.999994 -71.64197)
		(stroke
			(width 0.2)
			(type default)
		)
		(layer "In4.Cu")
	)
	(gr_line
		(start 129.999994 -71.64197)
		(end 129.00025 -71.64197)
		(stroke
			(width 0.2)
			(type default)
		)
		(layer "In4.Cu")
	)
	(gr_line
		(start 129.999994 -71.358252)
		(end 130.999992 -71.358252)
		(stroke
			(width 0.2)
			(type default)
		)
		(layer "In4.Cu")
	)
	(gr_arc
		(start 129.999994 -70.358254)
		(mid 130.358134 -70.000114)
		(end 129.999994 -69.641974)
		(stroke
			(width 0.2)
			(type default)
		)
		(layer "In4.Cu")
	)
	(gr_line
		(start 129.999994 -69.641974)
		(end 129.00025 -69.641974)
		(stroke
			(width 0.2)
			(type default)
		)
		(layer "In4.Cu")
	)
	(gr_line
		(start 129.999994 -69.358256)
		(end 130.999992 -69.358256)
		(stroke
			(width 0.2)
			(type default)
		)
		(layer "In4.Cu")
	)
	(gr_arc
		(start 129.999994 -68.358258)
		(mid 130.358134 -68.000118)
		(end 129.999994 -67.641978)
		(stroke
			(width 0.2)
			(type default)
		)
		(layer "In4.Cu")
	)
	(gr_line
		(start 129.999994 -67.641978)
		(end 129.00025 -67.641978)
		(stroke
			(width 0.2)
			(type default)
		)
		(layer "In4.Cu")
	)
	(gr_line
		(start 129.999994 -66.358262)
		(end 130.999992 -66.358262)
		(stroke
			(width 0.2)
			(type default)
		)
		(layer "In4.Cu")
	)
	(gr_arc
		(start 129.999994 -65.358264)
		(mid 130.358134 -65.000124)
		(end 129.999994 -64.641984)
		(stroke
			(width 0.2)
			(type default)
		)
		(layer "In4.Cu")
	)
	(gr_line
		(start 129.999994 -64.641984)
		(end 129.00025 -64.641984)
		(stroke
			(width 0.2)
			(type default)
		)
		(layer "In4.Cu")
	)
	(gr_line
		(start 129.999994 -64.358266)
		(end 130.999992 -64.358266)
		(stroke
			(width 0.2)
			(type default)
		)
		(layer "In4.Cu")
	)
	(gr_arc
		(start 129.999994 -63.358268)
		(mid 130.358134 -63.000128)
		(end 129.999994 -62.641988)
		(stroke
			(width 0.2)
			(type default)
		)
		(layer "In4.Cu")
	)
	(gr_line
		(start 129.999994 -62.641988)
		(end 129.00025 -62.641988)
		(stroke
			(width 0.2)
			(type default)
		)
		(layer "In4.Cu")
	)
	(gr_line
		(start 129.999994 -62.35827)
		(end 130.999992 -62.35827)
		(stroke
			(width 0.2)
			(type default)
		)
		(layer "In4.Cu")
	)
	(gr_arc
		(start 129.999994 -61.358272)
		(mid 130.358134 -61.000132)
		(end 129.999994 -60.641992)
		(stroke
			(width 0.2)
			(type default)
		)
		(layer "In4.Cu")
	)
	(gr_line
		(start 129.999994 -60.641992)
		(end 129.00025 -60.641992)
		(stroke
			(width 0.2)
			(type default)
		)
		(layer "In4.Cu")
	)
	(gr_arc
		(start 130.000248 -72.641968)
		(mid 129.641854 -72.999981)
		(end 129.999994 -73.358248)
		(stroke
			(width 0.2)
			(type default)
		)
		(layer "In4.Cu")
	)
	(gr_arc
		(start 130.000248 -70.641972)
		(mid 129.641854 -70.999985)
		(end 129.999994 -71.358252)
		(stroke
			(width 0.2)
			(type default)
		)
		(layer "In4.Cu")
	)
	(gr_arc
		(start 130.000248 -68.641976)
		(mid 129.641854 -68.999989)
		(end 129.999994 -69.358256)
		(stroke
			(width 0.2)
			(type default)
		)
		(layer "In4.Cu")
	)
	(gr_arc
		(start 130.000248 -65.641982)
		(mid 129.641854 -65.999995)
		(end 129.999994 -66.358262)
		(stroke
			(width 0.2)
			(type default)
		)
		(layer "In4.Cu")
	)
	(gr_arc
		(start 130.000248 -63.641986)
		(mid 129.641854 -63.999999)
		(end 129.999994 -64.358266)
		(stroke
			(width 0.2)
			(type default)
		)
		(layer "In4.Cu")
	)
	(gr_arc
		(start 130.000248 -61.64199)
		(mid 129.641854 -62.000003)
		(end 129.999994 -62.35827)
		(stroke
			(width 0.2)
			(type default)
		)
		(layer "In4.Cu")
	)
	(gr_line
		(start 130.105658 -46.972474)
		(end 130.105658 -45.829474)
		(stroke
			(width 0.2)
			(type default)
		)
		(layer "In4.Cu")
	)
	(gr_arc
		(start 130.105658 -45.829474)
		(mid 129.648458 -45.372274)
		(end 129.191258 -45.829474)
		(stroke
			(width 0.2)
			(type default)
		)
		(layer "In4.Cu")
	)
	(gr_arc
		(start 130.438652 -11.199876)
		(mid 130.999865 -11.76147)
		(end 131.561332 -11.20013)
		(stroke
			(width 0.2)
			(type default)
		)
		(layer "In4.Cu")
	)
	(gr_line
		(start 130.438652 -9.800082)
		(end 130.438652 -11.199876)
		(stroke
			(width 0.2)
			(type default)
		)
		(layer "In4.Cu")
	)
	(gr_arc
		(start 130.438652 -3.999738)
		(mid 130.999865 -4.561332)
		(end 131.561332 -3.999992)
		(stroke
			(width 0.2)
			(type default)
		)
		(layer "In4.Cu")
	)
	(gr_line
		(start 130.438652 -2.600198)
		(end 130.438652 -3.999738)
		(stroke
			(width 0.2)
			(type default)
		)
		(layer "In4.Cu")
	)
	(gr_arc
		(start 130.999992 -73.358248)
		(mid 131.358132 -73.000108)
		(end 130.999992 -72.641968)
		(stroke
			(width 0.2)
			(type default)
		)
		(layer "In4.Cu")
	)
	(gr_line
		(start 130.999992 -72.641968)
		(end 130.000248 -72.641968)
		(stroke
			(width 0.2)
			(type default)
		)
		(layer "In4.Cu")
	)
	(gr_arc
		(start 130.999992 -71.358252)
		(mid 131.358132 -71.000112)
		(end 130.999992 -70.641972)
		(stroke
			(width 0.2)
			(type default)
		)
		(layer "In4.Cu")
	)
	(gr_line
		(start 130.999992 -70.641972)
		(end 130.000248 -70.641972)
		(stroke
			(width 0.2)
			(type default)
		)
		(layer "In4.Cu")
	)
	(gr_arc
		(start 130.999992 -69.358256)
		(mid 131.358132 -69.000116)
		(end 130.999992 -68.641976)
		(stroke
			(width 0.2)
			(type default)
		)
		(layer "In4.Cu")
	)
	(gr_line
		(start 130.999992 -68.641976)
		(end 130.000248 -68.641976)
		(stroke
			(width 0.2)
			(type default)
		)
		(layer "In4.Cu")
	)
	(gr_arc
		(start 130.999992 -66.358262)
		(mid 131.358132 -66.000122)
		(end 130.999992 -65.641982)
		(stroke
			(width 0.2)
			(type default)
		)
		(layer "In4.Cu")
	)
	(gr_line
		(start 130.999992 -65.641982)
		(end 130.000248 -65.641982)
		(stroke
			(width 0.2)
			(type default)
		)
		(layer "In4.Cu")
	)
	(gr_arc
		(start 130.999992 -64.358266)
		(mid 131.358132 -64.000126)
		(end 130.999992 -63.641986)
		(stroke
			(width 0.2)
			(type default)
		)
		(layer "In4.Cu")
	)
	(gr_line
		(start 130.999992 -63.641986)
		(end 130.000248 -63.641986)
		(stroke
			(width 0.2)
			(type default)
		)
		(layer "In4.Cu")
	)
	(gr_arc
		(start 130.999992 -62.35827)
		(mid 131.358132 -62.00013)
		(end 130.999992 -61.64199)
		(stroke
			(width 0.2)
			(type default)
		)
		(layer "In4.Cu")
	)
	(gr_line
		(start 130.999992 -61.64199)
		(end 130.000248 -61.64199)
		(stroke
			(width 0.2)
			(type default)
		)
		(layer "In4.Cu")
	)
	(gr_line
		(start 131.561332 -11.20013)
		(end 131.561332 -9.800082)
		(stroke
			(width 0.2)
			(type default)
		)
		(layer "In4.Cu")
	)
	(gr_arc
		(start 131.561332 -9.800082)
		(mid 130.999992 -9.238742)
		(end 130.438652 -9.800082)
		(stroke
			(width 0.2)
			(type default)
		)
		(layer "In4.Cu")
	)
	(gr_line
		(start 131.561332 -3.999992)
		(end 131.561332 -2.600198)
		(stroke
			(width 0.2)
			(type default)
		)
		(layer "In4.Cu")
	)
	(gr_arc
		(start 131.561332 -2.600198)
		(mid 130.999992 -2.038858)
		(end 130.438652 -2.600198)
		(stroke
			(width 0.2)
			(type default)
		)
		(layer "In4.Cu")
	)
	(gr_arc
		(start 131.763008 -46.957488)
		(mid 132.220081 -47.414942)
		(end 132.677408 -46.957742)
		(stroke
			(width 0.2)
			(type default)
		)
		(layer "In4.Cu")
	)
	(gr_line
		(start 131.763008 -45.814742)
		(end 131.763008 -46.957488)
		(stroke
			(width 0.2)
			(type default)
		)
		(layer "In4.Cu")
	)
	(gr_arc
		(start 132.23875 -12.399772)
		(mid 132.799963 -12.961366)
		(end 133.36143 -12.400026)
		(stroke
			(width 0.2)
			(type default)
		)
		(layer "In4.Cu")
	)
	(gr_line
		(start 132.23875 -10.999978)
		(end 132.23875 -12.399772)
		(stroke
			(width 0.2)
			(type default)
		)
		(layer "In4.Cu")
	)
	(gr_arc
		(start 132.23875 -5.199888)
		(mid 132.799963 -5.761482)
		(end 133.36143 -5.200142)
		(stroke
			(width 0.2)
			(type default)
		)
		(layer "In4.Cu")
	)
	(gr_line
		(start 132.23875 -3.800094)
		(end 132.23875 -5.199888)
		(stroke
			(width 0.2)
			(type default)
		)
		(layer "In4.Cu")
	)
	(gr_line
		(start 132.677408 -46.957742)
		(end 132.677408 -45.814742)
		(stroke
			(width 0.2)
			(type default)
		)
		(layer "In4.Cu")
	)
	(gr_arc
		(start 132.677408 -45.814742)
		(mid 132.220208 -45.357542)
		(end 131.763008 -45.814742)
		(stroke
			(width 0.2)
			(type default)
		)
		(layer "In4.Cu")
	)
	(gr_line
		(start 133.36143 -12.400026)
		(end 133.36143 -10.999978)
		(stroke
			(width 0.2)
			(type default)
		)
		(layer "In4.Cu")
	)
	(gr_arc
		(start 133.36143 -10.999978)
		(mid 132.80009 -10.438638)
		(end 132.23875 -10.999978)
		(stroke
			(width 0.2)
			(type default)
		)
		(layer "In4.Cu")
	)
	(gr_line
		(start 133.36143 -5.200142)
		(end 133.36143 -3.800094)
		(stroke
			(width 0.2)
			(type default)
		)
		(layer "In4.Cu")
	)
	(gr_arc
		(start 133.36143 -3.800094)
		(mid 132.80009 -3.238754)
		(end 132.23875 -3.800094)
		(stroke
			(width 0.2)
			(type default)
		)
		(layer "In4.Cu")
	)
	(gr_arc
		(start 134.038848 -11.199876)
		(mid 134.600061 -11.76147)
		(end 135.161528 -11.20013)
		(stroke
			(width 0.2)
			(type default)
		)
		(layer "In4.Cu")
	)
	(gr_line
		(start 134.038848 -9.800082)
		(end 134.038848 -11.199876)
		(stroke
			(width 0.2)
			(type default)
		)
		(layer "In4.Cu")
	)
	(gr_arc
		(start 134.038848 -3.999738)
		(mid 134.600061 -4.561332)
		(end 135.161528 -3.999992)
		(stroke
			(width 0.2)
			(type default)
		)
		(layer "In4.Cu")
	)
	(gr_line
		(start 134.038848 -2.600198)
		(end 134.038848 -3.999738)
		(stroke
			(width 0.2)
			(type default)
		)
		(layer "In4.Cu")
	)
	(gr_line
		(start 135.161528 -11.20013)
		(end 135.161528 -9.800082)
		(stroke
			(width 0.2)
			(type default)
		)
		(layer "In4.Cu")
	)
	(gr_arc
		(start 135.161528 -9.800082)
		(mid 134.600188 -9.238742)
		(end 134.038848 -9.800082)
		(stroke
			(width 0.2)
			(type default)
		)
		(layer "In4.Cu")
	)
	(gr_line
		(start 135.161528 -3.999992)
		(end 135.161528 -2.600198)
		(stroke
			(width 0.2)
			(type default)
		)
		(layer "In4.Cu")
	)
	(gr_arc
		(start 135.161528 -2.600198)
		(mid 134.600188 -2.038858)
		(end 134.038848 -2.600198)
		(stroke
			(width 0.2)
			(type default)
		)
		(layer "In4.Cu")
	)
	(gr_arc
		(start 135.838692 -12.399772)
		(mid 136.399905 -12.961366)
		(end 136.961372 -12.400026)
		(stroke
			(width 0.2)
			(type default)
		)
		(layer "In4.Cu")
	)
	(gr_line
		(start 135.838692 -10.999978)
		(end 135.838692 -12.399772)
		(stroke
			(width 0.2)
			(type default)
		)
		(layer "In4.Cu")
	)
	(gr_arc
		(start 135.838692 -5.199888)
		(mid 136.399905 -5.761482)
		(end 136.961372 -5.200142)
		(stroke
			(width 0.2)
			(type default)
		)
		(layer "In4.Cu")
	)
	(gr_line
		(start 135.838692 -3.800094)
		(end 135.838692 -5.199888)
		(stroke
			(width 0.2)
			(type default)
		)
		(layer "In4.Cu")
	)
	(gr_line
		(start 136.857232 -110.1598)
		(end 128.043432 -101.346)
		(stroke
			(width 0.381)
			(type default)
		)
		(layer "In4.Cu")
	)
	(gr_line
		(start 136.961372 -12.400026)
		(end 136.961372 -10.999978)
		(stroke
			(width 0.2)
			(type default)
		)
		(layer "In4.Cu")
	)
	(gr_arc
		(start 136.961372 -10.999978)
		(mid 136.400032 -10.438638)
		(end 135.838692 -10.999978)
		(stroke
			(width 0.2)
			(type default)
		)
		(layer "In4.Cu")
	)
	(gr_line
		(start 136.961372 -5.200142)
		(end 136.961372 -3.800094)
		(stroke
			(width 0.2)
			(type default)
		)
		(layer "In4.Cu")
	)
	(gr_arc
		(start 136.961372 -3.800094)
		(mid 136.400032 -3.238754)
		(end 135.838692 -3.800094)
		(stroke
			(width 0.2)
			(type default)
		)
		(layer "In4.Cu")
	)
	(gr_arc
		(start 137.63879 -11.199876)
		(mid 138.200003 -11.76147)
		(end 138.76147 -11.20013)
		(stroke
			(width 0.2)
			(type default)
		)
		(layer "In4.Cu")
	)
	(gr_line
		(start 137.63879 -9.800082)
		(end 137.63879 -11.199876)
		(stroke
			(width 0.2)
			(type default)
		)
		(layer "In4.Cu")
	)
	(gr_arc
		(start 137.63879 -3.999738)
		(mid 138.200003 -4.561332)
		(end 138.76147 -3.999992)
		(stroke
			(width 0.2)
			(type default)
		)
		(layer "In4.Cu")
	)
	(gr_line
		(start 137.63879 -2.600198)
		(end 137.63879 -3.999738)
		(stroke
			(width 0.2)
			(type default)
		)
		(layer "In4.Cu")
	)
	(gr_line
		(start 138.479022 -76.90866)
		(end 139.622022 -76.90866)
		(stroke
			(width 0.2)
			(type default)
		)
		(layer "In4.Cu")
	)
	(gr_line
		(start 138.479022 -76.907898)
		(end 138.479022 -76.90866)
		(stroke
			(width 0.2)
			(type default)
		)
		(layer "In4.Cu")
	)
	(gr_arc
		(start 138.479022 -76.142342)
		(mid 138.096244 -76.52512)
		(end 138.479022 -76.907898)
		(stroke
			(width 0.2)
			(type default)
		)
		(layer "In4.Cu")
	)
	(gr_line
		(start 138.479022 -76.141834)
		(end 138.479022 -76.142342)
		(stroke
			(width 0.2)
			(type default)
		)
		(layer "In4.Cu")
	)
	(gr_line
		(start 138.479276 -76.14158)
		(end 138.479022 -76.141834)
		(stroke
			(width 0.2)
			(type default)
		)
		(layer "In4.Cu")
	)
	(gr_line
		(start 138.486134 -78.811374)
		(end 139.62888 -78.811374)
		(stroke
			(width 0.2)
			(type default)
		)
		(layer "In4.Cu")
	)
	(gr_line
		(start 138.486134 -78.810612)
		(end 138.486134 -78.811374)
		(stroke
			(width 0.2)
			(type default)
		)
		(layer "In4.Cu")
	)
	(gr_arc
		(start 138.486134 -78.045056)
		(mid 138.103356 -78.427834)
		(end 138.486134 -78.810612)
		(stroke
			(width 0.2)
			(type default)
		)
		(layer "In4.Cu")
	)
	(gr_line
		(start 138.486134 -78.044294)
		(end 138.486134 -78.045056)
		(stroke
			(width 0.2)
			(type default)
		)
		(layer "In4.Cu")
	)
	(gr_line
		(start 138.500612 -80.580992)
		(end 139.643612 -80.580992)
		(stroke
			(width 0.2)
			(type default)
		)
		(layer "In4.Cu")
	)
	(gr_line
		(start 138.500612 -80.58023)
		(end 138.500612 -80.580992)
		(stroke
			(width 0.2)
			(type default)
		)
		(layer "In4.Cu")
	)
	(gr_arc
		(start 138.500612 -79.814674)
		(mid 138.117834 -80.197452)
		(end 138.500612 -80.58023)
		(stroke
			(width 0.2)
			(type default)
		)
		(layer "In4.Cu")
	)
	(gr_line
		(start 138.500612 -79.814166)
		(end 138.500612 -79.814674)
		(stroke
			(width 0.2)
			(type default)
		)
		(layer "In4.Cu")
	)
	(gr_line
		(start 138.500866 -79.813912)
		(end 138.500612 -79.814166)
		(stroke
			(width 0.2)
			(type default)
		)
		(layer "In4.Cu")
	)
	(gr_line
		(start 138.739118 -65.426844)
		(end 139.881864 -65.426844)
		(stroke
			(width 0.2)
			(type default)
		)
		(layer "In4.Cu")
	)
	(gr_arc
		(start 138.739118 -64.517524)
		(mid 138.284458 -64.972184)
		(end 138.739118 -65.426844)
		(stroke
			(width 0.2)
			(type default)
		)
		(layer "In4.Cu")
	)
	(gr_line
		(start 138.76147 -11.20013)
		(end 138.76147 -9.800082)
		(stroke
			(width 0.2)
			(type default)
		)
		(layer "In4.Cu")
	)
	(gr_arc
		(start 138.76147 -9.800082)
		(mid 138.20013 -9.238742)
		(end 137.63879 -9.800082)
		(stroke
			(width 0.2)
			(type default)
		)
		(layer "In4.Cu")
	)
	(gr_line
		(start 138.76147 -3.999992)
		(end 138.76147 -2.600198)
		(stroke
			(width 0.2)
			(type default)
		)
		(layer "In4.Cu")
	)
	(gr_arc
		(start 138.76147 -2.600198)
		(mid 138.20013 -2.038858)
		(end 137.63879 -2.600198)
		(stroke
			(width 0.2)
			(type default)
		)
		(layer "In4.Cu")
	)
	(gr_line
		(start 138.80465 -63.499746)
		(end 139.947396 -63.499746)
		(stroke
			(width 0.2)
			(type default)
		)
		(layer "In4.Cu")
	)
	(gr_arc
		(start 138.80465 -62.590426)
		(mid 138.34999 -63.045086)
		(end 138.80465 -63.499746)
		(stroke
			(width 0.2)
			(type default)
		)
		(layer "In4.Cu")
	)
	(gr_line
		(start 138.843258 -82.691986)
		(end 139.986258 -82.691986)
		(stroke
			(width 0.2)
			(type default)
		)
		(layer "In4.Cu")
	)
	(gr_line
		(start 138.843258 -82.691224)
		(end 138.843258 -82.691986)
		(stroke
			(width 0.2)
			(type default)
		)
		(layer "In4.Cu")
	)
	(gr_arc
		(start 138.843258 -81.925668)
		(mid 138.46048 -82.308446)
		(end 138.843258 -82.691224)
		(stroke
			(width 0.2)
			(type default)
		)
		(layer "In4.Cu")
	)
	(gr_line
		(start 138.843258 -81.92516)
		(end 138.843258 -81.925668)
		(stroke
			(width 0.2)
			(type default)
		)
		(layer "In4.Cu")
	)
	(gr_line
		(start 138.843512 -81.924906)
		(end 138.843258 -81.92516)
		(stroke
			(width 0.2)
			(type default)
		)
		(layer "In4.Cu")
	)
	(gr_line
		(start 139.03071 -61.576712)
		(end 140.173456 -61.576712)
		(stroke
			(width 0.2)
			(type default)
		)
		(layer "In4.Cu")
	)
	(gr_arc
		(start 139.03071 -60.667392)
		(mid 138.57605 -61.122052)
		(end 139.03071 -61.576712)
		(stroke
			(width 0.2)
			(type default)
		)
		(layer "In4.Cu")
	)
	(gr_arc
		(start 139.438634 -12.399772)
		(mid 139.999847 -12.961366)
		(end 140.561314 -12.400026)
		(stroke
			(width 0.2)
			(type default)
		)
		(layer "In4.Cu")
	)
	(gr_line
		(start 139.438634 -10.999978)
		(end 139.438634 -12.399772)
		(stroke
			(width 0.2)
			(type default)
		)
		(layer "In4.Cu")
	)
	(gr_arc
		(start 139.438634 -5.199888)
		(mid 139.999847 -5.761482)
		(end 140.561314 -5.200142)
		(stroke
			(width 0.2)
			(type default)
		)
		(layer "In4.Cu")
	)
	(gr_line
		(start 139.438634 -3.800094)
		(end 139.438634 -5.199888)
		(stroke
			(width 0.2)
			(type default)
		)
		(layer "In4.Cu")
	)
	(gr_line
		(start 139.446 -59.35726)
		(end 140.588746 -59.35726)
		(stroke
			(width 0.2)
			(type default)
		)
		(layer "In4.Cu")
	)
	(gr_arc
		(start 139.446 -58.44794)
		(mid 138.99134 -58.9026)
		(end 139.446 -59.35726)
		(stroke
			(width 0.2)
			(type default)
		)
		(layer "In4.Cu")
	)
	(gr_line
		(start 139.622022 -76.90866)
		(end 139.622022 -76.907898)
		(stroke
			(width 0.2)
			(type default)
		)
		(layer "In4.Cu")
	)
	(gr_arc
		(start 139.622022 -76.907898)
		(mid 140.0048 -76.52512)
		(end 139.622022 -76.142342)
		(stroke
			(width 0.2)
			(type default)
		)
		(layer "In4.Cu")
	)
	(gr_line
		(start 139.622022 -76.142342)
		(end 139.622022 -76.14158)
		(stroke
			(width 0.2)
			(type default)
		)
		(layer "In4.Cu")
	)
	(gr_line
		(start 139.622022 -76.14158)
		(end 138.479276 -76.14158)
		(stroke
			(width 0.2)
			(type default)
		)
		(layer "In4.Cu")
	)
	(gr_line
		(start 139.62888 -78.811374)
		(end 139.629134 -78.81112)
		(stroke
			(width 0.2)
			(type default)
		)
		(layer "In4.Cu")
	)
	(gr_line
		(start 139.629134 -78.81112)
		(end 139.629134 -78.810612)
		(stroke
			(width 0.2)
			(type default)
		)
		(layer "In4.Cu")
	)
	(gr_arc
		(start 139.629134 -78.810612)
		(mid 140.011912 -78.427834)
		(end 139.629134 -78.045056)
		(stroke
			(width 0.2)
			(type default)
		)
		(layer "In4.Cu")
	)
	(gr_line
		(start 139.629134 -78.045056)
		(end 139.629134 -78.044294)
		(stroke
			(width 0.2)
			(type default)
		)
		(layer "In4.Cu")
	)
	(gr_line
		(start 139.629134 -78.044294)
		(end 138.486134 -78.044294)
		(stroke
			(width 0.2)
			(type default)
		)
		(layer "In4.Cu")
	)
	(gr_line
		(start 139.643612 -80.580992)
		(end 139.643612 -80.58023)
		(stroke
			(width 0.2)
			(type default)
		)
		(layer "In4.Cu")
	)
	(gr_arc
		(start 139.643612 -80.58023)
		(mid 140.02639 -80.197452)
		(end 139.643612 -79.814674)
		(stroke
			(width 0.2)
			(type default)
		)
		(layer "In4.Cu")
	)
	(gr_line
		(start 139.643612 -79.814674)
		(end 139.643612 -79.813912)
		(stroke
			(width 0.2)
			(type default)
		)
		(layer "In4.Cu")
	)
	(gr_line
		(start 139.643612 -79.813912)
		(end 138.500866 -79.813912)
		(stroke
			(width 0.2)
			(type default)
		)
		(layer "In4.Cu")
	)
	(gr_arc
		(start 139.881864 -65.426844)
		(mid 140.336778 -64.972311)
		(end 139.882118 -64.517524)
		(stroke
			(width 0.2)
			(type default)
		)
		(layer "In4.Cu")
	)
	(gr_line
		(start 139.882118 -64.517524)
		(end 138.739118 -64.517524)
		(stroke
			(width 0.2)
			(type default)
		)
		(layer "In4.Cu")
	)
	(gr_arc
		(start 139.947396 -63.499746)
		(mid 140.40231 -63.045213)
		(end 139.94765 -62.590426)
		(stroke
			(width 0.2)
			(type default)
		)
		(layer "In4.Cu")
	)
	(gr_line
		(start 139.94765 -62.590426)
		(end 138.80465 -62.590426)
		(stroke
			(width 0.2)
			(type default)
		)
		(layer "In4.Cu")
	)
	(gr_line
		(start 139.986258 -82.691986)
		(end 139.986258 -82.691224)
		(stroke
			(width 0.2)
			(type default)
		)
		(layer "In4.Cu")
	)
	(gr_arc
		(start 139.986258 -82.691224)
		(mid 140.369036 -82.308446)
		(end 139.986258 -81.925668)
		(stroke
			(width 0.2)
			(type default)
		)
		(layer "In4.Cu")
	)
	(gr_line
		(start 139.986258 -81.925668)
		(end 139.986258 -81.924906)
		(stroke
			(width 0.2)
			(type default)
		)
		(layer "In4.Cu")
	)
	(gr_line
		(start 139.986258 -81.924906)
		(end 138.843512 -81.924906)
		(stroke
			(width 0.2)
			(type default)
		)
		(layer "In4.Cu")
	)
	(gr_arc
		(start 140.173456 -61.576712)
		(mid 140.62837 -61.122179)
		(end 140.17371 -60.667392)
		(stroke
			(width 0.2)
			(type default)
		)
		(layer "In4.Cu")
	)
	(gr_line
		(start 140.17371 -60.667392)
		(end 139.03071 -60.667392)
		(stroke
			(width 0.2)
			(type default)
		)
		(layer "In4.Cu")
	)
	(gr_line
		(start 140.561314 -12.400026)
		(end 140.561314 -10.999978)
		(stroke
			(width 0.2)
			(type default)
		)
		(layer "In4.Cu")
	)
	(gr_arc
		(start 140.561314 -10.999978)
		(mid 139.999974 -10.438638)
		(end 139.438634 -10.999978)
		(stroke
			(width 0.2)
			(type default)
		)
		(layer "In4.Cu")
	)
	(gr_line
		(start 140.561314 -5.200142)
		(end 140.561314 -3.800094)
		(stroke
			(width 0.2)
			(type default)
		)
		(layer "In4.Cu")
	)
	(gr_arc
		(start 140.561314 -3.800094)
		(mid 139.999974 -3.238754)
		(end 139.438634 -3.800094)
		(stroke
			(width 0.2)
			(type default)
		)
		(layer "In4.Cu")
	)
	(gr_arc
		(start 140.588746 -59.35726)
		(mid 141.04366 -58.902727)
		(end 140.589 -58.44794)
		(stroke
			(width 0.2)
			(type default)
		)
		(layer "In4.Cu")
	)
	(gr_line
		(start 140.589 -58.44794)
		(end 139.446 -58.44794)
		(stroke
			(width 0.2)
			(type default)
		)
		(layer "In4.Cu")
	)
	(gr_line
		(start 140.97 -77.47)
		(end 142.1384 -76.3016)
		(stroke
			(width 0.381)
			(type default)
		)
		(layer "In4.Cu")
	)
	(gr_arc
		(start 141.238732 -11.199876)
		(mid 141.799945 -11.76147)
		(end 142.361412 -11.20013)
		(stroke
			(width 0.2)
			(type default)
		)
		(layer "In4.Cu")
	)
	(gr_line
		(start 141.238732 -9.800082)
		(end 141.238732 -11.199876)
		(stroke
			(width 0.2)
			(type default)
		)
		(layer "In4.Cu")
	)
	(gr_arc
		(start 141.238732 -3.999738)
		(mid 141.799945 -4.561332)
		(end 142.361412 -3.999992)
		(stroke
			(width 0.2)
			(type default)
		)
		(layer "In4.Cu")
	)
	(gr_line
		(start 141.238732 -2.600198)
		(end 141.238732 -3.999738)
		(stroke
			(width 0.2)
			(type default)
		)
		(layer "In4.Cu")
	)
	(gr_line
		(start 142.1384 -76.3016)
		(end 142.1384 -47.3964)
		(stroke
			(width 0.381)
			(type default)
		)
		(layer "In4.Cu")
	)
	(gr_line
		(start 142.1384 -47.3964)
		(end 143.1036 -46.4312)
		(stroke
			(width 0.381)
			(type default)
		)
		(layer "In4.Cu")
	)
	(gr_line
		(start 142.361412 -11.20013)
		(end 142.361412 -9.800082)
		(stroke
			(width 0.2)
			(type default)
		)
		(layer "In4.Cu")
	)
	(gr_arc
		(start 142.361412 -9.800082)
		(mid 141.800072 -9.238742)
		(end 141.238732 -9.800082)
		(stroke
			(width 0.2)
			(type default)
		)
		(layer "In4.Cu")
	)
	(gr_line
		(start 142.361412 -3.999992)
		(end 142.361412 -2.600198)
		(stroke
			(width 0.2)
			(type default)
		)
		(layer "In4.Cu")
	)
	(gr_arc
		(start 142.361412 -2.600198)
		(mid 141.800072 -2.038858)
		(end 141.238732 -2.600198)
		(stroke
			(width 0.2)
			(type default)
		)
		(layer "In4.Cu")
	)
	(gr_circle
		(center 142.369794 -95.634048)
		(end 142.370048 -95.634048)
		(stroke
			(width 0.381)
			(type default)
		)
		(fill no)
		(layer "In4.Cu")
	)
	(gr_line
		(start 142.369794 -95.633794)
		(end 119.941594 -95.633794)
		(stroke
			(width 0.381)
			(type default)
		)
		(layer "In4.Cu")
	)
	(gr_line
		(start 142.621 -30.226)
		(end 143.1036 -30.7086)
		(stroke
			(width 0.381)
			(type default)
		)
		(layer "In4.Cu")
	)
	(gr_line
		(start 142.621 -30.226)
		(end 143.1036 -29.7434)
		(stroke
			(width 0.381)
			(type default)
		)
		(layer "In4.Cu")
	)
	(gr_arc
		(start 143.03883 -12.399772)
		(mid 143.600043 -12.961366)
		(end 144.16151 -12.400026)
		(stroke
			(width 0.2)
			(type default)
		)
		(layer "In4.Cu")
	)
	(gr_line
		(start 143.03883 -10.999978)
		(end 143.03883 -12.399772)
		(stroke
			(width 0.2)
			(type default)
		)
		(layer "In4.Cu")
	)
	(gr_arc
		(start 143.03883 -5.199888)
		(mid 143.600043 -5.761482)
		(end 144.16151 -5.200142)
		(stroke
			(width 0.2)
			(type default)
		)
		(layer "In4.Cu")
	)
	(gr_line
		(start 143.03883 -3.800094)
		(end 143.03883 -5.199888)
		(stroke
			(width 0.2)
			(type default)
		)
		(layer "In4.Cu")
	)
	(gr_line
		(start 143.1036 -46.4312)
		(end 143.1036 -30.226)
		(stroke
			(width 0.381)
			(type default)
		)
		(layer "In4.Cu")
	)
	(gr_line
		(start 143.1036 -30.226)
		(end 88.5952 -30.226)
		(stroke
			(width 0.381)
			(type default)
		)
		(layer "In4.Cu")
	)
	(gr_line
		(start 143.1036 -30.226)
		(end 143.1036 -25.85085)
		(stroke
			(width 0.381)
			(type default)
		)
		(layer "In4.Cu")
	)
	(gr_line
		(start 143.1036 -25.85085)
		(end 150.909274 -18.045176)
		(stroke
			(width 0.381)
			(type default)
		)
		(layer "In4.Cu")
	)
	(gr_line
		(start 144.16151 -12.400026)
		(end 144.16151 -10.999978)
		(stroke
			(width 0.2)
			(type default)
		)
		(layer "In4.Cu")
	)
	(gr_arc
		(start 144.16151 -10.999978)
		(mid 143.60017 -10.438638)
		(end 143.03883 -10.999978)
		(stroke
			(width 0.2)
			(type default)
		)
		(layer "In4.Cu")
	)
	(gr_line
		(start 144.16151 -5.200142)
		(end 144.16151 -3.800094)
		(stroke
			(width 0.2)
			(type default)
		)
		(layer "In4.Cu")
	)
	(gr_arc
		(start 144.16151 -3.800094)
		(mid 143.60017 -3.238754)
		(end 143.03883 -3.800094)
		(stroke
			(width 0.2)
			(type default)
		)
		(layer "In4.Cu")
	)
	(gr_arc
		(start 144.838674 -11.199876)
		(mid 145.399887 -11.76147)
		(end 145.961354 -11.20013)
		(stroke
			(width 0.2)
			(type default)
		)
		(layer "In4.Cu")
	)
	(gr_line
		(start 144.838674 -9.800082)
		(end 144.838674 -11.199876)
		(stroke
			(width 0.2)
			(type default)
		)
		(layer "In4.Cu")
	)
	(gr_arc
		(start 144.838674 -3.999738)
		(mid 145.399887 -4.561332)
		(end 145.961354 -3.999992)
		(stroke
			(width 0.2)
			(type default)
		)
		(layer "In4.Cu")
	)
	(gr_line
		(start 144.838674 -2.600198)
		(end 144.838674 -3.999738)
		(stroke
			(width 0.2)
			(type default)
		)
		(layer "In4.Cu")
	)
	(gr_arc
		(start 145.839434 -33.377886)
		(mid 146.191732 -33.920176)
		(end 146.734022 -33.567878)
		(stroke
			(width 0.2)
			(type default)
		)
		(layer "In4.Cu")
	)
	(gr_line
		(start 145.961354 -11.20013)
		(end 145.961354 -9.800082)
		(stroke
			(width 0.2)
			(type default)
		)
		(layer "In4.Cu")
	)
	(gr_arc
		(start 145.961354 -9.800082)
		(mid 145.400014 -9.238742)
		(end 144.838674 -9.800082)
		(stroke
			(width 0.2)
			(type default)
		)
		(layer "In4.Cu")
	)
	(gr_line
		(start 145.961354 -3.999992)
		(end 145.961354 -2.600198)
		(stroke
			(width 0.2)
			(type default)
		)
		(layer "In4.Cu")
	)
	(gr_arc
		(start 145.961354 -2.600198)
		(mid 145.400014 -2.038858)
		(end 144.838674 -2.600198)
		(stroke
			(width 0.2)
			(type default)
		)
		(layer "In4.Cu")
	)
	(gr_line
		(start 146.077178 -32.259778)
		(end 145.839434 -33.377886)
		(stroke
			(width 0.2)
			(type default)
		)
		(layer "In4.Cu")
	)
	(gr_line
		(start 146.304 -55.0926)
		(end 148.1328 -56.9214)
		(stroke
			(width 0.381)
			(type default)
		)
		(layer "In4.Cu")
	)
	(gr_line
		(start 146.304 -35.5854)
		(end 146.304 -55.0926)
		(stroke
			(width 0.381)
			(type default)
		)
		(layer "In4.Cu")
	)
	(gr_arc
		(start 146.638772 -12.399772)
		(mid 147.199985 -12.961366)
		(end 147.761452 -12.400026)
		(stroke
			(width 0.2)
			(type default)
		)
		(layer "In4.Cu")
	)
	(gr_line
		(start 146.638772 -10.999978)
		(end 146.638772 -12.399772)
		(stroke
			(width 0.2)
			(type default)
		)
		(layer "In4.Cu")
	)
	(gr_arc
		(start 146.638772 -5.199888)
		(mid 147.199985 -5.761482)
		(end 147.761452 -5.200142)
		(stroke
			(width 0.2)
			(type default)
		)
		(layer "In4.Cu")
	)
	(gr_line
		(start 146.638772 -3.800094)
		(end 146.638772 -5.199888)
		(stroke
			(width 0.2)
			(type default)
		)
		(layer "In4.Cu")
	)
	(gr_line
		(start 146.734022 -33.567878)
		(end 146.969226 -32.460184)
		(stroke
			(width 0.2)
			(type default)
		)
		(layer "In4.Cu")
	)
	(gr_arc
		(start 146.859752 -47.469298)
		(mid 147.21205 -48.011588)
		(end 147.75434 -47.65929)
		(stroke
			(width 0.2)
			(type default)
		)
		(layer "In4.Cu")
	)
	(gr_arc
		(start 146.969226 -32.460184)
		(mid 146.624662 -31.908815)
		(end 146.077178 -32.259778)
		(stroke
			(width 0.2)
			(type default)
		)
		(layer "In4.Cu")
	)
	(gr_line
		(start 147.097496 -46.35119)
		(end 146.859752 -47.469298)
		(stroke
			(width 0.2)
			(type default)
		)
		(layer "In4.Cu")
	)
	(gr_line
		(start 147.3708 -34.5186)
		(end 146.304 -35.5854)
		(stroke
			(width 0.381)
			(type default)
		)
		(layer "In4.Cu")
	)
	(gr_line
		(start 147.3708 -28.00858)
		(end 147.3708 -34.5186)
		(stroke
			(width 0.381)
			(type default)
		)
		(layer "In4.Cu")
	)
	(gr_line
		(start 147.75434 -47.65929)
		(end 147.989544 -46.551596)
		(stroke
			(width 0.2)
			(type default)
		)
		(layer "In4.Cu")
	)
	(gr_line
		(start 147.761452 -12.400026)
		(end 147.761452 -10.999978)
		(stroke
			(width 0.2)
			(type default)
		)
		(layer "In4.Cu")
	)
	(gr_arc
		(start 147.761452 -10.999978)
		(mid 147.200112 -10.438638)
		(end 146.638772 -10.999978)
		(stroke
			(width 0.2)
			(type default)
		)
		(layer "In4.Cu")
	)
	(gr_line
		(start 147.761452 -5.200142)
		(end 147.761452 -3.800094)
		(stroke
			(width 0.2)
			(type default)
		)
		(layer "In4.Cu")
	)
	(gr_arc
		(start 147.761452 -3.800094)
		(mid 147.200112 -3.238754)
		(end 146.638772 -3.800094)
		(stroke
			(width 0.2)
			(type default)
		)
		(layer "In4.Cu")
	)
	(gr_arc
		(start 147.907502 -51.437794)
		(mid 148.2598 -51.980084)
		(end 148.80209 -51.627786)
		(stroke
			(width 0.2)
			(type default)
		)
		(layer "In4.Cu")
	)
	(gr_arc
		(start 147.989544 -46.551596)
		(mid 147.64498 -46.000227)
		(end 147.097496 -46.35119)
		(stroke
			(width 0.2)
			(type default)
		)
		(layer "In4.Cu")
	)
	(gr_line
		(start 148.1328 -77.216)
		(end 150.9776 -80.0608)
		(stroke
			(width 0.381)
			(type default)
		)
		(layer "In4.Cu")
	)
	(gr_line
		(start 148.1328 -56.9214)
		(end 148.1328 -77.216)
		(stroke
			(width 0.381)
			(type default)
		)
		(layer "In4.Cu")
	)
	(gr_line
		(start 148.145246 -50.319686)
		(end 147.907502 -51.437794)
		(stroke
			(width 0.2)
			(type default)
		)
		(layer "In4.Cu")
	)
	(gr_arc
		(start 148.179536 -41.25849)
		(mid 148.531834 -41.80078)
		(end 149.074124 -41.448482)
		(stroke
			(width 0.2)
			(type default)
		)
		(layer "In4.Cu")
	)
	(gr_line
		(start 148.41728 -40.140382)
		(end 148.179536 -41.25849)
		(stroke
			(width 0.2)
			(type default)
		)
		(layer "In4.Cu")
	)
	(gr_arc
		(start 148.438616 -11.199876)
		(mid 148.999829 -11.76147)
		(end 149.561296 -11.20013)
		(stroke
			(width 0.2)
			(type default)
		)
		(layer "In4.Cu")
	)
	(gr_line
		(start 148.438616 -9.800082)
		(end 148.438616 -11.199876)
		(stroke
			(width 0.2)
			(type default)
		)
		(layer "In4.Cu")
	)
	(gr_arc
		(start 148.438616 -3.999738)
		(mid 148.999829 -4.561332)
		(end 149.561296 -3.999992)
		(stroke
			(width 0.2)
			(type default)
		)
		(layer "In4.Cu")
	)
	(gr_line
		(start 148.438616 -2.600198)
		(end 148.438616 -3.999738)
		(stroke
			(width 0.2)
			(type default)
		)
		(layer "In4.Cu")
	)
	(gr_arc
		(start 148.684742 -36.130992)
		(mid 149.03704 -36.673282)
		(end 149.57933 -36.320984)
		(stroke
			(width 0.2)
			(type default)
		)
		(layer "In4.Cu")
	)
	(gr_line
		(start 148.80209 -51.627786)
		(end 149.037294 -50.520092)
		(stroke
			(width 0.2)
			(type default)
		)
		(layer "In4.Cu")
	)
	(gr_line
		(start 148.9202 -102.1842)
		(end 142.369794 -95.633794)
		(stroke
			(width 0.381)
			(type default)
		)
		(layer "In4.Cu")
	)
	(gr_line
		(start 148.922486 -35.012884)
		(end 148.684742 -36.130992)
		(stroke
			(width 0.2)
			(type default)
		)
		(layer "In4.Cu")
	)
	(gr_arc
		(start 148.957792 -55.395876)
		(mid 149.302356 -55.947245)
		(end 149.84984 -55.596282)
		(stroke
			(width 0.2)
			(type default)
		)
		(layer "In4.Cu")
	)
	(gr_arc
		(start 149.037294 -50.520092)
		(mid 148.69273 -49.968723)
		(end 148.145246 -50.319686)
		(stroke
			(width 0.2)
			(type default)
		)
		(layer "In4.Cu")
	)
	(gr_line
		(start 149.074124 -41.448482)
		(end 149.309328 -40.340788)
		(stroke
			(width 0.2)
			(type default)
		)
		(layer "In4.Cu")
	)
	(gr_arc
		(start 149.100286 -45.226986)
		(mid 149.452584 -45.769276)
		(end 149.994874 -45.416978)
		(stroke
			(width 0.2)
			(type default)
		)
		(layer "In4.Cu")
	)
	(gr_line
		(start 149.192996 -54.288182)
		(end 148.957792 -55.395876)
		(stroke
			(width 0.2)
			(type default)
		)
		(layer "In4.Cu")
	)
	(gr_arc
		(start 149.309328 -40.340788)
		(mid 148.964764 -39.789419)
		(end 148.41728 -40.140382)
		(stroke
			(width 0.2)
			(type default)
		)
		(layer "In4.Cu")
	)
	(gr_line
		(start 149.33803 -44.108878)
		(end 149.100286 -45.226986)
		(stroke
			(width 0.2)
			(type default)
		)
		(layer "In4.Cu")
	)
	(gr_line
		(start 149.561296 -11.20013)
		(end 149.561296 -9.800082)
		(stroke
			(width 0.2)
			(type default)
		)
		(layer "In4.Cu")
	)
	(gr_arc
		(start 149.561296 -9.800082)
		(mid 148.999956 -9.238742)
		(end 148.438616 -9.800082)
		(stroke
			(width 0.2)
			(type default)
		)
		(layer "In4.Cu")
	)
	(gr_line
		(start 149.561296 -3.999992)
		(end 149.561296 -2.600198)
		(stroke
			(width 0.2)
			(type default)
		)
		(layer "In4.Cu")
	)
	(gr_arc
		(start 149.561296 -2.600198)
		(mid 148.999956 -2.038858)
		(end 148.438616 -2.600198)
		(stroke
			(width 0.2)
			(type default)
		)
		(layer "In4.Cu")
	)
	(gr_line
		(start 149.57933 -36.320984)
		(end 149.814534 -35.21329)
		(stroke
			(width 0.2)
			(type default)
		)
		(layer "In4.Cu")
	)
	(gr_arc
		(start 149.814534 -35.21329)
		(mid 149.46997 -34.661921)
		(end 148.922486 -35.012884)
		(stroke
			(width 0.2)
			(type default)
		)
		(layer "In4.Cu")
	)
	(gr_line
		(start 149.84984 -55.596282)
		(end 150.087584 -54.478174)
		(stroke
			(width 0.2)
			(type default)
		)
		(layer "In4.Cu")
	)
	(gr_line
		(start 149.994874 -45.416978)
		(end 150.230078 -44.309284)
		(stroke
			(width 0.2)
			(type default)
		)
		(layer "In4.Cu")
	)
	(gr_arc
		(start 150.087584 -54.478174)
		(mid 149.735286 -53.935884)
		(end 149.192996 -54.288182)
		(stroke
			(width 0.2)
			(type default)
		)
		(layer "In4.Cu")
	)
	(gr_arc
		(start 150.230078 -44.309284)
		(mid 149.885514 -43.757915)
		(end 149.33803 -44.108878)
		(stroke
			(width 0.2)
			(type default)
		)
		(layer "In4.Cu")
	)
	(gr_arc
		(start 150.54707 -39.016178)
		(mid 150.899368 -39.558468)
		(end 151.441658 -39.20617)
		(stroke
			(width 0.2)
			(type default)
		)
		(layer "In4.Cu")
	)
	(gr_line
		(start 150.784814 -37.89807)
		(end 150.54707 -39.016178)
		(stroke
			(width 0.2)
			(type default)
		)
		(layer "In4.Cu")
	)
	(gr_line
		(start 150.909274 -18.045176)
		(end 150.909274 -4.149344)
		(stroke
			(width 0.381)
			(type default)
		)
		(layer "In4.Cu")
	)
	(gr_line
		(start 150.909274 -4.149344)
		(end 152.120854 -2.937764)
		(stroke
			(width 0.381)
			(type default)
		)
		(layer "In4.Cu")
	)
	(gr_line
		(start 150.9776 -86.4616)
		(end 151.6634 -87.1474)
		(stroke
			(width 0.381)
			(type default)
		)
		(layer "In4.Cu")
	)
	(gr_line
		(start 150.9776 -80.0608)
		(end 150.9776 -86.4616)
		(stroke
			(width 0.381)
			(type default)
		)
		(layer "In4.Cu")
	)
	(gr_line
		(start 151.441658 -39.20617)
		(end 151.676862 -38.098476)
		(stroke
			(width 0.2)
			(type default)
		)
		(layer "In4.Cu")
	)
	(gr_line
		(start 151.6634 -87.1474)
		(end 155.702 -87.1474)
		(stroke
			(width 0.381)
			(type default)
		)
		(layer "In4.Cu")
	)
	(gr_arc
		(start 151.676862 -38.098476)
		(mid 151.332298 -37.547107)
		(end 150.784814 -37.89807)
		(stroke
			(width 0.2)
			(type default)
		)
		(layer "In4.Cu")
	)
	(gr_line
		(start 152.120854 -2.937764)
		(end 167.963596 -2.937764)
		(stroke
			(width 0.381)
			(type default)
		)
		(layer "In4.Cu")
	)
	(gr_line
		(start 153.416 -110.1598)
		(end 136.857232 -110.1598)
		(stroke
			(width 0.381)
			(type default)
		)
		(layer "In4.Cu")
	)
	(gr_line
		(start 154.820874 -20.558506)
		(end 147.3708 -28.00858)
		(stroke
			(width 0.381)
			(type default)
		)
		(layer "In4.Cu")
	)
	(gr_line
		(start 154.820874 -7.173722)
		(end 154.820874 -20.558506)
		(stroke
			(width 0.381)
			(type default)
		)
		(layer "In4.Cu")
	)
	(gr_line
		(start 155.4734 -6.521196)
		(end 154.820874 -7.173722)
		(stroke
			(width 0.381)
			(type default)
		)
		(layer "In4.Cu")
	)
	(gr_line
		(start 155.702 -87.1474)
		(end 163.7538 -95.1992)
		(stroke
			(width 0.381)
			(type default)
		)
		(layer "In4.Cu")
	)
	(gr_line
		(start 155.702 -81.3308)
		(end 155.702 -26.416)
		(stroke
			(width 0.381)
			(type default)
		)
		(layer "In4.Cu")
	)
	(gr_line
		(start 155.702 -26.416)
		(end 156.609542 -25.508458)
		(stroke
			(width 0.381)
			(type default)
		)
		(layer "In4.Cu")
	)
	(gr_line
		(start 156.1084 -107.4674)
		(end 153.416 -110.1598)
		(stroke
			(width 0.381)
			(type default)
		)
		(layer "In4.Cu")
	)
	(gr_line
		(start 156.609542 -25.508458)
		(end 178.086258 -25.508458)
		(stroke
			(width 0.381)
			(type default)
		)
		(layer "In4.Cu")
	)
	(gr_line
		(start 156.8958 -82.5246)
		(end 155.702 -81.3308)
		(stroke
			(width 0.381)
			(type default)
		)
		(layer "In4.Cu")
	)
	(gr_line
		(start 161.036 -102.1842)
		(end 148.9202 -102.1842)
		(stroke
			(width 0.381)
			(type default)
		)
		(layer "In4.Cu")
	)
	(gr_line
		(start 163.068 -107.4674)
		(end 156.1084 -107.4674)
		(stroke
			(width 0.381)
			(type default)
		)
		(layer "In4.Cu")
	)
	(gr_line
		(start 163.7538 -99.4664)
		(end 161.036 -102.1842)
		(stroke
			(width 0.381)
			(type default)
		)
		(layer "In4.Cu")
	)
	(gr_line
		(start 163.7538 -95.1992)
		(end 163.7538 -99.4664)
		(stroke
			(width 0.381)
			(type default)
		)
		(layer "In4.Cu")
	)
	(gr_line
		(start 163.7792 -99.0854)
		(end 164.1348 -99.441)
		(stroke
			(width 0.381)
			(type default)
		)
		(layer "In4.Cu")
	)
	(gr_line
		(start 164.9984 -64.1858)
		(end 175.5648 -74.7522)
		(stroke
			(width 0.381)
			(type default)
		)
		(layer "In4.Cu")
	)
	(gr_line
		(start 164.9984 -41.260014)
		(end 164.9984 -64.1858)
		(stroke
			(width 0.381)
			(type default)
		)
		(layer "In4.Cu")
	)
	(gr_arc
		(start 165.005766 -41.242234)
		(mid 165.000369 -41.250406)
		(end 164.9984 -41.260014)
		(stroke
			(width 0.381)
			(type default)
		)
		(layer "In4.Cu")
	)
	(gr_line
		(start 165.399974 -37.183568)
		(end 166.199566 -37.183568)
		(stroke
			(width 0.2)
			(type default)
		)
		(layer "In4.Cu")
	)
	(gr_arc
		(start 165.399974 -36.416488)
		(mid 165.016434 -36.800028)
		(end 165.399974 -37.183568)
		(stroke
			(width 0.2)
			(type default)
		)
		(layer "In4.Cu")
	)
	(gr_line
		(start 165.399974 -34.783522)
		(end 166.199566 -34.783522)
		(stroke
			(width 0.2)
			(type default)
		)
		(layer "In4.Cu")
	)
	(gr_arc
		(start 165.399974 -34.016442)
		(mid 165.016434 -34.399982)
		(end 165.399974 -34.783522)
		(stroke
			(width 0.2)
			(type default)
		)
		(layer "In4.Cu")
	)
	(gr_line
		(start 165.4556 -40.7924)
		(end 165.005766 -41.242234)
		(stroke
			(width 0.381)
			(type default)
		)
		(layer "In4.Cu")
	)
	(gr_line
		(start 165.7096 -104.8258)
		(end 163.068 -107.4674)
		(stroke
			(width 0.381)
			(type default)
		)
		(layer "In4.Cu")
	)
	(gr_arc
		(start 165.741858 -24.055578)
		(mid 166.125271 -24.439372)
		(end 166.508938 -24.055832)
		(stroke
			(width 0.2)
			(type default)
		)
		(layer "In4.Cu")
	)
	(gr_line
		(start 165.741858 -23.166832)
		(end 165.741858 -24.055578)
		(stroke
			(width 0.2)
			(type default)
		)
		(layer "In4.Cu")
	)
	(gr_arc
		(start 165.81628 -38.399974)
		(mid 166.19982 -38.783514)
		(end 166.58336 -38.399974)
		(stroke
			(width 0.2)
			(type default)
		)
		(layer "In4.Cu")
	)
	(gr_line
		(start 165.81628 -37.599874)
		(end 165.81628 -38.399974)
		(stroke
			(width 0.2)
			(type default)
		)
		(layer "In4.Cu")
	)
	(gr_arc
		(start 165.81628 -35.999928)
		(mid 166.19982 -36.383468)
		(end 166.58336 -35.999928)
		(stroke
			(width 0.2)
			(type default)
		)
		(layer "In4.Cu")
	)
	(gr_line
		(start 165.81628 -35.199828)
		(end 165.81628 -35.999928)
		(stroke
			(width 0.2)
			(type default)
		)
		(layer "In4.Cu")
	)
	(gr_arc
		(start 165.81628 -33.599882)
		(mid 166.19982 -33.983422)
		(end 166.58336 -33.599882)
		(stroke
			(width 0.2)
			(type default)
		)
		(layer "In4.Cu")
	)
	(gr_line
		(start 165.81628 -32.800036)
		(end 165.81628 -33.599882)
		(stroke
			(width 0.2)
			(type default)
		)
		(layer "In4.Cu")
	)
	(gr_arc
		(start 165.81628 -31.199836)
		(mid 166.19982 -31.583376)
		(end 166.58336 -31.199836)
		(stroke
			(width 0.2)
			(type default)
		)
		(layer "In4.Cu")
	)
	(gr_line
		(start 165.81628 -30.39999)
		(end 165.81628 -31.199836)
		(stroke
			(width 0.2)
			(type default)
		)
		(layer "In4.Cu")
	)
	(gr_arc
		(start 166.199566 -37.183568)
		(mid 166.58336 -36.800155)
		(end 166.19982 -36.416488)
		(stroke
			(width 0.2)
			(type default)
		)
		(layer "In4.Cu")
	)
	(gr_arc
		(start 166.199566 -34.783522)
		(mid 166.58336 -34.400109)
		(end 166.19982 -34.016442)
		(stroke
			(width 0.2)
			(type default)
		)
		(layer "In4.Cu")
	)
	(gr_line
		(start 166.19982 -36.416488)
		(end 165.399974 -36.416488)
		(stroke
			(width 0.2)
			(type default)
		)
		(layer "In4.Cu")
	)
	(gr_line
		(start 166.19982 -34.016442)
		(end 165.399974 -34.016442)
		(stroke
			(width 0.2)
			(type default)
		)
		(layer "In4.Cu")
	)
	(gr_line
		(start 166.19982 -29.98343)
		(end 166.999412 -29.983684)
		(stroke
			(width 0.2)
			(type default)
		)
		(layer "In4.Cu")
	)
	(gr_line
		(start 166.200074 -32.383476)
		(end 166.999666 -32.383476)
		(stroke
			(width 0.2)
			(type default)
		)
		(layer "In4.Cu")
	)
	(gr_arc
		(start 166.200074 -31.616396)
		(mid 165.816534 -31.999936)
		(end 166.200074 -32.383476)
		(stroke
			(width 0.2)
			(type default)
		)
		(layer "In4.Cu")
	)
	(gr_arc
		(start 166.200074 -29.21635)
		(mid 165.81628 -29.599763)
		(end 166.19982 -29.98343)
		(stroke
			(width 0.2)
			(type default)
		)
		(layer "In4.Cu")
	)
	(gr_line
		(start 166.508938 -24.055832)
		(end 166.508938 -23.166832)
		(stroke
			(width 0.2)
			(type default)
		)
		(layer "In4.Cu")
	)
	(gr_arc
		(start 166.508938 -23.166832)
		(mid 166.125398 -22.783292)
		(end 165.741858 -23.166832)
		(stroke
			(width 0.2)
			(type default)
		)
		(layer "In4.Cu")
	)
	(gr_line
		(start 166.58336 -38.399974)
		(end 166.58336 -37.600128)
		(stroke
			(width 0.2)
			(type default)
		)
		(layer "In4.Cu")
	)
	(gr_arc
		(start 166.58336 -37.600128)
		(mid 166.199947 -37.216334)
		(end 165.81628 -37.599874)
		(stroke
			(width 0.2)
			(type default)
		)
		(layer "In4.Cu")
	)
	(gr_line
		(start 166.58336 -35.999928)
		(end 166.58336 -35.200082)
		(stroke
			(width 0.2)
			(type default)
		)
		(layer "In4.Cu")
	)
	(gr_arc
		(start 166.58336 -35.200082)
		(mid 166.199947 -34.816288)
		(end 165.81628 -35.199828)
		(stroke
			(width 0.2)
			(type default)
		)
		(layer "In4.Cu")
	)
	(gr_line
		(start 166.58336 -33.599882)
		(end 166.58336 -32.80029)
		(stroke
			(width 0.2)
			(type default)
		)
		(layer "In4.Cu")
	)
	(gr_arc
		(start 166.58336 -32.80029)
		(mid 166.199947 -32.416496)
		(end 165.81628 -32.800036)
		(stroke
			(width 0.2)
			(type default)
		)
		(layer "In4.Cu")
	)
	(gr_line
		(start 166.58336 -31.199836)
		(end 166.58336 -30.400244)
		(stroke
			(width 0.2)
			(type default)
		)
		(layer "In4.Cu")
	)
	(gr_arc
		(start 166.58336 -30.400244)
		(mid 166.199947 -30.01645)
		(end 165.81628 -30.39999)
		(stroke
			(width 0.2)
			(type default)
		)
		(layer "In4.Cu")
	)
	(gr_arc
		(start 166.999412 -29.983684)
		(mid 167.383206 -29.600271)
		(end 166.999666 -29.216604)
		(stroke
			(width 0.2)
			(type default)
		)
		(layer "In4.Cu")
	)
	(gr_arc
		(start 166.999666 -32.383476)
		(mid 167.38346 -32.000063)
		(end 166.99992 -31.616396)
		(stroke
			(width 0.2)
			(type default)
		)
		(layer "In4.Cu")
	)
	(gr_line
		(start 166.999666 -29.216604)
		(end 166.200074 -29.21635)
		(stroke
			(width 0.2)
			(type default)
		)
		(layer "In4.Cu")
	)
	(gr_line
		(start 166.99992 -31.616396)
		(end 166.200074 -31.616396)
		(stroke
			(width 0.2)
			(type default)
		)
		(layer "In4.Cu")
	)
	(gr_line
		(start 167.0304 -40.7924)
		(end 165.4556 -40.7924)
		(stroke
			(width 0.381)
			(type default)
		)
		(layer "In4.Cu")
	)
	(gr_line
		(start 167.169846 -6.521196)
		(end 155.4734 -6.521196)
		(stroke
			(width 0.381)
			(type default)
		)
		(layer "In4.Cu")
	)
	(gr_line
		(start 167.386 -40.4368)
		(end 167.0304 -40.7924)
		(stroke
			(width 0.381)
			(type default)
		)
		(layer "In4.Cu")
	)
	(gr_line
		(start 167.386 -35.1282)
		(end 167.386 -40.4368)
		(stroke
			(width 0.381)
			(type default)
		)
		(layer "In4.Cu")
	)
	(gr_line
		(start 167.441626 -30.400244)
		(end 167.44188 -31.199582)
		(stroke
			(width 0.2)
			(type default)
		)
		(layer "In4.Cu")
	)
	(gr_arc
		(start 167.44188 -31.199582)
		(mid 167.80002 -31.557976)
		(end 168.15816 -31.199582)
		(stroke
			(width 0.2)
			(type default)
		)
		(layer "In4.Cu")
	)
	(gr_line
		(start 167.658034 -34.856166)
		(end 167.386 -35.1282)
		(stroke
			(width 0.381)
			(type default)
		)
		(layer "In4.Cu")
	)
	(gr_arc
		(start 167.675814 -34.8488)
		(mid 167.666177 -34.850699)
		(end 167.658034 -34.856166)
		(stroke
			(width 0.381)
			(type default)
		)
		(layer "In4.Cu")
	)
	(gr_arc
		(start 167.776398 -24.012652)
		(mid 168.159811 -24.396446)
		(end 168.543478 -24.012906)
		(stroke
			(width 0.2)
			(type default)
		)
		(layer "In4.Cu")
	)
	(gr_line
		(start 167.776398 -23.123906)
		(end 167.776398 -24.012652)
		(stroke
			(width 0.2)
			(type default)
		)
		(layer "In4.Cu")
	)
	(gr_line
		(start 167.963596 -2.937764)
		(end 168.563036 -3.537204)
		(stroke
			(width 0.381)
			(type default)
		)
		(layer "In4.Cu")
	)
	(gr_arc
		(start 168.157906 -30.39999)
		(mid 167.799639 -30.04185)
		(end 167.441626 -30.400244)
		(stroke
			(width 0.2)
			(type default)
		)
		(layer "In4.Cu")
	)
	(gr_line
		(start 168.15816 -31.199582)
		(end 168.157906 -30.39999)
		(stroke
			(width 0.2)
			(type default)
		)
		(layer "In4.Cu")
	)
	(gr_arc
		(start 168.241726 -31.199582)
		(mid 168.599739 -31.557976)
		(end 168.958006 -31.199836)
		(stroke
			(width 0.2)
			(type default)
		)
		(layer "In4.Cu")
	)
	(gr_line
		(start 168.241726 -30.39999)
		(end 168.241726 -31.199582)
		(stroke
			(width 0.2)
			(type default)
		)
		(layer "In4.Cu")
	)
	(gr_line
		(start 168.543478 -24.012906)
		(end 168.543478 -23.123906)
		(stroke
			(width 0.2)
			(type default)
		)
		(layer "In4.Cu")
	)
	(gr_arc
		(start 168.543478 -23.123906)
		(mid 168.159938 -22.740366)
		(end 167.776398 -23.123906)
		(stroke
			(width 0.2)
			(type default)
		)
		(layer "In4.Cu")
	)
	(gr_line
		(start 168.563036 -5.128006)
		(end 167.169846 -6.521196)
		(stroke
			(width 0.381)
			(type default)
		)
		(layer "In4.Cu")
	)
	(gr_line
		(start 168.563036 -3.537204)
		(end 168.563036 -5.128006)
		(stroke
			(width 0.381)
			(type default)
		)
		(layer "In4.Cu")
	)
	(gr_line
		(start 168.958006 -31.199836)
		(end 168.958006 -30.39999)
		(stroke
			(width 0.2)
			(type default)
		)
		(layer "In4.Cu")
	)
	(gr_arc
		(start 168.958006 -30.39999)
		(mid 168.599866 -30.04185)
		(end 168.241726 -30.39999)
		(stroke
			(width 0.2)
			(type default)
		)
		(layer "In4.Cu")
	)
	(gr_arc
		(start 169.833544 -24.004016)
		(mid 170.216957 -24.38781)
		(end 170.600624 -24.00427)
		(stroke
			(width 0.2)
			(type default)
		)
		(layer "In4.Cu")
	)
	(gr_line
		(start 169.833544 -23.11527)
		(end 169.833544 -24.004016)
		(stroke
			(width 0.2)
			(type default)
		)
		(layer "In4.Cu")
	)
	(gr_line
		(start 169.841672 -30.400244)
		(end 169.841926 -31.199836)
		(stroke
			(width 0.2)
			(type default)
		)
		(layer "In4.Cu")
	)
	(gr_arc
		(start 169.841926 -31.199836)
		(mid 170.200066 -31.55823)
		(end 170.558206 -31.199836)
		(stroke
			(width 0.2)
			(type default)
		)
		(layer "In4.Cu")
	)
	(gr_arc
		(start 170.557952 -30.39999)
		(mid 170.199685 -30.04185)
		(end 169.841672 -30.400244)
		(stroke
			(width 0.2)
			(type default)
		)
		(layer "In4.Cu")
	)
	(gr_line
		(start 170.558206 -31.199836)
		(end 170.557952 -30.39999)
		(stroke
			(width 0.2)
			(type default)
		)
		(layer "In4.Cu")
	)
	(gr_line
		(start 170.600624 -24.00427)
		(end 170.600624 -23.11527)
		(stroke
			(width 0.2)
			(type default)
		)
		(layer "In4.Cu")
	)
	(gr_arc
		(start 170.600624 -23.11527)
		(mid 170.217084 -22.73173)
		(end 169.833544 -23.11527)
		(stroke
			(width 0.2)
			(type default)
		)
		(layer "In4.Cu")
	)
	(gr_line
		(start 170.641772 -30.400244)
		(end 170.642026 -31.199836)
		(stroke
			(width 0.2)
			(type default)
		)
		(layer "In4.Cu")
	)
	(gr_arc
		(start 170.642026 -31.199836)
		(mid 171.000166 -31.55823)
		(end 171.358306 -31.199836)
		(stroke
			(width 0.2)
			(type default)
		)
		(layer "In4.Cu")
	)
	(gr_arc
		(start 171.358052 -30.39999)
		(mid 170.999785 -30.04185)
		(end 170.641772 -30.400244)
		(stroke
			(width 0.2)
			(type default)
		)
		(layer "In4.Cu")
	)
	(gr_line
		(start 171.358306 -31.199836)
		(end 171.358052 -30.39999)
		(stroke
			(width 0.2)
			(type default)
		)
		(layer "In4.Cu")
	)
	(gr_line
		(start 171.7294 -99.4664)
		(end 163.7538 -99.4664)
		(stroke
			(width 0.381)
			(type default)
		)
		(layer "In4.Cu")
	)
	(gr_arc
		(start 171.88561 -24.00173)
		(mid 172.269023 -24.385524)
		(end 172.65269 -24.001984)
		(stroke
			(width 0.2)
			(type default)
		)
		(layer "In4.Cu")
	)
	(gr_line
		(start 171.88561 -23.112984)
		(end 171.88561 -24.00173)
		(stroke
			(width 0.2)
			(type default)
		)
		(layer "In4.Cu")
	)
	(gr_line
		(start 172.241718 -30.400244)
		(end 172.241972 -31.199836)
		(stroke
			(width 0.2)
			(type default)
		)
		(layer "In4.Cu")
	)
	(gr_arc
		(start 172.241972 -31.199836)
		(mid 172.600112 -31.55823)
		(end 172.958252 -31.199836)
		(stroke
			(width 0.2)
			(type default)
		)
		(layer "In4.Cu")
	)
	(gr_line
		(start 172.65269 -24.001984)
		(end 172.65269 -23.112984)
		(stroke
			(width 0.2)
			(type default)
		)
		(layer "In4.Cu")
	)
	(gr_arc
		(start 172.65269 -23.112984)
		(mid 172.26915 -22.729444)
		(end 171.88561 -23.112984)
		(stroke
			(width 0.2)
			(type default)
		)
		(layer "In4.Cu")
	)
	(gr_arc
		(start 172.957998 -30.39999)
		(mid 172.599731 -30.04185)
		(end 172.241718 -30.400244)
		(stroke
			(width 0.2)
			(type default)
		)
		(layer "In4.Cu")
	)
	(gr_line
		(start 172.958252 -31.199836)
		(end 172.957998 -30.39999)
		(stroke
			(width 0.2)
			(type default)
		)
		(layer "In4.Cu")
	)
	(gr_line
		(start 173.041818 -30.400244)
		(end 173.042072 -31.199836)
		(stroke
			(width 0.2)
			(type default)
		)
		(layer "In4.Cu")
	)
	(gr_arc
		(start 173.042072 -31.199836)
		(mid 173.400212 -31.55823)
		(end 173.758352 -31.199836)
		(stroke
			(width 0.2)
			(type default)
		)
		(layer "In4.Cu")
	)
	(gr_arc
		(start 173.758098 -30.39999)
		(mid 173.399831 -30.04185)
		(end 173.041818 -30.400244)
		(stroke
			(width 0.2)
			(type default)
		)
		(layer "In4.Cu")
	)
	(gr_line
		(start 173.758352 -31.199836)
		(end 173.758098 -30.39999)
		(stroke
			(width 0.2)
			(type default)
		)
		(layer "In4.Cu")
	)
	(gr_arc
		(start 173.931326 -24.001222)
		(mid 174.314739 -24.385016)
		(end 174.698406 -24.001476)
		(stroke
			(width 0.2)
			(type default)
		)
		(layer "In4.Cu")
	)
	(gr_line
		(start 173.931326 -23.112476)
		(end 173.931326 -24.001222)
		(stroke
			(width 0.2)
			(type default)
		)
		(layer "In4.Cu")
	)
	(gr_line
		(start 174.641764 -30.400244)
		(end 174.642018 -31.199836)
		(stroke
			(width 0.2)
			(type default)
		)
		(layer "In4.Cu")
	)
	(gr_arc
		(start 174.642018 -31.199836)
		(mid 175.000158 -31.55823)
		(end 175.358298 -31.199836)
		(stroke
			(width 0.2)
			(type default)
		)
		(layer "In4.Cu")
	)
	(gr_line
		(start 174.698406 -24.001476)
		(end 174.698406 -23.112476)
		(stroke
			(width 0.2)
			(type default)
		)
		(layer "In4.Cu")
	)
	(gr_arc
		(start 174.698406 -23.112476)
		(mid 174.314866 -22.728936)
		(end 173.931326 -23.112476)
		(stroke
			(width 0.2)
			(type default)
		)
		(layer "In4.Cu")
	)
	(gr_arc
		(start 175.158654 -82.549746)
		(mid 175.158442 -82.55)
		(end 175.158654 -82.550254)
		(stroke
			(width 0.381)
			(type default)
		)
		(layer "In4.Cu")
	)
	(gr_line
		(start 175.158654 -82.549746)
		(end 175.4886 -82.2198)
		(stroke
			(width 0.381)
			(type default)
		)
		(layer "In4.Cu")
	)
	(gr_arc
		(start 175.358044 -30.39999)
		(mid 174.999777 -30.04185)
		(end 174.641764 -30.400244)
		(stroke
			(width 0.2)
			(type default)
		)
		(layer "In4.Cu")
	)
	(gr_line
		(start 175.358298 -31.199836)
		(end 175.358044 -30.39999)
		(stroke
			(width 0.2)
			(type default)
		)
		(layer "In4.Cu")
	)
	(gr_arc
		(start 175.441864 -31.199836)
		(mid 175.799877 -31.55823)
		(end 176.158144 -31.20009)
		(stroke
			(width 0.2)
			(type default)
		)
		(layer "In4.Cu")
	)
	(gr_line
		(start 175.441864 -30.400244)
		(end 175.441864 -31.199836)
		(stroke
			(width 0.2)
			(type default)
		)
		(layer "In4.Cu")
	)
	(gr_line
		(start 175.4886 -82.8802)
		(end 175.158654 -82.550254)
		(stroke
			(width 0.381)
			(type default)
		)
		(layer "In4.Cu")
	)
	(gr_line
		(start 175.4886 -82.5246)
		(end 156.8958 -82.5246)
		(stroke
			(width 0.381)
			(type default)
		)
		(layer "In4.Cu")
	)
	(gr_line
		(start 175.5648 -95.631)
		(end 171.7294 -99.4664)
		(stroke
			(width 0.381)
			(type default)
		)
		(layer "In4.Cu")
	)
	(gr_line
		(start 175.5648 -95.631)
		(end 182.8292 -95.631)
		(stroke
			(width 0.381)
			(type default)
		)
		(layer "In4.Cu")
	)
	(gr_line
		(start 175.5648 -74.7522)
		(end 175.5648 -95.631)
		(stroke
			(width 0.381)
			(type default)
		)
		(layer "In4.Cu")
	)
	(gr_line
		(start 175.9458 -95.5802)
		(end 175.5902 -95.2246)
		(stroke
			(width 0.381)
			(type default)
		)
		(layer "In4.Cu")
	)
	(gr_arc
		(start 175.98517 -23.992078)
		(mid 176.368583 -24.375872)
		(end 176.75225 -23.992332)
		(stroke
			(width 0.2)
			(type default)
		)
		(layer "In4.Cu")
	)
	(gr_line
		(start 175.98517 -23.103332)
		(end 175.98517 -23.992078)
		(stroke
			(width 0.2)
			(type default)
		)
		(layer "In4.Cu")
	)
	(gr_line
		(start 176.158144 -31.20009)
		(end 176.158144 -30.400244)
		(stroke
			(width 0.2)
			(type default)
		)
		(layer "In4.Cu")
	)
	(gr_arc
		(start 176.158144 -30.400244)
		(mid 175.800004 -30.042104)
		(end 175.441864 -30.400244)
		(stroke
			(width 0.2)
			(type default)
		)
		(layer "In4.Cu")
	)
	(gr_line
		(start 176.75225 -23.992332)
		(end 176.75225 -23.103332)
		(stroke
			(width 0.2)
			(type default)
		)
		(layer "In4.Cu")
	)
	(gr_arc
		(start 176.75225 -23.103332)
		(mid 176.36871 -22.719792)
		(end 175.98517 -23.103332)
		(stroke
			(width 0.2)
			(type default)
		)
		(layer "In4.Cu")
	)
	(gr_arc
		(start 178.023774 -24.005286)
		(mid 178.407187 -24.38908)
		(end 178.790854 -24.00554)
		(stroke
			(width 0.2)
			(type default)
		)
		(layer "In4.Cu")
	)
	(gr_line
		(start 178.023774 -23.11654)
		(end 178.023774 -24.005286)
		(stroke
			(width 0.2)
			(type default)
		)
		(layer "In4.Cu")
	)
	(gr_line
		(start 178.086258 -25.508458)
		(end 180.2638 -27.686)
		(stroke
			(width 0.381)
			(type default)
		)
		(layer "In4.Cu")
	)
	(gr_line
		(start 178.790854 -24.00554)
		(end 178.790854 -23.11654)
		(stroke
			(width 0.2)
			(type default)
		)
		(layer "In4.Cu")
	)
	(gr_arc
		(start 178.790854 -23.11654)
		(mid 178.407314 -22.733)
		(end 178.023774 -23.11654)
		(stroke
			(width 0.2)
			(type default)
		)
		(layer "In4.Cu")
	)
	(gr_arc
		(start 179.438554 -12.399772)
		(mid 179.999767 -12.961366)
		(end 180.561234 -12.400026)
		(stroke
			(width 0.2)
			(type default)
		)
		(layer "In4.Cu")
	)
	(gr_line
		(start 179.438554 -10.999978)
		(end 179.438554 -12.399772)
		(stroke
			(width 0.2)
			(type default)
		)
		(layer "In4.Cu")
	)
	(gr_arc
		(start 179.438554 -8.79983)
		(mid 179.999767 -9.361424)
		(end 180.561234 -8.800084)
		(stroke
			(width 0.2)
			(type default)
		)
		(layer "In4.Cu")
	)
	(gr_line
		(start 179.438554 -7.400036)
		(end 179.438554 -8.79983)
		(stroke
			(width 0.2)
			(type default)
		)
		(layer "In4.Cu")
	)
	(gr_arc
		(start 179.438554 -5.199888)
		(mid 179.999767 -5.761482)
		(end 180.561234 -5.200142)
		(stroke
			(width 0.2)
			(type default)
		)
		(layer "In4.Cu")
	)
	(gr_line
		(start 179.438554 -3.800094)
		(end 179.438554 -5.199888)
		(stroke
			(width 0.2)
			(type default)
		)
		(layer "In4.Cu")
	)
	(gr_arc
		(start 180.052472 -24.485092)
		(mid 180.435885 -24.868886)
		(end 180.819552 -24.485346)
		(stroke
			(width 0.2)
			(type default)
		)
		(layer "In4.Cu")
	)
	(gr_line
		(start 180.052472 -23.596346)
		(end 180.052472 -24.485092)
		(stroke
			(width 0.2)
			(type default)
		)
		(layer "In4.Cu")
	)
	(gr_line
		(start 180.2638 -34.4932)
		(end 179.9336 -34.8234)
		(stroke
			(width 0.381)
			(type default)
		)
		(layer "In4.Cu")
	)
	(gr_line
		(start 180.2638 -27.686)
		(end 180.2638 -34.8234)
		(stroke
			(width 0.381)
			(type default)
		)
		(layer "In4.Cu")
	)
	(gr_line
		(start 180.561234 -12.400026)
		(end 180.561234 -10.999978)
		(stroke
			(width 0.2)
			(type default)
		)
		(layer "In4.Cu")
	)
	(gr_arc
		(start 180.561234 -10.999978)
		(mid 179.999894 -10.438638)
		(end 179.438554 -10.999978)
		(stroke
			(width 0.2)
			(type default)
		)
		(layer "In4.Cu")
	)
	(gr_line
		(start 180.561234 -8.800084)
		(end 180.561234 -7.400036)
		(stroke
			(width 0.2)
			(type default)
		)
		(layer "In4.Cu")
	)
	(gr_arc
		(start 180.561234 -7.400036)
		(mid 179.999894 -6.838696)
		(end 179.438554 -7.400036)
		(stroke
			(width 0.2)
			(type default)
		)
		(layer "In4.Cu")
	)
	(gr_line
		(start 180.561234 -5.200142)
		(end 180.561234 -3.800094)
		(stroke
			(width 0.2)
			(type default)
		)
		(layer "In4.Cu")
	)
	(gr_arc
		(start 180.561234 -3.800094)
		(mid 179.999894 -3.238754)
		(end 179.438554 -3.800094)
		(stroke
			(width 0.2)
			(type default)
		)
		(layer "In4.Cu")
	)
	(gr_line
		(start 180.594 -34.8234)
		(end 180.2638 -34.4932)
		(stroke
			(width 0.381)
			(type default)
		)
		(layer "In4.Cu")
	)
	(gr_line
		(start 180.819552 -24.485346)
		(end 180.819552 -23.596346)
		(stroke
			(width 0.2)
			(type default)
		)
		(layer "In4.Cu")
	)
	(gr_arc
		(start 180.819552 -23.596346)
		(mid 180.436012 -23.212806)
		(end 180.052472 -23.596346)
		(stroke
			(width 0.2)
			(type default)
		)
		(layer "In4.Cu")
	)
	(gr_arc
		(start 181.238652 -11.199876)
		(mid 181.799865 -11.76147)
		(end 182.361332 -11.20013)
		(stroke
			(width 0.2)
			(type default)
		)
		(layer "In4.Cu")
	)
	(gr_line
		(start 181.238652 -9.800082)
		(end 181.238652 -11.199876)
		(stroke
			(width 0.2)
			(type default)
		)
		(layer "In4.Cu")
	)
	(gr_arc
		(start 181.238652 -3.999738)
		(mid 181.799865 -4.561332)
		(end 182.361332 -3.999992)
		(stroke
			(width 0.2)
			(type default)
		)
		(layer "In4.Cu")
	)
	(gr_line
		(start 181.238652 -2.600198)
		(end 181.238652 -3.999738)
		(stroke
			(width 0.2)
			(type default)
		)
		(layer "In4.Cu")
	)
	(gr_line
		(start 182.361332 -11.20013)
		(end 182.361332 -9.800082)
		(stroke
			(width 0.2)
			(type default)
		)
		(layer "In4.Cu")
	)
	(gr_arc
		(start 182.361332 -9.800082)
		(mid 181.799992 -9.238742)
		(end 181.238652 -9.800082)
		(stroke
			(width 0.2)
			(type default)
		)
		(layer "In4.Cu")
	)
	(gr_line
		(start 182.361332 -3.999992)
		(end 182.361332 -2.600198)
		(stroke
			(width 0.2)
			(type default)
		)
		(layer "In4.Cu")
	)
	(gr_arc
		(start 182.361332 -2.600198)
		(mid 181.799992 -2.038858)
		(end 181.238652 -2.600198)
		(stroke
			(width 0.2)
			(type default)
		)
		(layer "In4.Cu")
	)
	(gr_line
		(start 182.8292 -95.631)
		(end 184.7342 -97.536)
		(stroke
			(width 0.381)
			(type default)
		)
		(layer "In4.Cu")
	)
	(gr_arc
		(start 183.038496 -12.399772)
		(mid 183.599709 -12.961366)
		(end 184.161176 -12.400026)
		(stroke
			(width 0.2)
			(type default)
		)
		(layer "In4.Cu")
	)
	(gr_line
		(start 183.038496 -10.999978)
		(end 183.038496 -12.399772)
		(stroke
			(width 0.2)
			(type default)
		)
		(layer "In4.Cu")
	)
	(gr_arc
		(start 183.038496 -5.199888)
		(mid 183.599709 -5.761482)
		(end 184.161176 -5.200142)
		(stroke
			(width 0.2)
			(type default)
		)
		(layer "In4.Cu")
	)
	(gr_line
		(start 183.038496 -3.800094)
		(end 183.038496 -5.199888)
		(stroke
			(width 0.2)
			(type default)
		)
		(layer "In4.Cu")
	)
	(gr_line
		(start 184.161176 -12.400026)
		(end 184.161176 -10.999978)
		(stroke
			(width 0.2)
			(type default)
		)
		(layer "In4.Cu")
	)
	(gr_arc
		(start 184.161176 -10.999978)
		(mid 183.599836 -10.438638)
		(end 183.038496 -10.999978)
		(stroke
			(width 0.2)
			(type default)
		)
		(layer "In4.Cu")
	)
	(gr_line
		(start 184.161176 -5.200142)
		(end 184.161176 -3.800094)
		(stroke
			(width 0.2)
			(type default)
		)
		(layer "In4.Cu")
	)
	(gr_arc
		(start 184.161176 -3.800094)
		(mid 183.599836 -3.238754)
		(end 183.038496 -3.800094)
		(stroke
			(width 0.2)
			(type default)
		)
		(layer "In4.Cu")
	)
	(gr_line
		(start 184.7342 -97.536)
		(end 189.8904 -97.536)
		(stroke
			(width 0.381)
			(type default)
		)
		(layer "In4.Cu")
	)
	(gr_arc
		(start 184.838594 -11.199876)
		(mid 185.399807 -11.76147)
		(end 185.961274 -11.20013)
		(stroke
			(width 0.2)
			(type default)
		)
		(layer "In4.Cu")
	)
	(gr_line
		(start 184.838594 -9.800082)
		(end 184.838594 -11.199876)
		(stroke
			(width 0.2)
			(type default)
		)
		(layer "In4.Cu")
	)
	(gr_arc
		(start 184.838594 -3.999738)
		(mid 185.399807 -4.561332)
		(end 185.961274 -3.999992)
		(stroke
			(width 0.2)
			(type default)
		)
		(layer "In4.Cu")
	)
	(gr_line
		(start 184.838594 -2.600198)
		(end 184.838594 -3.999738)
		(stroke
			(width 0.2)
			(type default)
		)
		(layer "In4.Cu")
	)
	(gr_line
		(start 185.961274 -11.20013)
		(end 185.961274 -9.800082)
		(stroke
			(width 0.2)
			(type default)
		)
		(layer "In4.Cu")
	)
	(gr_arc
		(start 185.961274 -9.800082)
		(mid 185.399934 -9.238742)
		(end 184.838594 -9.800082)
		(stroke
			(width 0.2)
			(type default)
		)
		(layer "In4.Cu")
	)
	(gr_line
		(start 185.961274 -3.999992)
		(end 185.961274 -2.600198)
		(stroke
			(width 0.2)
			(type default)
		)
		(layer "In4.Cu")
	)
	(gr_arc
		(start 185.961274 -2.600198)
		(mid 185.399934 -2.038858)
		(end 184.838594 -2.600198)
		(stroke
			(width 0.2)
			(type default)
		)
		(layer "In4.Cu")
	)
	(gr_line
		(start 185.9788 -34.8488)
		(end 167.675814 -34.8488)
		(stroke
			(width 0.381)
			(type default)
		)
		(layer "In4.Cu")
	)
	(gr_arc
		(start 186.638438 -12.399772)
		(mid 187.199651 -12.961366)
		(end 187.761118 -12.400026)
		(stroke
			(width 0.2)
			(type default)
		)
		(layer "In4.Cu")
	)
	(gr_line
		(start 186.638438 -10.999978)
		(end 186.638438 -12.399772)
		(stroke
			(width 0.2)
			(type default)
		)
		(layer "In4.Cu")
	)
	(gr_arc
		(start 186.638438 -5.199888)
		(mid 187.199651 -5.761482)
		(end 187.761118 -5.200142)
		(stroke
			(width 0.2)
			(type default)
		)
		(layer "In4.Cu")
	)
	(gr_line
		(start 186.638438 -3.800094)
		(end 186.638438 -5.199888)
		(stroke
			(width 0.2)
			(type default)
		)
		(layer "In4.Cu")
	)
	(gr_line
		(start 186.6646 -63.7286)
		(end 186.6646 -35.5346)
		(stroke
			(width 0.381)
			(type default)
		)
		(layer "In4.Cu")
	)
	(gr_line
		(start 186.6646 -35.5346)
		(end 185.9788 -34.8488)
		(stroke
			(width 0.381)
			(type default)
		)
		(layer "In4.Cu")
	)
	(gr_line
		(start 187.761118 -12.400026)
		(end 187.761118 -10.999978)
		(stroke
			(width 0.2)
			(type default)
		)
		(layer "In4.Cu")
	)
	(gr_arc
		(start 187.761118 -10.999978)
		(mid 187.199778 -10.438638)
		(end 186.638438 -10.999978)
		(stroke
			(width 0.2)
			(type default)
		)
		(layer "In4.Cu")
	)
	(gr_line
		(start 187.761118 -5.200142)
		(end 187.761118 -3.800094)
		(stroke
			(width 0.2)
			(type default)
		)
		(layer "In4.Cu")
	)
	(gr_arc
		(start 187.761118 -3.800094)
		(mid 187.199778 -3.238754)
		(end 186.638438 -3.800094)
		(stroke
			(width 0.2)
			(type default)
		)
		(layer "In4.Cu")
	)
	(gr_arc
		(start 188.438536 -11.199876)
		(mid 188.999749 -11.76147)
		(end 189.561216 -11.20013)
		(stroke
			(width 0.2)
			(type default)
		)
		(layer "In4.Cu")
	)
	(gr_line
		(start 188.438536 -9.800082)
		(end 188.438536 -11.199876)
		(stroke
			(width 0.2)
			(type default)
		)
		(layer "In4.Cu")
	)
	(gr_arc
		(start 188.438536 -3.999738)
		(mid 188.999749 -4.561332)
		(end 189.561216 -3.999992)
		(stroke
			(width 0.2)
			(type default)
		)
		(layer "In4.Cu")
	)
	(gr_line
		(start 188.438536 -2.600198)
		(end 188.438536 -3.999738)
		(stroke
			(width 0.2)
			(type default)
		)
		(layer "In4.Cu")
	)
	(gr_line
		(start 189.561216 -11.20013)
		(end 189.561216 -9.800082)
		(stroke
			(width 0.2)
			(type default)
		)
		(layer "In4.Cu")
	)
	(gr_arc
		(start 189.561216 -9.800082)
		(mid 188.999876 -9.238742)
		(end 188.438536 -9.800082)
		(stroke
			(width 0.2)
			(type default)
		)
		(layer "In4.Cu")
	)
	(gr_line
		(start 189.561216 -3.999992)
		(end 189.561216 -2.600198)
		(stroke
			(width 0.2)
			(type default)
		)
		(layer "In4.Cu")
	)
	(gr_arc
		(start 189.561216 -2.600198)
		(mid 188.999876 -2.038858)
		(end 188.438536 -2.600198)
		(stroke
			(width 0.2)
			(type default)
		)
		(layer "In4.Cu")
	)
	(gr_line
		(start 189.8904 -97.536)
		(end 192.4558 -94.9706)
		(stroke
			(width 0.381)
			(type default)
		)
		(layer "In4.Cu")
	)
	(gr_arc
		(start 190.238634 -12.399772)
		(mid 190.799847 -12.961366)
		(end 191.361314 -12.400026)
		(stroke
			(width 0.2)
			(type default)
		)
		(layer "In4.Cu")
	)
	(gr_line
		(start 190.238634 -10.999978)
		(end 190.238634 -12.399772)
		(stroke
			(width 0.2)
			(type default)
		)
		(layer "In4.Cu")
	)
	(gr_arc
		(start 190.238634 -5.199888)
		(mid 190.799847 -5.761482)
		(end 191.361314 -5.200142)
		(stroke
			(width 0.2)
			(type default)
		)
		(layer "In4.Cu")
	)
	(gr_line
		(start 190.238634 -3.800094)
		(end 190.238634 -5.199888)
		(stroke
			(width 0.2)
			(type default)
		)
		(layer "In4.Cu")
	)
	(gr_line
		(start 191.361314 -12.400026)
		(end 191.361314 -10.999978)
		(stroke
			(width 0.2)
			(type default)
		)
		(layer "In4.Cu")
	)
	(gr_arc
		(start 191.361314 -10.999978)
		(mid 190.799974 -10.438638)
		(end 190.238634 -10.999978)
		(stroke
			(width 0.2)
			(type default)
		)
		(layer "In4.Cu")
	)
	(gr_line
		(start 191.361314 -5.200142)
		(end 191.361314 -3.800094)
		(stroke
			(width 0.2)
			(type default)
		)
		(layer "In4.Cu")
	)
	(gr_arc
		(start 191.361314 -3.800094)
		(mid 190.799974 -3.238754)
		(end 190.238634 -3.800094)
		(stroke
			(width 0.2)
			(type default)
		)
		(layer "In4.Cu")
	)
	(gr_arc
		(start 192.038478 -11.199876)
		(mid 192.599691 -11.76147)
		(end 193.161158 -11.20013)
		(stroke
			(width 0.2)
			(type default)
		)
		(layer "In4.Cu")
	)
	(gr_line
		(start 192.038478 -9.800082)
		(end 192.038478 -11.199876)
		(stroke
			(width 0.2)
			(type default)
		)
		(layer "In4.Cu")
	)
	(gr_arc
		(start 192.038478 -3.999738)
		(mid 192.599691 -4.561332)
		(end 193.161158 -3.999992)
		(stroke
			(width 0.2)
			(type default)
		)
		(layer "In4.Cu")
	)
	(gr_line
		(start 192.038478 -2.600198)
		(end 192.038478 -3.999738)
		(stroke
			(width 0.2)
			(type default)
		)
		(layer "In4.Cu")
	)
	(gr_line
		(start 192.4558 -94.9706)
		(end 192.4558 -74.5998)
		(stroke
			(width 0.381)
			(type default)
		)
		(layer "In4.Cu")
	)
	(gr_line
		(start 192.4558 -74.5998)
		(end 193.1924 -73.8632)
		(stroke
			(width 0.381)
			(type default)
		)
		(layer "In4.Cu")
	)
	(gr_line
		(start 193.161158 -11.20013)
		(end 193.161158 -9.800082)
		(stroke
			(width 0.2)
			(type default)
		)
		(layer "In4.Cu")
	)
	(gr_arc
		(start 193.161158 -9.800082)
		(mid 192.599818 -9.238742)
		(end 192.038478 -9.800082)
		(stroke
			(width 0.2)
			(type default)
		)
		(layer "In4.Cu")
	)
	(gr_line
		(start 193.161158 -3.999992)
		(end 193.161158 -2.600198)
		(stroke
			(width 0.2)
			(type default)
		)
		(layer "In4.Cu")
	)
	(gr_arc
		(start 193.161158 -2.600198)
		(mid 192.599818 -2.038858)
		(end 192.038478 -2.600198)
		(stroke
			(width 0.2)
			(type default)
		)
		(layer "In4.Cu")
	)
	(gr_line
		(start 193.1924 -73.8632)
		(end 193.1924 -70.2564)
		(stroke
			(width 0.381)
			(type default)
		)
		(layer "In4.Cu")
	)
	(gr_line
		(start 193.1924 -73.8632)
		(end 196.7738 -73.8632)
		(stroke
			(width 0.381)
			(type default)
		)
		(layer "In4.Cu")
	)
	(gr_line
		(start 193.1924 -70.2564)
		(end 186.6646 -63.7286)
		(stroke
			(width 0.381)
			(type default)
		)
		(layer "In4.Cu")
	)
	(gr_line
		(start 193.2432 -73.4314)
		(end 193.5988 -73.787)
		(stroke
			(width 0.381)
			(type default)
		)
		(layer "In4.Cu")
	)
	(gr_line
		(start 196.7738 -73.8632)
		(end 201.4474 -78.5368)
		(stroke
			(width 0.381)
			(type default)
		)
		(layer "In4.Cu")
	)
	(gr_line
		(start 199.9996 -104.8258)
		(end 165.7096 -104.8258)
		(stroke
			(width 0.381)
			(type default)
		)
		(layer "In4.Cu")
	)
	(gr_line
		(start 201.4474 -103.378)
		(end 199.9996 -104.8258)
		(stroke
			(width 0.381)
			(type default)
		)
		(layer "In4.Cu")
	)
	(gr_line
		(start 201.4474 -103.378)
		(end 209.423 -103.378)
		(stroke
			(width 0.381)
			(type default)
		)
		(layer "In4.Cu")
	)
	(gr_line
		(start 201.4474 -78.5368)
		(end 201.4474 -103.378)
		(stroke
			(width 0.381)
			(type default)
		)
		(layer "In4.Cu")
	)
	(gr_line
		(start 208.000092 -144.999964)
		(end 127.00254 -144.999964)
		(stroke
			(width 2.54)
			(type default)
		)
		(layer "In4.Cu")
	)
	(gr_arc
		(start 208.000092 -144.999964)
		(mid 209.414297 -144.41418)
		(end 210.000088 -142.999968)
		(stroke
			(width 2.54)
			(type default)
		)
		(layer "In4.Cu")
	)
	(gr_arc
		(start 208.497678 -103.378)
		(mid 208.497399 -103.378295)
		(end 208.497678 -103.378508)
		(stroke
			(width 0.381)
			(type default)
		)
		(layer "In4.Cu")
	)
	(gr_line
		(start 208.497678 -103.378)
		(end 208.827624 -103.048054)
		(stroke
			(width 0.381)
			(type default)
		)
		(layer "In4.Cu")
	)
	(gr_line
		(start 208.827624 -103.708454)
		(end 208.497678 -103.378508)
		(stroke
			(width 0.381)
			(type default)
		)
		(layer "In4.Cu")
	)
	(gr_arc
		(start 210.000088 -1.999996)
		(mid 209.414301 -0.585791)
		(end 208.000092 0)
		(stroke
			(width 2.54)
			(type default)
		)
		(layer "In4.Cu")
	)
	(gr_line
		(start 210.000088 -1.999996)
		(end 210.000088 -142.999968)
		(stroke
			(width 2.54)
			(type default)
		)
		(layer "In4.Cu")
	)
	(gr_line
		(start 85.109812 -13.951204)
		(end 85.113622 -13.96873)
		(stroke
			(width 0.0508)
			(type default)
		)
		(layer "In5.Cu")
	)
	(gr_line
		(start 85.113622 -13.96873)
		(end 85.123274 -13.983716)
		(stroke
			(width 0.0508)
			(type default)
		)
		(layer "In5.Cu")
	)
	(gr_line
		(start 85.751924 -14.95171)
		(end 85.766656 -14.974316)
		(stroke
			(width 0.0508)
			(type default)
		)
		(layer "In5.Cu")
	)
	(gr_line
		(start 85.766656 -14.974316)
		(end 85.788246 -14.988032)
		(stroke
			(width 0.0508)
			(type default)
		)
		(layer "In5.Cu")
	)
	(gr_arc
		(start 85.820758 -11.547602)
		(mid 85.947579 -11.495093)
		(end 86.000082 -11.368278)
		(stroke
			(width 0.0508)
			(type default)
		)
		(layer "In5.Cu")
	)
	(gr_arc
		(start 86.000082 -12.031726)
		(mid 85.947559 -11.904925)
		(end 85.820758 -11.852402)
		(stroke
			(width 0.0508)
			(type default)
		)
		(layer "In5.Cu")
	)
	(gr_line
		(start 86.000082 -12.031726)
		(end 86.000082 -12.400026)
		(stroke
			(width 0.0508)
			(type default)
		)
		(layer "In5.Cu")
	)
	(gr_line
		(start 86.000082 -10.999978)
		(end 86.000082 -11.368278)
		(stroke
			(width 0.0508)
			(type default)
		)
		(layer "In5.Cu")
	)
	(gr_line
		(start 86.827614 -13.17117)
		(end 86.831424 -13.188696)
		(stroke
			(width 0.0508)
			(type default)
		)
		(layer "In5.Cu")
	)
	(gr_line
		(start 86.831424 -13.188696)
		(end 86.841076 -13.203682)
		(stroke
			(width 0.0508)
			(type default)
		)
		(layer "In5.Cu")
	)
	(gr_arc
		(start 87.620856 -10.347706)
		(mid 87.747657 -10.295183)
		(end 87.80018 -10.168382)
		(stroke
			(width 0.0508)
			(type default)
		)
		(layer "In5.Cu")
	)
	(gr_arc
		(start 87.80018 -10.83183)
		(mid 87.747665 -10.705025)
		(end 87.620856 -10.652506)
		(stroke
			(width 0.0508)
			(type default)
		)
		(layer "In5.Cu")
	)
	(gr_line
		(start 87.80018 -10.83183)
		(end 87.80018 -11.20013)
		(stroke
			(width 0.0508)
			(type default)
		)
		(layer "In5.Cu")
	)
	(gr_line
		(start 87.80018 -9.800082)
		(end 87.80018 -10.168382)
		(stroke
			(width 0.0508)
			(type default)
		)
		(layer "In5.Cu")
	)
	(gr_line
		(start 88.024208 -15.025116)
		(end 88.03894 -15.047722)
		(stroke
			(width 0.0508)
			(type default)
		)
		(layer "In5.Cu")
	)
	(gr_line
		(start 88.03894 -15.047722)
		(end 88.06053 -15.061438)
		(stroke
			(width 0.0508)
			(type default)
		)
		(layer "In5.Cu")
	)
	(gr_line
		(start 88.613742 -13.632688)
		(end 88.617552 -13.650214)
		(stroke
			(width 0.0508)
			(type default)
		)
		(layer "In5.Cu")
	)
	(gr_line
		(start 88.617552 -13.650214)
		(end 88.627204 -13.6652)
		(stroke
			(width 0.0508)
			(type default)
		)
		(layer "In5.Cu")
	)
	(gr_line
		(start 88.933782 -16.667226)
		(end 88.956388 -16.681958)
		(stroke
			(width 0.0508)
			(type default)
		)
		(layer "In5.Cu")
	)
	(gr_line
		(start 88.956388 -16.681958)
		(end 88.97112 -16.704564)
		(stroke
			(width 0.0508)
			(type default)
		)
		(layer "In5.Cu")
	)
	(gr_line
		(start 89.149936 -14.469872)
		(end 89.164668 -14.492478)
		(stroke
			(width 0.0508)
			(type default)
		)
		(layer "In5.Cu")
	)
	(gr_line
		(start 89.164668 -14.492478)
		(end 89.187274 -14.50721)
		(stroke
			(width 0.0508)
			(type default)
		)
		(layer "In5.Cu")
	)
	(gr_arc
		(start 89.4207 -11.547602)
		(mid 89.547501 -11.495079)
		(end 89.600024 -11.368278)
		(stroke
			(width 0.0508)
			(type default)
		)
		(layer "In5.Cu")
	)
	(gr_line
		(start 89.56548 -15.67561)
		(end 89.58707 -15.689326)
		(stroke
			(width 0.0508)
			(type default)
		)
		(layer "In5.Cu")
	)
	(gr_line
		(start 89.58707 -15.689326)
		(end 89.601802 -15.711932)
		(stroke
			(width 0.0508)
			(type default)
		)
		(layer "In5.Cu")
	)
	(gr_arc
		(start 89.600024 -12.031726)
		(mid 89.54751 -11.904908)
		(end 89.4207 -11.852402)
		(stroke
			(width 0.0508)
			(type default)
		)
		(layer "In5.Cu")
	)
	(gr_line
		(start 89.600024 -12.031726)
		(end 89.600024 -12.400026)
		(stroke
			(width 0.0508)
			(type default)
		)
		(layer "In5.Cu")
	)
	(gr_line
		(start 89.600024 -10.999978)
		(end 89.600024 -11.368278)
		(stroke
			(width 0.0508)
			(type default)
		)
		(layer "In5.Cu")
	)
	(gr_line
		(start 90.321892 -14.88059)
		(end 90.344498 -14.895322)
		(stroke
			(width 0.0508)
			(type default)
		)
		(layer "In5.Cu")
	)
	(gr_line
		(start 90.344498 -14.895322)
		(end 90.35923 -14.917928)
		(stroke
			(width 0.0508)
			(type default)
		)
		(layer "In5.Cu")
	)
	(gr_line
		(start 90.347546 -12.946888)
		(end 90.375232 -12.98956)
		(stroke
			(width 0.0508)
			(type default)
		)
		(layer "In5.Cu")
	)
	(gr_arc
		(start 91.220798 -10.347706)
		(mid 91.347599 -10.295183)
		(end 91.400122 -10.168382)
		(stroke
			(width 0.0508)
			(type default)
		)
		(layer "In5.Cu")
	)
	(gr_arc
		(start 91.400122 -10.83183)
		(mid 91.34761 -10.70501)
		(end 91.220798 -10.652506)
		(stroke
			(width 0.0508)
			(type default)
		)
		(layer "In5.Cu")
	)
	(gr_line
		(start 91.400122 -10.83183)
		(end 91.400122 -11.20013)
		(stroke
			(width 0.0508)
			(type default)
		)
		(layer "In5.Cu")
	)
	(gr_line
		(start 91.400122 -9.800082)
		(end 91.400122 -10.168382)
		(stroke
			(width 0.0508)
			(type default)
		)
		(layer "In5.Cu")
	)
	(gr_line
		(start 92.299282 -14.087094)
		(end 92.303092 -14.10462)
		(stroke
			(width 0.0508)
			(type default)
		)
		(layer "In5.Cu")
	)
	(gr_line
		(start 92.303092 -14.10462)
		(end 92.312744 -14.119606)
		(stroke
			(width 0.0508)
			(type default)
		)
		(layer "In5.Cu")
	)
	(gr_arc
		(start 93.020642 -11.547602)
		(mid 93.147443 -11.495079)
		(end 93.199966 -11.368278)
		(stroke
			(width 0.0508)
			(type default)
		)
		(layer "In5.Cu")
	)
	(gr_arc
		(start 93.199966 -12.031726)
		(mid 93.147455 -11.904893)
		(end 93.020642 -11.852402)
		(stroke
			(width 0.0508)
			(type default)
		)
		(layer "In5.Cu")
	)
	(gr_line
		(start 93.199966 -12.031726)
		(end 93.199966 -12.400026)
		(stroke
			(width 0.0508)
			(type default)
		)
		(layer "In5.Cu")
	)
	(gr_line
		(start 93.199966 -10.999978)
		(end 93.199966 -11.368278)
		(stroke
			(width 0.0508)
			(type default)
		)
		(layer "In5.Cu")
	)
	(gr_line
		(start 94.32925 -15.0114)
		(end 94.33306 -15.028926)
		(stroke
			(width 0.0508)
			(type default)
		)
		(layer "In5.Cu")
	)
	(gr_line
		(start 94.33306 -15.028926)
		(end 94.342712 -15.043912)
		(stroke
			(width 0.0508)
			(type default)
		)
		(layer "In5.Cu")
	)
	(gr_arc
		(start 94.82074 -10.347706)
		(mid 94.947541 -10.295183)
		(end 95.000064 -10.168382)
		(stroke
			(width 0.0508)
			(type default)
		)
		(layer "In5.Cu")
	)
	(gr_arc
		(start 95.000064 -10.83183)
		(mid 94.947554 -10.704995)
		(end 94.82074 -10.652506)
		(stroke
			(width 0.0508)
			(type default)
		)
		(layer "In5.Cu")
	)
	(gr_line
		(start 95.000064 -10.83183)
		(end 95.000064 -11.20013)
		(stroke
			(width 0.0508)
			(type default)
		)
		(layer "In5.Cu")
	)
	(gr_line
		(start 95.000064 -9.800082)
		(end 95.000064 -10.168382)
		(stroke
			(width 0.0508)
			(type default)
		)
		(layer "In5.Cu")
	)
	(gr_line
		(start 96.057974 -43.206162)
		(end 96.063054 -43.17746)
		(stroke
			(width 0.0508)
			(type default)
		)
		(layer "In5.Cu")
	)
	(gr_line
		(start 96.063054 -43.17746)
		(end 96.079564 -43.154092)
		(stroke
			(width 0.0508)
			(type default)
		)
		(layer "In5.Cu")
	)
	(gr_line
		(start 96.075246 -45.376338)
		(end 96.080326 -45.404532)
		(stroke
			(width 0.0508)
			(type default)
		)
		(layer "In5.Cu")
	)
	(gr_line
		(start 96.080326 -45.404532)
		(end 96.096836 -45.428154)
		(stroke
			(width 0.0508)
			(type default)
		)
		(layer "In5.Cu")
	)
	(gr_line
		(start 96.159828 -15.220696)
		(end 96.163638 -15.238222)
		(stroke
			(width 0.0508)
			(type default)
		)
		(layer "In5.Cu")
	)
	(gr_line
		(start 96.163638 -15.238222)
		(end 96.17329 -15.253208)
		(stroke
			(width 0.0508)
			(type default)
		)
		(layer "In5.Cu")
	)
	(gr_line
		(start 96.20758 -42.970958)
		(end 96.217232 -42.957242)
		(stroke
			(width 0.0508)
			(type default)
		)
		(layer "In5.Cu")
	)
	(gr_line
		(start 96.217232 -42.957242)
		(end 96.23044 -42.948098)
		(stroke
			(width 0.0508)
			(type default)
		)
		(layer "In5.Cu")
	)
	(gr_line
		(start 96.342454 -45.779436)
		(end 96.352106 -45.793152)
		(stroke
			(width 0.0508)
			(type default)
		)
		(layer "In5.Cu")
	)
	(gr_line
		(start 96.352106 -45.793152)
		(end 96.365822 -45.802804)
		(stroke
			(width 0.0508)
			(type default)
		)
		(layer "In5.Cu")
	)
	(gr_arc
		(start 96.620838 -11.547602)
		(mid 96.747639 -11.495079)
		(end 96.800162 -11.368278)
		(stroke
			(width 0.0508)
			(type default)
		)
		(layer "In5.Cu")
	)
	(gr_arc
		(start 96.800162 -12.031726)
		(mid 96.747651 -11.904895)
		(end 96.620838 -11.852402)
		(stroke
			(width 0.0508)
			(type default)
		)
		(layer "In5.Cu")
	)
	(gr_line
		(start 96.800162 -12.031726)
		(end 96.800162 -12.400026)
		(stroke
			(width 0.0508)
			(type default)
		)
		(layer "In5.Cu")
	)
	(gr_line
		(start 96.800162 -10.999978)
		(end 96.800162 -11.368278)
		(stroke
			(width 0.0508)
			(type default)
		)
		(layer "In5.Cu")
	)
	(gr_line
		(start 96.908366 -45.810678)
		(end 96.935036 -45.82922)
		(stroke
			(width 0.0508)
			(type default)
		)
		(layer "In5.Cu")
	)
	(gr_line
		(start 96.935036 -45.82922)
		(end 96.951292 -45.858684)
		(stroke
			(width 0.0508)
			(type default)
		)
		(layer "In5.Cu")
	)
	(gr_line
		(start 97.50933 -29.852366)
		(end 97.518982 -29.867352)
		(stroke
			(width 0.0508)
			(type default)
		)
		(layer "In5.Cu")
	)
	(gr_line
		(start 97.518982 -29.867352)
		(end 97.522792 -29.884878)
		(stroke
			(width 0.0508)
			(type default)
		)
		(layer "In5.Cu")
	)
	(gr_line
		(start 97.570036 -43.274488)
		(end 97.575116 -43.245786)
		(stroke
			(width 0.0508)
			(type default)
		)
		(layer "In5.Cu")
	)
	(gr_line
		(start 97.575116 -43.245786)
		(end 97.592134 -43.221402)
		(stroke
			(width 0.0508)
			(type default)
		)
		(layer "In5.Cu")
	)
	(gr_line
		(start 97.599246 -45.376338)
		(end 97.604326 -45.404532)
		(stroke
			(width 0.0508)
			(type default)
		)
		(layer "In5.Cu")
	)
	(gr_line
		(start 97.604326 -45.404532)
		(end 97.620328 -45.427138)
		(stroke
			(width 0.0508)
			(type default)
		)
		(layer "In5.Cu")
	)
	(gr_line
		(start 97.799652 -42.924476)
		(end 97.809304 -42.91076)
		(stroke
			(width 0.0508)
			(type default)
		)
		(layer "In5.Cu")
	)
	(gr_line
		(start 97.809304 -42.91076)
		(end 97.82302 -42.901108)
		(stroke
			(width 0.0508)
			(type default)
		)
		(layer "In5.Cu")
	)
	(gr_line
		(start 97.868486 -48.170338)
		(end 97.887282 -48.204628)
		(stroke
			(width 0.0508)
			(type default)
		)
		(layer "In5.Cu")
	)
	(gr_line
		(start 97.887282 -48.204628)
		(end 97.919794 -48.22571)
		(stroke
			(width 0.0508)
			(type default)
		)
		(layer "In5.Cu")
	)
	(gr_line
		(start 97.936812 -45.864526)
		(end 97.93986 -45.868336)
		(stroke
			(width 0.0508)
			(type default)
		)
		(layer "In5.Cu")
	)
	(gr_line
		(start 97.93986 -45.868336)
		(end 97.94367 -45.87113)
		(stroke
			(width 0.0508)
			(type default)
		)
		(layer "In5.Cu")
	)
	(gr_line
		(start 97.970086 -41.730422)
		(end 97.970594 -41.730422)
		(stroke
			(width 0.0508)
			(type default)
		)
		(layer "In5.Cu")
	)
	(gr_line
		(start 97.970594 -41.730422)
		(end 97.970848 -41.729914)
		(stroke
			(width 0.0508)
			(type default)
		)
		(layer "In5.Cu")
	)
	(gr_line
		(start 97.973388 -45.891958)
		(end 97.97669 -45.894244)
		(stroke
			(width 0.0508)
			(type default)
		)
		(layer "In5.Cu")
	)
	(gr_line
		(start 98.07448 -15.318232)
		(end 98.07829 -15.335758)
		(stroke
			(width 0.0508)
			(type default)
		)
		(layer "In5.Cu")
	)
	(gr_line
		(start 98.07829 -15.335758)
		(end 98.087942 -15.350744)
		(stroke
			(width 0.0508)
			(type default)
		)
		(layer "In5.Cu")
	)
	(gr_line
		(start 98.135694 -41.986708)
		(end 98.15576 -41.972484)
		(stroke
			(width 0.0508)
			(type default)
		)
		(layer "In5.Cu")
	)
	(gr_line
		(start 98.150934 -45.644054)
		(end 98.152712 -45.645324)
		(stroke
			(width 0.0508)
			(type default)
		)
		(layer "In5.Cu")
	)
	(gr_line
		(start 98.179636 -41.95572)
		(end 98.194368 -41.94556)
		(stroke
			(width 0.0508)
			(type default)
		)
		(layer "In5.Cu")
	)
	(gr_line
		(start 98.194368 -41.94556)
		(end 98.194622 -41.94556)
		(stroke
			(width 0.0508)
			(type default)
		)
		(layer "In5.Cu")
	)
	(gr_line
		(start 98.194622 -41.94556)
		(end 98.206052 -41.928034)
		(stroke
			(width 0.0508)
			(type default)
		)
		(layer "In5.Cu")
	)
	(gr_line
		(start 98.36023 -29.19857)
		(end 98.369882 -29.213556)
		(stroke
			(width 0.0508)
			(type default)
		)
		(layer "In5.Cu")
	)
	(gr_line
		(start 98.369882 -29.213556)
		(end 98.373692 -29.231082)
		(stroke
			(width 0.0508)
			(type default)
		)
		(layer "In5.Cu")
	)
	(gr_arc
		(start 98.420682 -10.347706)
		(mid 98.547483 -10.295183)
		(end 98.600006 -10.168382)
		(stroke
			(width 0.0508)
			(type default)
		)
		(layer "In5.Cu")
	)
	(gr_line
		(start 98.596704 -42.73169)
		(end 98.614738 -42.71899)
		(stroke
			(width 0.0508)
			(type default)
		)
		(layer "In5.Cu")
	)
	(gr_arc
		(start 98.600006 -10.83183)
		(mid 98.547493 -10.705016)
		(end 98.420682 -10.652506)
		(stroke
			(width 0.0508)
			(type default)
		)
		(layer "In5.Cu")
	)
	(gr_line
		(start 98.600006 -10.83183)
		(end 98.600006 -11.20013)
		(stroke
			(width 0.0508)
			(type default)
		)
		(layer "In5.Cu")
	)
	(gr_line
		(start 98.600006 -9.800082)
		(end 98.600006 -10.168382)
		(stroke
			(width 0.0508)
			(type default)
		)
		(layer "In5.Cu")
	)
	(gr_line
		(start 98.614738 -42.71899)
		(end 98.626676 -42.700702)
		(stroke
			(width 0.0508)
			(type default)
		)
		(layer "In5.Cu")
	)
	(gr_line
		(start 98.74123 -41.104058)
		(end 98.75139 -41.08831)
		(stroke
			(width 0.0508)
			(type default)
		)
		(layer "In5.Cu")
	)
	(gr_line
		(start 98.75139 -41.08831)
		(end 98.754946 -41.070784)
		(stroke
			(width 0.0508)
			(type default)
		)
		(layer "In5.Cu")
	)
	(gr_line
		(start 98.806762 -46.103032)
		(end 98.825558 -46.11624)
		(stroke
			(width 0.0508)
			(type default)
		)
		(layer "In5.Cu")
	)
	(gr_line
		(start 98.825558 -46.11624)
		(end 98.838512 -46.136052)
		(stroke
			(width 0.0508)
			(type default)
		)
		(layer "In5.Cu")
	)
	(gr_line
		(start 98.918268 -48.873918)
		(end 99.429824 -49.205896)
		(stroke
			(width 0.0508)
			(type default)
		)
		(layer "In5.Cu")
	)
	(gr_line
		(start 99.055682 -48.59655)
		(end 99.315778 -48.541178)
		(stroke
			(width 0.0508)
			(type default)
		)
		(layer "In5.Cu")
	)
	(gr_line
		(start 99.058984 -45.001942)
		(end 99.08667 -45.044614)
		(stroke
			(width 0.0508)
			(type default)
		)
		(layer "In5.Cu")
	)
	(gr_line
		(start 99.130104 -43.12158)
		(end 99.135184 -43.092878)
		(stroke
			(width 0.0508)
			(type default)
		)
		(layer "In5.Cu")
	)
	(gr_line
		(start 99.135184 -43.092878)
		(end 99.151694 -43.06951)
		(stroke
			(width 0.0508)
			(type default)
		)
		(layer "In5.Cu")
	)
	(gr_line
		(start 99.13874 -47.159672)
		(end 99.471226 -47.672498)
		(stroke
			(width 0.0508)
			(type default)
		)
		(layer "In5.Cu")
	)
	(gr_line
		(start 99.220274 -28.5623)
		(end 99.229926 -28.577286)
		(stroke
			(width 0.0508)
			(type default)
		)
		(layer "In5.Cu")
	)
	(gr_line
		(start 99.229926 -28.577286)
		(end 99.233736 -28.594812)
		(stroke
			(width 0.0508)
			(type default)
		)
		(layer "In5.Cu")
	)
	(gr_line
		(start 99.315778 -48.541178)
		(end 99.571556 -48.70704)
		(stroke
			(width 0.0508)
			(type default)
		)
		(layer "In5.Cu")
	)
	(gr_line
		(start 99.32289 -38.40353)
		(end 99.328224 -38.37813)
		(stroke
			(width 0.0508)
			(type default)
		)
		(layer "In5.Cu")
	)
	(gr_line
		(start 99.32289 -38.352984)
		(end 99.328224 -38.37813)
		(stroke
			(width 0.0508)
			(type default)
		)
		(layer "In5.Cu")
	)
	(gr_line
		(start 99.376992 -46.962314)
		(end 99.637088 -47.017432)
		(stroke
			(width 0.0508)
			(type default)
		)
		(layer "In5.Cu")
	)
	(gr_line
		(start 99.472242 -41.399206)
		(end 99.482402 -41.383458)
		(stroke
			(width 0.0508)
			(type default)
		)
		(layer "In5.Cu")
	)
	(gr_line
		(start 99.482402 -41.383458)
		(end 99.485958 -41.365932)
		(stroke
			(width 0.0508)
			(type default)
		)
		(layer "In5.Cu")
	)
	(gr_line
		(start 99.519994 -45.713142)
		(end 99.860862 -46.237652)
		(stroke
			(width 0.0508)
			(type default)
		)
		(layer "In5.Cu")
	)
	(gr_line
		(start 99.571556 -48.70704)
		(end 99.626928 -48.96739)
		(stroke
			(width 0.0508)
			(type default)
		)
		(layer "In5.Cu")
	)
	(gr_line
		(start 99.637088 -47.017432)
		(end 99.803204 -47.27321)
		(stroke
			(width 0.0508)
			(type default)
		)
		(layer "In5.Cu")
	)
	(gr_line
		(start 99.747578 -47.533814)
		(end 99.803204 -47.27321)
		(stroke
			(width 0.0508)
			(type default)
		)
		(layer "In5.Cu")
	)
	(gr_line
		(start 99.762818 -45.522896)
		(end 100.024438 -45.578522)
		(stroke
			(width 0.0508)
			(type default)
		)
		(layer "In5.Cu")
	)
	(gr_line
		(start 99.792536 -15.12951)
		(end 99.796346 -15.147036)
		(stroke
			(width 0.0508)
			(type default)
		)
		(layer "In5.Cu")
	)
	(gr_line
		(start 99.796346 -15.147036)
		(end 99.805998 -15.162022)
		(stroke
			(width 0.0508)
			(type default)
		)
		(layer "In5.Cu")
	)
	(gr_line
		(start 100.000054 -51.684174)
		(end 100.000054 -52.00015)
		(stroke
			(width 0.04445)
			(type default)
		)
		(layer "In5.Cu")
	)
	(gr_arc
		(start 100.000054 -51.315874)
		(mid 100.02608 -51.378769)
		(end 100.088954 -51.404774)
		(stroke
			(width 0.04445)
			(type default)
		)
		(layer "In5.Cu")
	)
	(gr_line
		(start 100.000054 -51.000152)
		(end 100.000054 -51.315874)
		(stroke
			(width 0.04445)
			(type default)
		)
		(layer "In5.Cu")
	)
	(gr_line
		(start 100.024438 -45.578522)
		(end 100.190554 -45.834046)
		(stroke
			(width 0.0508)
			(type default)
		)
		(layer "In5.Cu")
	)
	(gr_line
		(start 100.047044 -27.322018)
		(end 100.056696 -27.337004)
		(stroke
			(width 0.0508)
			(type default)
		)
		(layer "In5.Cu")
	)
	(gr_line
		(start 100.056696 -27.337004)
		(end 100.060506 -27.35453)
		(stroke
			(width 0.0508)
			(type default)
		)
		(layer "In5.Cu")
	)
	(gr_arc
		(start 100.088954 -51.595274)
		(mid 100.026092 -51.621312)
		(end 100.000054 -51.684174)
		(stroke
			(width 0.04445)
			(type default)
		)
		(layer "In5.Cu")
	)
	(gr_line
		(start 100.090986 -49.271428)
		(end 100.113338 -49.285906)
		(stroke
			(width 0.0508)
			(type default)
		)
		(layer "In5.Cu")
	)
	(gr_line
		(start 100.113338 -49.285906)
		(end 100.127816 -49.308258)
		(stroke
			(width 0.0508)
			(type default)
		)
		(layer "In5.Cu")
	)
	(gr_line
		(start 100.134928 -46.095412)
		(end 100.190554 -45.834046)
		(stroke
			(width 0.0508)
			(type default)
		)
		(layer "In5.Cu")
	)
	(gr_line
		(start 100.21443 -37.942012)
		(end 100.219764 -37.916866)
		(stroke
			(width 0.0508)
			(type default)
		)
		(layer "In5.Cu")
	)
	(gr_line
		(start 100.21443 -37.89172)
		(end 100.219764 -37.916866)
		(stroke
			(width 0.0508)
			(type default)
		)
		(layer "In5.Cu")
	)
	(gr_arc
		(start 100.22078 -11.547602)
		(mid 100.347581 -11.495079)
		(end 100.400104 -11.368278)
		(stroke
			(width 0.0508)
			(type default)
		)
		(layer "In5.Cu")
	)
	(gr_line
		(start 100.336858 -41.907968)
		(end 100.350066 -41.888918)
		(stroke
			(width 0.0508)
			(type default)
		)
		(layer "In5.Cu")
	)
	(gr_line
		(start 100.350066 -50.65649)
		(end 100.366068 -50.672492)
		(stroke
			(width 0.04445)
			(type default)
		)
		(layer "In5.Cu")
	)
	(gr_line
		(start 100.350066 -50.634392)
		(end 100.350066 -50.65649)
		(stroke
			(width 0.04445)
			(type default)
		)
		(layer "In5.Cu")
	)
	(gr_line
		(start 100.350066 -41.888918)
		(end 100.35032 -41.888664)
		(stroke
			(width 0.0508)
			(type default)
		)
		(layer "In5.Cu")
	)
	(gr_line
		(start 100.35032 -41.888664)
		(end 100.3554 -41.865042)
		(stroke
			(width 0.0508)
			(type default)
		)
		(layer "In5.Cu")
	)
	(gr_line
		(start 100.367846 -50.67427)
		(end 100.407216 -50.71364)
		(stroke
			(width 0.04445)
			(type default)
		)
		(layer "In5.Cu")
	)
	(gr_arc
		(start 100.400104 -12.031726)
		(mid 100.347589 -11.904915)
		(end 100.22078 -11.852402)
		(stroke
			(width 0.0508)
			(type default)
		)
		(layer "In5.Cu")
	)
	(gr_line
		(start 100.400104 -12.031726)
		(end 100.400104 -12.400026)
		(stroke
			(width 0.0508)
			(type default)
		)
		(layer "In5.Cu")
	)
	(gr_line
		(start 100.400104 -10.999978)
		(end 100.400104 -11.368278)
		(stroke
			(width 0.0508)
			(type default)
		)
		(layer "In5.Cu")
	)
	(gr_line
		(start 100.592128 -50.02403)
		(end 100.60178 -50.039016)
		(stroke
			(width 0.0508)
			(type default)
		)
		(layer "In5.Cu")
	)
	(gr_line
		(start 100.597716 -50.71364)
		(end 100.637086 -50.67427)
		(stroke
			(width 0.04445)
			(type default)
		)
		(layer "In5.Cu")
	)
	(gr_line
		(start 100.60178 -50.039016)
		(end 100.60559 -50.056542)
		(stroke
			(width 0.0508)
			(type default)
		)
		(layer "In5.Cu")
	)
	(gr_line
		(start 100.638864 -50.672492)
		(end 100.654866 -50.65649)
		(stroke
			(width 0.04445)
			(type default)
		)
		(layer "In5.Cu")
	)
	(gr_line
		(start 100.64369 -43.236388)
		(end 100.64877 -43.207686)
		(stroke
			(width 0.0508)
			(type default)
		)
		(layer "In5.Cu")
	)
	(gr_line
		(start 100.647246 -45.376338)
		(end 100.652326 -45.404532)
		(stroke
			(width 0.0508)
			(type default)
		)
		(layer "In5.Cu")
	)
	(gr_line
		(start 100.64877 -43.207686)
		(end 100.665534 -43.183556)
		(stroke
			(width 0.0508)
			(type default)
		)
		(layer "In5.Cu")
	)
	(gr_line
		(start 100.652326 -45.404532)
		(end 100.668836 -45.428154)
		(stroke
			(width 0.0508)
			(type default)
		)
		(layer "In5.Cu")
	)
	(gr_line
		(start 100.654866 -50.634392)
		(end 100.654866 -50.65649)
		(stroke
			(width 0.04445)
			(type default)
		)
		(layer "In5.Cu")
	)
	(gr_line
		(start 100.857812 -46.032928)
		(end 100.861622 -46.050454)
		(stroke
			(width 0.0508)
			(type default)
		)
		(layer "In5.Cu")
	)
	(gr_line
		(start 100.861622 -46.050454)
		(end 100.871274 -46.06544)
		(stroke
			(width 0.0508)
			(type default)
		)
		(layer "In5.Cu")
	)
	(gr_line
		(start 101.000052 -52.684172)
		(end 101.000052 -53.000148)
		(stroke
			(width 0.04445)
			(type default)
		)
		(layer "In5.Cu")
	)
	(gr_arc
		(start 101.000052 -52.315872)
		(mid 101.02609 -52.378734)
		(end 101.088952 -52.404772)
		(stroke
			(width 0.04445)
			(type default)
		)
		(layer "In5.Cu")
	)
	(gr_line
		(start 101.000052 -52.00015)
		(end 101.000052 -52.315872)
		(stroke
			(width 0.04445)
			(type default)
		)
		(layer "In5.Cu")
	)
	(gr_line
		(start 101.027738 -45.409104)
		(end 101.040946 -45.428154)
		(stroke
			(width 0.0508)
			(type default)
		)
		(layer "In5.Cu")
	)
	(gr_line
		(start 101.040946 -45.428154)
		(end 101.045772 -45.45076)
		(stroke
			(width 0.0508)
			(type default)
		)
		(layer "In5.Cu")
	)
	(gr_line
		(start 101.082602 -27.06243)
		(end 101.092254 -27.077416)
		(stroke
			(width 0.0508)
			(type default)
		)
		(layer "In5.Cu")
	)
	(gr_arc
		(start 101.088952 -52.595272)
		(mid 101.026111 -52.621325)
		(end 101.000052 -52.684172)
		(stroke
			(width 0.04445)
			(type default)
		)
		(layer "In5.Cu")
	)
	(gr_line
		(start 101.092254 -27.077416)
		(end 101.096064 -27.094942)
		(stroke
			(width 0.0508)
			(type default)
		)
		(layer "In5.Cu")
	)
	(gr_line
		(start 101.199188 -37.893244)
		(end 101.204522 -37.868098)
		(stroke
			(width 0.0508)
			(type default)
		)
		(layer "In5.Cu")
	)
	(gr_line
		(start 101.199188 -37.842952)
		(end 101.204522 -37.868098)
		(stroke
			(width 0.0508)
			(type default)
		)
		(layer "In5.Cu")
	)
	(gr_line
		(start 101.337618 -14.213078)
		(end 101.341428 -14.230604)
		(stroke
			(width 0.0508)
			(type default)
		)
		(layer "In5.Cu")
	)
	(gr_line
		(start 101.341428 -14.230604)
		(end 101.35108 -14.24559)
		(stroke
			(width 0.0508)
			(type default)
		)
		(layer "In5.Cu")
	)
	(gr_line
		(start 101.345238 -42.74566)
		(end 101.362002 -42.72153)
		(stroke
			(width 0.0508)
			(type default)
		)
		(layer "In5.Cu")
	)
	(gr_line
		(start 101.34727 -50.546)
		(end 101.363272 -50.562002)
		(stroke
			(width 0.04445)
			(type default)
		)
		(layer "In5.Cu")
	)
	(gr_line
		(start 101.34727 -50.523902)
		(end 101.34727 -50.546)
		(stroke
			(width 0.04445)
			(type default)
		)
		(layer "In5.Cu")
	)
	(gr_line
		(start 101.362002 -42.72153)
		(end 101.367082 -42.692828)
		(stroke
			(width 0.0508)
			(type default)
		)
		(layer "In5.Cu")
	)
	(gr_line
		(start 101.36505 -50.56378)
		(end 101.40442 -50.60315)
		(stroke
			(width 0.04445)
			(type default)
		)
		(layer "In5.Cu")
	)
	(gr_line
		(start 101.575108 -49.78019)
		(end 101.585268 -49.795938)
		(stroke
			(width 0.0508)
			(type default)
		)
		(layer "In5.Cu")
	)
	(gr_line
		(start 101.585268 -49.795938)
		(end 101.589078 -49.813972)
		(stroke
			(width 0.0508)
			(type default)
		)
		(layer "In5.Cu")
	)
	(gr_line
		(start 101.59492 -50.60315)
		(end 101.63429 -50.56378)
		(stroke
			(width 0.04445)
			(type default)
		)
		(layer "In5.Cu")
	)
	(gr_line
		(start 101.636068 -50.562002)
		(end 101.65207 -50.546)
		(stroke
			(width 0.04445)
			(type default)
		)
		(layer "In5.Cu")
	)
	(gr_line
		(start 101.65207 -50.523902)
		(end 101.65207 -50.546)
		(stroke
			(width 0.04445)
			(type default)
		)
		(layer "In5.Cu")
	)
	(gr_line
		(start 102.00005 -51.684174)
		(end 102.00005 -52.00015)
		(stroke
			(width 0.04445)
			(type default)
		)
		(layer "In5.Cu")
	)
	(gr_arc
		(start 102.00005 -51.315874)
		(mid 102.026088 -51.378736)
		(end 102.08895 -51.404774)
		(stroke
			(width 0.04445)
			(type default)
		)
		(layer "In5.Cu")
	)
	(gr_line
		(start 102.00005 -51.000152)
		(end 102.00005 -51.315874)
		(stroke
			(width 0.04445)
			(type default)
		)
		(layer "In5.Cu")
	)
	(gr_line
		(start 102.008178 -26.287222)
		(end 102.01783 -26.302208)
		(stroke
			(width 0.0508)
			(type default)
		)
		(layer "In5.Cu")
	)
	(gr_line
		(start 102.01783 -26.302208)
		(end 102.02164 -26.319734)
		(stroke
			(width 0.0508)
			(type default)
		)
		(layer "In5.Cu")
	)
	(gr_arc
		(start 102.020878 -10.347706)
		(mid 102.147679 -10.295183)
		(end 102.200202 -10.168382)
		(stroke
			(width 0.0508)
			(type default)
		)
		(layer "In5.Cu")
	)
	(gr_arc
		(start 102.08895 -51.595274)
		(mid 102.026047 -51.621293)
		(end 102.00005 -51.684174)
		(stroke
			(width 0.04445)
			(type default)
		)
		(layer "In5.Cu")
	)
	(gr_line
		(start 102.113334 -45.046646)
		(end 102.132384 -45.154088)
		(stroke
			(width 0.0508)
			(type default)
		)
		(layer "In5.Cu")
	)
	(gr_line
		(start 102.132384 -45.154088)
		(end 102.153974 -45.277024)
		(stroke
			(width 0.0508)
			(type default)
		)
		(layer "In5.Cu")
	)
	(gr_line
		(start 102.171246 -45.376084)
		(end 102.176326 -45.404786)
		(stroke
			(width 0.0508)
			(type default)
		)
		(layer "In5.Cu")
	)
	(gr_line
		(start 102.176326 -45.404786)
		(end 102.19309 -45.428916)
		(stroke
			(width 0.0508)
			(type default)
		)
		(layer "In5.Cu")
	)
	(gr_arc
		(start 102.200202 -10.83183)
		(mid 102.147688 -10.705017)
		(end 102.020878 -10.652506)
		(stroke
			(width 0.0508)
			(type default)
		)
		(layer "In5.Cu")
	)
	(gr_line
		(start 102.200202 -10.83183)
		(end 102.200202 -11.20013)
		(stroke
			(width 0.0508)
			(type default)
		)
		(layer "In5.Cu")
	)
	(gr_line
		(start 102.200202 -9.800082)
		(end 102.200202 -10.168382)
		(stroke
			(width 0.0508)
			(type default)
		)
		(layer "In5.Cu")
	)
	(gr_line
		(start 102.248462 -37.649912)
		(end 102.252526 -37.668962)
		(stroke
			(width 0.0508)
			(type default)
		)
		(layer "In5.Cu")
	)
	(gr_line
		(start 102.249224 -37.688266)
		(end 102.249224 -37.68852)
		(stroke
			(width 0.0508)
			(type default)
		)
		(layer "In5.Cu")
	)
	(gr_line
		(start 102.249224 -37.688266)
		(end 102.252526 -37.668962)
		(stroke
			(width 0.0508)
			(type default)
		)
		(layer "In5.Cu")
	)
	(gr_line
		(start 102.351586 -50.563526)
		(end 102.367588 -50.579528)
		(stroke
			(width 0.04445)
			(type default)
		)
		(layer "In5.Cu")
	)
	(gr_line
		(start 102.351586 -50.541428)
		(end 102.351586 -50.563526)
		(stroke
			(width 0.04445)
			(type default)
		)
		(layer "In5.Cu")
	)
	(gr_line
		(start 102.369366 -50.581306)
		(end 102.408736 -50.620676)
		(stroke
			(width 0.04445)
			(type default)
		)
		(layer "In5.Cu")
	)
	(gr_line
		(start 102.413308 -44.993306)
		(end 102.45725 -45.241718)
		(stroke
			(width 0.0508)
			(type default)
		)
		(layer "In5.Cu")
	)
	(gr_line
		(start 102.43312 -106.954066)
		(end 102.43439 -106.949748)
		(stroke
			(width 0.0508)
			(type default)
		)
		(layer "In5.Cu")
	)
	(gr_line
		(start 102.453694 -102.801928)
		(end 102.459028 -102.7938)
		(stroke
			(width 0.0508)
			(type default)
		)
		(layer "In5.Cu")
	)
	(gr_line
		(start 102.486206 -46.06798)
		(end 102.61219 -46.661832)
		(stroke
			(width 0.0508)
			(type default)
		)
		(layer "In5.Cu")
	)
	(gr_line
		(start 102.599236 -50.620676)
		(end 102.638606 -50.581306)
		(stroke
			(width 0.04445)
			(type default)
		)
		(layer "In5.Cu")
	)
	(gr_line
		(start 102.628446 -49.938178)
		(end 102.656386 -49.981358)
		(stroke
			(width 0.0508)
			(type default)
		)
		(layer "In5.Cu")
	)
	(gr_line
		(start 102.640384 -50.579528)
		(end 102.656386 -50.563526)
		(stroke
			(width 0.04445)
			(type default)
		)
		(layer "In5.Cu")
	)
	(gr_line
		(start 102.656132 -106.194606)
		(end 102.67696 -106.122978)
		(stroke
			(width 0.0508)
			(type default)
		)
		(layer "In5.Cu")
	)
	(gr_line
		(start 102.656386 -50.541428)
		(end 102.656386 -50.563526)
		(stroke
			(width 0.04445)
			(type default)
		)
		(layer "In5.Cu")
	)
	(gr_line
		(start 102.67696 -106.122978)
		(end 102.739952 -106.082084)
		(stroke
			(width 0.0508)
			(type default)
		)
		(layer "In5.Cu")
	)
	(gr_line
		(start 102.690168 -45.606462)
		(end 102.704392 -45.626782)
		(stroke
			(width 0.0508)
			(type default)
		)
		(layer "In5.Cu")
	)
	(gr_line
		(start 102.691184 -47.034196)
		(end 102.695248 -47.052992)
		(stroke
			(width 0.0508)
			(type default)
		)
		(layer "In5.Cu")
	)
	(gr_line
		(start 102.695248 -47.052992)
		(end 102.705408 -47.06874)
		(stroke
			(width 0.0508)
			(type default)
		)
		(layer "In5.Cu")
	)
	(gr_line
		(start 102.704392 -45.626782)
		(end 102.709472 -45.650912)
		(stroke
			(width 0.0508)
			(type default)
		)
		(layer "In5.Cu")
	)
	(gr_line
		(start 102.714298 -48.904652)
		(end 103.044752 -49.413922)
		(stroke
			(width 0.0508)
			(type default)
		)
		(layer "In5.Cu")
	)
	(gr_line
		(start 102.750112 -108.650024)
		(end 103.004874 -108.174028)
		(stroke
			(width 0.0508)
			(type default)
		)
		(layer "In5.Cu")
	)
	(gr_line
		(start 102.750112 -104.84993)
		(end 103.004874 -104.373934)
		(stroke
			(width 0.0508)
			(type default)
		)
		(layer "In5.Cu")
	)
	(gr_line
		(start 102.779068 -45.967396)
		(end 103.001826 -46.112176)
		(stroke
			(width 0.0508)
			(type default)
		)
		(layer "In5.Cu")
	)
	(gr_line
		(start 102.860856 -102.17531)
		(end 102.874572 -102.15372)
		(stroke
			(width 0.0508)
			(type default)
		)
		(layer "In5.Cu")
	)
	(gr_line
		(start 102.874572 -102.15372)
		(end 102.896162 -102.140004)
		(stroke
			(width 0.0508)
			(type default)
		)
		(layer "In5.Cu")
	)
	(gr_line
		(start 102.920292 -46.633384)
		(end 103.065326 -46.410372)
		(stroke
			(width 0.0508)
			(type default)
		)
		(layer "In5.Cu")
	)
	(gr_line
		(start 102.935278 -25.105106)
		(end 102.94493 -25.120092)
		(stroke
			(width 0.0508)
			(type default)
		)
		(layer "In5.Cu")
	)
	(gr_line
		(start 102.94493 -25.120092)
		(end 102.94874 -25.137618)
		(stroke
			(width 0.0508)
			(type default)
		)
		(layer "In5.Cu")
	)
	(gr_line
		(start 102.951788 -48.706278)
		(end 103.212138 -48.76165)
		(stroke
			(width 0.0508)
			(type default)
		)
		(layer "In5.Cu")
	)
	(gr_line
		(start 103.000048 -52.684172)
		(end 103.000048 -53.000148)
		(stroke
			(width 0.04445)
			(type default)
		)
		(layer "In5.Cu")
	)
	(gr_arc
		(start 103.000048 -52.315872)
		(mid 103.026086 -52.378734)
		(end 103.088948 -52.404772)
		(stroke
			(width 0.04445)
			(type default)
		)
		(layer "In5.Cu")
	)
	(gr_line
		(start 103.000048 -52.00015)
		(end 103.000048 -52.315872)
		(stroke
			(width 0.04445)
			(type default)
		)
		(layer "In5.Cu")
	)
	(gr_line
		(start 103.001826 -46.112176)
		(end 103.065326 -46.410372)
		(stroke
			(width 0.0508)
			(type default)
		)
		(layer "In5.Cu")
	)
	(gr_arc
		(start 103.004874 -108.174028)
		(mid 103.012583 -108.096582)
		(end 102.963218 -108.03636)
		(stroke
			(width 0.0508)
			(type default)
		)
		(layer "In5.Cu")
	)
	(gr_arc
		(start 103.004874 -104.373934)
		(mid 103.012679 -104.296433)
		(end 102.963218 -104.236266)
		(stroke
			(width 0.0508)
			(type default)
		)
		(layer "In5.Cu")
	)
	(gr_arc
		(start 103.088948 -52.595272)
		(mid 103.026045 -52.621292)
		(end 103.000048 -52.684172)
		(stroke
			(width 0.04445)
			(type default)
		)
		(layer "In5.Cu")
	)
	(gr_arc
		(start 103.107236 -107.767628)
		(mid 103.184682 -107.775337)
		(end 103.244904 -107.725972)
		(stroke
			(width 0.0508)
			(type default)
		)
		(layer "In5.Cu")
	)
	(gr_arc
		(start 103.107236 -103.967534)
		(mid 103.184682 -103.975243)
		(end 103.244904 -103.925878)
		(stroke
			(width 0.0508)
			(type default)
		)
		(layer "In5.Cu")
	)
	(gr_line
		(start 103.212138 -48.76165)
		(end 103.378 -49.017428)
		(stroke
			(width 0.0508)
			(type default)
		)
		(layer "In5.Cu")
	)
	(gr_line
		(start 103.244904 -107.725972)
		(end 103.49992 -107.249976)
		(stroke
			(width 0.0508)
			(type default)
		)
		(layer "In5.Cu")
	)
	(gr_line
		(start 103.322628 -49.27727)
		(end 103.378 -49.017428)
		(stroke
			(width 0.0508)
			(type default)
		)
		(layer "In5.Cu")
	)
	(gr_line
		(start 103.347266 -50.546)
		(end 103.363268 -50.562002)
		(stroke
			(width 0.04445)
			(type default)
		)
		(layer "In5.Cu")
	)
	(gr_line
		(start 103.347266 -50.523902)
		(end 103.347266 -50.546)
		(stroke
			(width 0.04445)
			(type default)
		)
		(layer "In5.Cu")
	)
	(gr_line
		(start 103.359204 -15.367508)
		(end 103.363014 -15.385034)
		(stroke
			(width 0.0508)
			(type default)
		)
		(layer "In5.Cu")
	)
	(gr_line
		(start 103.363014 -15.385034)
		(end 103.372666 -15.40002)
		(stroke
			(width 0.0508)
			(type default)
		)
		(layer "In5.Cu")
	)
	(gr_line
		(start 103.365046 -50.56378)
		(end 103.404416 -50.60315)
		(stroke
			(width 0.04445)
			(type default)
		)
		(layer "In5.Cu")
	)
	(gr_line
		(start 103.379524 -105.667302)
		(end 103.39451 -105.65765)
		(stroke
			(width 0.0508)
			(type default)
		)
		(layer "In5.Cu")
	)
	(gr_line
		(start 103.39451 -105.65765)
		(end 103.412036 -105.65384)
		(stroke
			(width 0.0508)
			(type default)
		)
		(layer "In5.Cu")
	)
	(gr_line
		(start 103.39705 -37.919406)
		(end 103.401368 -37.940234)
		(stroke
			(width 0.0508)
			(type default)
		)
		(layer "In5.Cu")
	)
	(gr_line
		(start 103.397558 -37.961316)
		(end 103.401368 -37.940234)
		(stroke
			(width 0.0508)
			(type default)
		)
		(layer "In5.Cu")
	)
	(gr_line
		(start 103.418132 -42.320972)
		(end 103.420926 -42.336974)
		(stroke
			(width 0.0508)
			(type default)
		)
		(layer "In5.Cu")
	)
	(gr_line
		(start 103.418132 -42.320972)
		(end 103.421434 -42.302938)
		(stroke
			(width 0.0508)
			(type default)
		)
		(layer "In5.Cu")
	)
	(gr_line
		(start 103.420926 -42.337228)
		(end 103.420926 -42.337736)
		(stroke
			(width 0.0508)
			(type default)
		)
		(layer "In5.Cu")
	)
	(gr_line
		(start 103.426514 -42.3672)
		(end 103.4288 -42.380662)
		(stroke
			(width 0.0508)
			(type default)
		)
		(layer "In5.Cu")
	)
	(gr_line
		(start 103.427022 -42.371772)
		(end 103.4288 -42.380662)
		(stroke
			(width 0.0508)
			(type default)
		)
		(layer "In5.Cu")
	)
	(gr_arc
		(start 103.49992 -103.450136)
		(mid 103.372092 -103.687835)
		(end 103.244904 -103.925878)
		(stroke
			(width 0.0508)
			(type default)
		)
		(layer "In5.Cu")
	)
	(gr_line
		(start 103.553006 -49.636426)
		(end 103.563166 -49.652174)
		(stroke
			(width 0.0508)
			(type default)
		)
		(layer "In5.Cu")
	)
	(gr_line
		(start 103.563166 -49.652174)
		(end 103.566722 -49.6697)
		(stroke
			(width 0.0508)
			(type default)
		)
		(layer "In5.Cu")
	)
	(gr_line
		(start 103.594916 -50.60315)
		(end 103.634286 -50.56378)
		(stroke
			(width 0.04445)
			(type default)
		)
		(layer "In5.Cu")
	)
	(gr_line
		(start 103.636064 -50.562002)
		(end 103.652066 -50.546)
		(stroke
			(width 0.04445)
			(type default)
		)
		(layer "In5.Cu")
	)
	(gr_line
		(start 103.652066 -50.523902)
		(end 103.652066 -50.546)
		(stroke
			(width 0.04445)
			(type default)
		)
		(layer "In5.Cu")
	)
	(gr_line
		(start 103.677466 -101.632258)
		(end 103.692452 -101.622606)
		(stroke
			(width 0.0508)
			(type default)
		)
		(layer "In5.Cu")
	)
	(gr_line
		(start 103.692452 -101.622606)
		(end 103.709978 -101.618796)
		(stroke
			(width 0.0508)
			(type default)
		)
		(layer "In5.Cu")
	)
	(gr_line
		(start 103.695246 -45.376338)
		(end 103.700326 -45.404532)
		(stroke
			(width 0.0508)
			(type default)
		)
		(layer "In5.Cu")
	)
	(gr_line
		(start 103.700326 -45.404532)
		(end 103.716328 -45.427138)
		(stroke
			(width 0.0508)
			(type default)
		)
		(layer "In5.Cu")
	)
	(gr_arc
		(start 103.820722 -11.547602)
		(mid 103.947523 -11.495079)
		(end 104.000046 -11.368278)
		(stroke
			(width 0.0508)
			(type default)
		)
		(layer "In5.Cu")
	)
	(gr_line
		(start 103.867966 -23.69058)
		(end 103.877618 -23.705566)
		(stroke
			(width 0.0508)
			(type default)
		)
		(layer "In5.Cu")
	)
	(gr_line
		(start 103.877618 -23.705566)
		(end 103.881428 -23.723092)
		(stroke
			(width 0.0508)
			(type default)
		)
		(layer "In5.Cu")
	)
	(gr_line
		(start 103.918766 -45.716444)
		(end 103.943658 -45.75175)
		(stroke
			(width 0.0508)
			(type default)
		)
		(layer "In5.Cu")
	)
	(gr_line
		(start 103.943658 -45.75175)
		(end 103.94442 -45.755814)
		(stroke
			(width 0.0508)
			(type default)
		)
		(layer "In5.Cu")
	)
	(gr_line
		(start 104.000046 -51.684174)
		(end 104.000046 -52.00015)
		(stroke
			(width 0.04445)
			(type default)
		)
		(layer "In5.Cu")
	)
	(gr_arc
		(start 104.000046 -51.315874)
		(mid 104.026084 -51.378736)
		(end 104.088946 -51.404774)
		(stroke
			(width 0.04445)
			(type default)
		)
		(layer "In5.Cu")
	)
	(gr_line
		(start 104.000046 -51.000152)
		(end 104.000046 -51.315874)
		(stroke
			(width 0.04445)
			(type default)
		)
		(layer "In5.Cu")
	)
	(gr_arc
		(start 104.000046 -12.031726)
		(mid 103.947534 -11.9049)
		(end 103.820722 -11.852402)
		(stroke
			(width 0.0508)
			(type default)
		)
		(layer "In5.Cu")
	)
	(gr_line
		(start 104.000046 -12.031726)
		(end 104.000046 -12.400026)
		(stroke
			(width 0.0508)
			(type default)
		)
		(layer "In5.Cu")
	)
	(gr_line
		(start 104.000046 -10.999978)
		(end 104.000046 -11.368278)
		(stroke
			(width 0.0508)
			(type default)
		)
		(layer "In5.Cu")
	)
	(gr_arc
		(start 104.088946 -51.595274)
		(mid 104.026045 -51.621294)
		(end 104.000046 -51.684174)
		(stroke
			(width 0.04445)
			(type default)
		)
		(layer "In5.Cu")
	)
	(gr_line
		(start 104.097836 -46.477682)
		(end 104.224328 -47.072804)
		(stroke
			(width 0.0508)
			(type default)
		)
		(layer "In5.Cu")
	)
	(gr_line
		(start 104.168448 -45.541438)
		(end 104.19715 -45.582586)
		(stroke
			(width 0.0508)
			(type default)
		)
		(layer "In5.Cu")
	)
	(gr_line
		(start 104.2162 -45.60951)
		(end 104.23017 -45.629576)
		(stroke
			(width 0.0508)
			(type default)
		)
		(layer "In5.Cu")
	)
	(gr_line
		(start 104.23017 -45.629576)
		(end 104.233726 -45.65015)
		(stroke
			(width 0.0508)
			(type default)
		)
		(layer "In5.Cu")
	)
	(gr_line
		(start 104.238806 -45.675804)
		(end 104.244394 -45.701712)
		(stroke
			(width 0.0508)
			(type default)
		)
		(layer "In5.Cu")
	)
	(gr_line
		(start 104.30383 -47.4472)
		(end 104.30764 -47.464726)
		(stroke
			(width 0.0508)
			(type default)
		)
		(layer "In5.Cu")
	)
	(gr_line
		(start 104.30764 -47.464726)
		(end 104.317292 -47.479712)
		(stroke
			(width 0.0508)
			(type default)
		)
		(layer "In5.Cu")
	)
	(gr_line
		(start 104.351582 -50.563526)
		(end 104.367584 -50.579528)
		(stroke
			(width 0.04445)
			(type default)
		)
		(layer "In5.Cu")
	)
	(gr_line
		(start 104.351582 -50.541428)
		(end 104.351582 -50.563526)
		(stroke
			(width 0.04445)
			(type default)
		)
		(layer "In5.Cu")
	)
	(gr_line
		(start 104.369362 -50.581306)
		(end 104.408732 -50.620676)
		(stroke
			(width 0.04445)
			(type default)
		)
		(layer "In5.Cu")
	)
	(gr_line
		(start 104.390952 -46.378622)
		(end 104.613964 -46.523656)
		(stroke
			(width 0.0508)
			(type default)
		)
		(layer "In5.Cu")
	)
	(gr_line
		(start 104.499664 -49.271428)
		(end 104.509316 -49.286414)
		(stroke
			(width 0.0508)
			(type default)
		)
		(layer "In5.Cu")
	)
	(gr_line
		(start 104.509316 -49.286414)
		(end 104.513126 -49.30394)
		(stroke
			(width 0.0508)
			(type default)
		)
		(layer "In5.Cu")
	)
	(gr_line
		(start 104.53243 -47.044864)
		(end 104.677464 -46.821852)
		(stroke
			(width 0.0508)
			(type default)
		)
		(layer "In5.Cu")
	)
	(gr_line
		(start 104.570276 -38.360604)
		(end 104.57561 -38.335458)
		(stroke
			(width 0.0508)
			(type default)
		)
		(layer "In5.Cu")
	)
	(gr_line
		(start 104.570276 -38.310312)
		(end 104.57561 -38.335458)
		(stroke
			(width 0.0508)
			(type default)
		)
		(layer "In5.Cu")
	)
	(gr_line
		(start 104.599232 -50.620676)
		(end 104.638602 -50.581306)
		(stroke
			(width 0.04445)
			(type default)
		)
		(layer "In5.Cu")
	)
	(gr_line
		(start 104.613964 -46.523656)
		(end 104.677464 -46.821852)
		(stroke
			(width 0.0508)
			(type default)
		)
		(layer "In5.Cu")
	)
	(gr_line
		(start 104.64038 -50.579528)
		(end 104.656382 -50.563526)
		(stroke
			(width 0.04445)
			(type default)
		)
		(layer "In5.Cu")
	)
	(gr_line
		(start 104.656382 -50.541428)
		(end 104.656382 -50.563526)
		(stroke
			(width 0.04445)
			(type default)
		)
		(layer "In5.Cu")
	)
	(gr_line
		(start 104.73563 -102.89032)
		(end 104.73944 -102.872794)
		(stroke
			(width 0.0508)
			(type default)
		)
		(layer "In5.Cu")
	)
	(gr_line
		(start 104.73944 -102.872794)
		(end 104.748584 -102.858824)
		(stroke
			(width 0.0508)
			(type default)
		)
		(layer "In5.Cu")
	)
	(gr_line
		(start 104.74071 -106.974386)
		(end 104.742234 -106.9721)
		(stroke
			(width 0.0508)
			(type default)
		)
		(layer "In5.Cu")
	)
	(gr_line
		(start 104.873298 -41.929304)
		(end 104.875838 -41.914318)
		(stroke
			(width 0.0508)
			(type default)
		)
		(layer "In5.Cu")
	)
	(gr_line
		(start 104.873298 -41.929304)
		(end 104.876092 -41.945052)
		(stroke
			(width 0.0508)
			(type default)
		)
		(layer "In5.Cu")
	)
	(gr_line
		(start 104.929432 -22.491446)
		(end 104.939084 -22.506432)
		(stroke
			(width 0.0508)
			(type default)
		)
		(layer "In5.Cu")
	)
	(gr_line
		(start 104.932226 -102.57536)
		(end 104.947212 -102.551992)
		(stroke
			(width 0.0508)
			(type default)
		)
		(layer "In5.Cu")
	)
	(gr_line
		(start 104.939084 -22.506432)
		(end 104.942894 -22.523958)
		(stroke
			(width 0.0508)
			(type default)
		)
		(layer "In5.Cu")
	)
	(gr_line
		(start 104.947212 -102.551992)
		(end 104.97058 -102.536752)
		(stroke
			(width 0.0508)
			(type default)
		)
		(layer "In5.Cu")
	)
	(gr_line
		(start 104.964484 -106.629454)
		(end 104.97947 -106.606086)
		(stroke
			(width 0.0508)
			(type default)
		)
		(layer "In5.Cu")
	)
	(gr_line
		(start 104.97947 -106.606086)
		(end 105.002584 -106.5911)
		(stroke
			(width 0.0508)
			(type default)
		)
		(layer "In5.Cu")
	)
	(gr_line
		(start 105.000044 -108.650024)
		(end 105.25506 -108.174028)
		(stroke
			(width 0.0508)
			(type default)
		)
		(layer "In5.Cu")
	)
	(gr_line
		(start 105.000044 -104.84993)
		(end 105.254806 -104.373934)
		(stroke
			(width 0.0508)
			(type default)
		)
		(layer "In5.Cu")
	)
	(gr_line
		(start 105.000044 -52.684172)
		(end 105.000044 -53.000148)
		(stroke
			(width 0.04445)
			(type default)
		)
		(layer "In5.Cu")
	)
	(gr_arc
		(start 105.000044 -52.315872)
		(mid 105.026082 -52.378734)
		(end 105.088944 -52.404772)
		(stroke
			(width 0.04445)
			(type default)
		)
		(layer "In5.Cu")
	)
	(gr_line
		(start 105.000044 -52.00015)
		(end 105.000044 -52.315872)
		(stroke
			(width 0.04445)
			(type default)
		)
		(layer "In5.Cu")
	)
	(gr_arc
		(start 105.088944 -52.595272)
		(mid 105.026044 -52.621293)
		(end 105.000044 -52.684172)
		(stroke
			(width 0.04445)
			(type default)
		)
		(layer "In5.Cu")
	)
	(gr_line
		(start 105.191306 -108.024676)
		(end 105.192068 -108.025184)
		(stroke
			(width 0.0508)
			(type default)
		)
		(layer "In5.Cu")
	)
	(gr_line
		(start 105.192068 -108.025184)
		(end 105.1941 -108.0262)
		(stroke
			(width 0.0508)
			(type default)
		)
		(layer "In5.Cu")
	)
	(gr_line
		(start 105.195878 -108.027216)
		(end 105.19664 -108.027724)
		(stroke
			(width 0.0508)
			(type default)
		)
		(layer "In5.Cu")
	)
	(gr_line
		(start 105.219246 -45.376338)
		(end 105.224326 -45.404532)
		(stroke
			(width 0.0508)
			(type default)
		)
		(layer "In5.Cu")
	)
	(gr_line
		(start 105.224326 -45.404532)
		(end 105.240328 -45.427138)
		(stroke
			(width 0.0508)
			(type default)
		)
		(layer "In5.Cu")
	)
	(gr_arc
		(start 105.254806 -104.373934)
		(mid 105.262608 -104.296431)
		(end 105.21315 -104.236266)
		(stroke
			(width 0.0508)
			(type default)
		)
		(layer "In5.Cu")
	)
	(gr_arc
		(start 105.25506 -108.174028)
		(mid 105.262862 -108.096531)
		(end 105.213404 -108.03636)
		(stroke
			(width 0.0508)
			(type default)
		)
		(layer "In5.Cu")
	)
	(gr_line
		(start 105.268776 -106.41838)
		(end 105.284524 -106.40822)
		(stroke
			(width 0.0508)
			(type default)
		)
		(layer "In5.Cu")
	)
	(gr_line
		(start 105.284524 -106.40822)
		(end 105.303066 -106.40441)
		(stroke
			(width 0.0508)
			(type default)
		)
		(layer "In5.Cu")
	)
	(gr_line
		(start 105.3338 -107.754928)
		(end 105.334562 -107.755436)
		(stroke
			(width 0.0508)
			(type default)
		)
		(layer "In5.Cu")
	)
	(gr_line
		(start 105.347262 -50.546)
		(end 105.363264 -50.562002)
		(stroke
			(width 0.04445)
			(type default)
		)
		(layer "In5.Cu")
	)
	(gr_line
		(start 105.347262 -50.523902)
		(end 105.347262 -50.546)
		(stroke
			(width 0.04445)
			(type default)
		)
		(layer "In5.Cu")
	)
	(gr_line
		(start 105.355644 -107.766612)
		(end 105.35666 -107.76712)
		(stroke
			(width 0.0508)
			(type default)
		)
		(layer "In5.Cu")
	)
	(gr_arc
		(start 105.357168 -103.967534)
		(mid 105.434666 -103.975342)
		(end 105.494836 -103.925878)
		(stroke
			(width 0.0508)
			(type default)
		)
		(layer "In5.Cu")
	)
	(gr_arc
		(start 105.357422 -107.767628)
		(mid 105.434868 -107.775337)
		(end 105.49509 -107.725972)
		(stroke
			(width 0.0508)
			(type default)
		)
		(layer "In5.Cu")
	)
	(gr_line
		(start 105.365042 -50.56378)
		(end 105.404412 -50.60315)
		(stroke
			(width 0.04445)
			(type default)
		)
		(layer "In5.Cu")
	)
	(gr_line
		(start 105.430066 -102.238556)
		(end 105.445052 -102.228904)
		(stroke
			(width 0.0508)
			(type default)
		)
		(layer "In5.Cu")
	)
	(gr_line
		(start 105.433876 -48.638968)
		(end 105.443528 -48.653954)
		(stroke
			(width 0.0508)
			(type default)
		)
		(layer "In5.Cu")
	)
	(gr_line
		(start 105.443528 -48.653954)
		(end 105.447338 -48.67148)
		(stroke
			(width 0.0508)
			(type default)
		)
		(layer "In5.Cu")
	)
	(gr_line
		(start 105.445052 -102.228904)
		(end 105.462578 -102.225094)
		(stroke
			(width 0.0508)
			(type default)
		)
		(layer "In5.Cu")
	)
	(gr_line
		(start 105.451148 -16.629888)
		(end 105.454958 -16.647414)
		(stroke
			(width 0.0508)
			(type default)
		)
		(layer "In5.Cu")
	)
	(gr_line
		(start 105.454958 -16.647414)
		(end 105.46461 -16.6624)
		(stroke
			(width 0.0508)
			(type default)
		)
		(layer "In5.Cu")
	)
	(gr_line
		(start 105.49509 -107.725972)
		(end 105.750106 -107.249976)
		(stroke
			(width 0.0508)
			(type default)
		)
		(layer "In5.Cu")
	)
	(gr_line
		(start 105.594912 -50.60315)
		(end 105.634282 -50.56378)
		(stroke
			(width 0.04445)
			(type default)
		)
		(layer "In5.Cu")
	)
	(gr_arc
		(start 105.62082 -10.347706)
		(mid 105.747621 -10.295183)
		(end 105.800144 -10.168382)
		(stroke
			(width 0.0508)
			(type default)
		)
		(layer "In5.Cu")
	)
	(gr_line
		(start 105.63606 -50.562002)
		(end 105.652062 -50.546)
		(stroke
			(width 0.04445)
			(type default)
		)
		(layer "In5.Cu")
	)
	(gr_line
		(start 105.652062 -50.523902)
		(end 105.652062 -50.546)
		(stroke
			(width 0.04445)
			(type default)
		)
		(layer "In5.Cu")
	)
	(gr_line
		(start 105.6894 -46.81982)
		(end 105.815638 -47.413672)
		(stroke
			(width 0.0508)
			(type default)
		)
		(layer "In5.Cu")
	)
	(gr_line
		(start 105.701084 -101.195632)
		(end 105.701846 -101.195378)
		(stroke
			(width 0.0508)
			(type default)
		)
		(layer "In5.Cu")
	)
	(gr_line
		(start 105.740962 -45.611542)
		(end 105.756964 -45.634148)
		(stroke
			(width 0.0508)
			(type default)
		)
		(layer "In5.Cu")
	)
	(gr_arc
		(start 105.750106 -103.450136)
		(mid 105.622101 -103.687809)
		(end 105.494836 -103.925878)
		(stroke
			(width 0.0508)
			(type default)
		)
		(layer "In5.Cu")
	)
	(gr_line
		(start 105.756964 -45.634148)
		(end 105.762044 -45.662342)
		(stroke
			(width 0.0508)
			(type default)
		)
		(layer "In5.Cu")
	)
	(gr_line
		(start 105.762552 -20.478242)
		(end 105.772204 -20.493228)
		(stroke
			(width 0.0508)
			(type default)
		)
		(layer "In5.Cu")
	)
	(gr_line
		(start 105.764584 -101.494082)
		(end 105.765346 -101.493828)
		(stroke
			(width 0.0508)
			(type default)
		)
		(layer "In5.Cu")
	)
	(gr_line
		(start 105.772204 -20.493228)
		(end 105.776014 -20.510754)
		(stroke
			(width 0.0508)
			(type default)
		)
		(layer "In5.Cu")
	)
	(gr_line
		(start 105.783634 -38.477444)
		(end 105.787952 -38.498272)
		(stroke
			(width 0.0508)
			(type default)
		)
		(layer "In5.Cu")
	)
	(gr_line
		(start 105.784142 -38.519354)
		(end 105.787952 -38.498272)
		(stroke
			(width 0.0508)
			(type default)
		)
		(layer "In5.Cu")
	)
	(gr_arc
		(start 105.800144 -10.83183)
		(mid 105.747633 -10.705002)
		(end 105.62082 -10.652506)
		(stroke
			(width 0.0508)
			(type default)
		)
		(layer "In5.Cu")
	)
	(gr_line
		(start 105.800144 -10.83183)
		(end 105.800144 -11.20013)
		(stroke
			(width 0.0508)
			(type default)
		)
		(layer "In5.Cu")
	)
	(gr_line
		(start 105.800144 -9.800082)
		(end 105.800144 -10.168382)
		(stroke
			(width 0.0508)
			(type default)
		)
		(layer "In5.Cu")
	)
	(gr_line
		(start 105.982262 -46.719236)
		(end 106.205274 -46.864016)
		(stroke
			(width 0.0508)
			(type default)
		)
		(layer "In5.Cu")
	)
	(gr_line
		(start 106.000042 -51.684174)
		(end 106.000042 -52.00015)
		(stroke
			(width 0.04445)
			(type default)
		)
		(layer "In5.Cu")
	)
	(gr_arc
		(start 106.000042 -51.315874)
		(mid 106.02608 -51.378736)
		(end 106.088942 -51.404774)
		(stroke
			(width 0.04445)
			(type default)
		)
		(layer "In5.Cu")
	)
	(gr_line
		(start 106.000042 -51.000152)
		(end 106.000042 -51.315874)
		(stroke
			(width 0.04445)
			(type default)
		)
		(layer "In5.Cu")
	)
	(gr_arc
		(start 106.088942 -51.595274)
		(mid 106.026044 -51.621296)
		(end 106.000042 -51.684174)
		(stroke
			(width 0.04445)
			(type default)
		)
		(layer "In5.Cu")
	)
	(gr_line
		(start 106.12374 -47.385224)
		(end 106.26852 -47.161958)
		(stroke
			(width 0.0508)
			(type default)
		)
		(layer "In5.Cu")
	)
	(gr_line
		(start 106.205274 -46.864016)
		(end 106.26852 -47.161958)
		(stroke
			(width 0.0508)
			(type default)
		)
		(layer "In5.Cu")
	)
	(gr_line
		(start 106.299762 -41.376092)
		(end 106.303572 -41.397682)
		(stroke
			(width 0.0508)
			(type default)
		)
		(layer "In5.Cu")
	)
	(gr_line
		(start 106.299762 -41.376092)
		(end 106.30408 -41.355772)
		(stroke
			(width 0.0508)
			(type default)
		)
		(layer "In5.Cu")
	)
	(gr_line
		(start 106.351578 -50.563526)
		(end 106.36758 -50.579528)
		(stroke
			(width 0.04445)
			(type default)
		)
		(layer "In5.Cu")
	)
	(gr_line
		(start 106.351578 -50.541428)
		(end 106.351578 -50.563526)
		(stroke
			(width 0.04445)
			(type default)
		)
		(layer "In5.Cu")
	)
	(gr_line
		(start 106.369358 -50.581306)
		(end 106.408728 -50.620676)
		(stroke
			(width 0.04445)
			(type default)
		)
		(layer "In5.Cu")
	)
	(gr_line
		(start 106.599228 -50.620676)
		(end 106.638598 -50.581306)
		(stroke
			(width 0.04445)
			(type default)
		)
		(layer "In5.Cu")
	)
	(gr_line
		(start 106.640376 -50.579528)
		(end 106.656378 -50.563526)
		(stroke
			(width 0.04445)
			(type default)
		)
		(layer "In5.Cu")
	)
	(gr_line
		(start 106.656378 -50.541428)
		(end 106.656378 -50.563526)
		(stroke
			(width 0.04445)
			(type default)
		)
		(layer "In5.Cu")
	)
	(gr_line
		(start 106.678984 -101.966268)
		(end 106.70413 -101.960934)
		(stroke
			(width 0.0508)
			(type default)
		)
		(layer "In5.Cu")
	)
	(gr_line
		(start 106.70413 -101.960934)
		(end 106.729276 -101.966268)
		(stroke
			(width 0.0508)
			(type default)
		)
		(layer "In5.Cu")
	)
	(gr_line
		(start 106.743246 -45.376084)
		(end 106.748326 -45.404786)
		(stroke
			(width 0.0508)
			(type default)
		)
		(layer "In5.Cu")
	)
	(gr_line
		(start 106.748326 -45.404786)
		(end 106.764836 -45.428154)
		(stroke
			(width 0.0508)
			(type default)
		)
		(layer "In5.Cu")
	)
	(gr_line
		(start 106.947462 -20.34413)
		(end 106.957114 -20.359116)
		(stroke
			(width 0.0508)
			(type default)
		)
		(layer "In5.Cu")
	)
	(gr_line
		(start 106.957114 -20.359116)
		(end 106.960924 -20.376642)
		(stroke
			(width 0.0508)
			(type default)
		)
		(layer "In5.Cu")
	)
	(gr_line
		(start 107.00004 -52.684172)
		(end 107.00004 -53.000148)
		(stroke
			(width 0.04445)
			(type default)
		)
		(layer "In5.Cu")
	)
	(gr_arc
		(start 107.00004 -52.315872)
		(mid 107.026078 -52.378734)
		(end 107.08894 -52.404772)
		(stroke
			(width 0.04445)
			(type default)
		)
		(layer "In5.Cu")
	)
	(gr_line
		(start 107.00004 -52.00015)
		(end 107.00004 -52.315872)
		(stroke
			(width 0.04445)
			(type default)
		)
		(layer "In5.Cu")
	)
	(gr_arc
		(start 107.08894 -52.595272)
		(mid 107.026042 -52.621294)
		(end 107.00004 -52.684172)
		(stroke
			(width 0.04445)
			(type default)
		)
		(layer "In5.Cu")
	)
	(gr_line
		(start 107.117134 -38.995858)
		(end 107.122468 -38.970712)
		(stroke
			(width 0.0508)
			(type default)
		)
		(layer "In5.Cu")
	)
	(gr_line
		(start 107.117134 -38.945566)
		(end 107.122468 -38.970712)
		(stroke
			(width 0.0508)
			(type default)
		)
		(layer "In5.Cu")
	)
	(gr_line
		(start 107.15244 -17.290542)
		(end 107.15625 -17.308068)
		(stroke
			(width 0.0508)
			(type default)
		)
		(layer "In5.Cu")
	)
	(gr_line
		(start 107.15625 -17.308068)
		(end 107.165902 -17.323054)
		(stroke
			(width 0.0508)
			(type default)
		)
		(layer "In5.Cu")
	)
	(gr_line
		(start 107.248452 -100.866956)
		(end 107.273598 -100.861622)
		(stroke
			(width 0.0508)
			(type default)
		)
		(layer "In5.Cu")
	)
	(gr_line
		(start 107.263946 -45.610272)
		(end 107.27563 -45.626782)
		(stroke
			(width 0.0508)
			(type default)
		)
		(layer "In5.Cu")
	)
	(gr_line
		(start 107.273598 -100.861622)
		(end 107.298744 -100.866956)
		(stroke
			(width 0.0508)
			(type default)
		)
		(layer "In5.Cu")
	)
	(gr_line
		(start 107.277662 -45.62983)
		(end 107.278932 -45.636688)
		(stroke
			(width 0.0508)
			(type default)
		)
		(layer "In5.Cu")
	)
	(gr_line
		(start 107.278932 -45.636688)
		(end 107.282234 -45.65269)
		(stroke
			(width 0.0508)
			(type default)
		)
		(layer "In5.Cu")
	)
	(gr_line
		(start 107.347258 -50.546)
		(end 107.36326 -50.562002)
		(stroke
			(width 0.04445)
			(type default)
		)
		(layer "In5.Cu")
	)
	(gr_line
		(start 107.347258 -50.523902)
		(end 107.347258 -50.546)
		(stroke
			(width 0.04445)
			(type default)
		)
		(layer "In5.Cu")
	)
	(gr_line
		(start 107.358434 -47.476664)
		(end 107.48518 -48.072548)
		(stroke
			(width 0.0508)
			(type default)
		)
		(layer "In5.Cu")
	)
	(gr_line
		(start 107.365038 -50.56378)
		(end 107.404408 -50.60315)
		(stroke
			(width 0.04445)
			(type default)
		)
		(layer "In5.Cu")
	)
	(gr_arc
		(start 107.420664 -11.547602)
		(mid 107.547465 -11.495079)
		(end 107.599988 -11.368278)
		(stroke
			(width 0.0508)
			(type default)
		)
		(layer "In5.Cu")
	)
	(gr_line
		(start 107.594908 -50.60315)
		(end 107.634278 -50.56378)
		(stroke
			(width 0.04445)
			(type default)
		)
		(layer "In5.Cu")
	)
	(gr_arc
		(start 107.599988 -12.031726)
		(mid 107.547472 -11.904921)
		(end 107.420664 -11.852402)
		(stroke
			(width 0.0508)
			(type default)
		)
		(layer "In5.Cu")
	)
	(gr_line
		(start 107.599988 -12.031726)
		(end 107.599988 -12.400026)
		(stroke
			(width 0.0508)
			(type default)
		)
		(layer "In5.Cu")
	)
	(gr_line
		(start 107.599988 -10.999978)
		(end 107.599988 -11.368278)
		(stroke
			(width 0.0508)
			(type default)
		)
		(layer "In5.Cu")
	)
	(gr_line
		(start 107.636056 -50.562002)
		(end 107.652058 -50.546)
		(stroke
			(width 0.04445)
			(type default)
		)
		(layer "In5.Cu")
	)
	(gr_line
		(start 107.651804 -47.378366)
		(end 107.874816 -47.5234)
		(stroke
			(width 0.0508)
			(type default)
		)
		(layer "In5.Cu")
	)
	(gr_line
		(start 107.652058 -50.523902)
		(end 107.652058 -50.546)
		(stroke
			(width 0.04445)
			(type default)
		)
		(layer "In5.Cu")
	)
	(gr_line
		(start 107.698794 -40.55618)
		(end 107.702604 -40.577262)
		(stroke
			(width 0.0508)
			(type default)
		)
		(layer "In5.Cu")
	)
	(gr_line
		(start 107.698794 -40.55618)
		(end 107.703112 -40.535352)
		(stroke
			(width 0.0508)
			(type default)
		)
		(layer "In5.Cu")
	)
	(gr_line
		(start 107.793536 -48.044354)
		(end 107.938316 -47.821596)
		(stroke
			(width 0.0508)
			(type default)
		)
		(layer "In5.Cu")
	)
	(gr_line
		(start 107.84967 -48.371252)
		(end 107.855004 -48.345852)
		(stroke
			(width 0.0508)
			(type default)
		)
		(layer "In5.Cu")
	)
	(gr_line
		(start 107.84967 -48.320706)
		(end 107.855004 -48.345852)
		(stroke
			(width 0.0508)
			(type default)
		)
		(layer "In5.Cu")
	)
	(gr_line
		(start 107.874816 -47.5234)
		(end 107.938316 -47.821596)
		(stroke
			(width 0.0508)
			(type default)
		)
		(layer "In5.Cu")
	)
	(gr_line
		(start 107.937046 -19.909028)
		(end 107.946698 -19.924014)
		(stroke
			(width 0.0508)
			(type default)
		)
		(layer "In5.Cu")
	)
	(gr_line
		(start 107.946698 -19.924014)
		(end 107.950508 -19.94154)
		(stroke
			(width 0.0508)
			(type default)
		)
		(layer "In5.Cu")
	)
	(gr_line
		(start 108.000038 -51.684174)
		(end 108.000038 -52.00015)
		(stroke
			(width 0.04445)
			(type default)
		)
		(layer "In5.Cu")
	)
	(gr_arc
		(start 108.000038 -51.315874)
		(mid 108.026076 -51.378736)
		(end 108.088938 -51.404774)
		(stroke
			(width 0.04445)
			(type default)
		)
		(layer "In5.Cu")
	)
	(gr_line
		(start 108.000038 -51.000152)
		(end 108.000038 -51.315874)
		(stroke
			(width 0.04445)
			(type default)
		)
		(layer "In5.Cu")
	)
	(gr_arc
		(start 108.088938 -51.595274)
		(mid 108.026042 -51.621297)
		(end 108.000038 -51.684174)
		(stroke
			(width 0.04445)
			(type default)
		)
		(layer "In5.Cu")
	)
	(gr_line
		(start 108.351574 -50.563526)
		(end 108.367576 -50.579528)
		(stroke
			(width 0.04445)
			(type default)
		)
		(layer "In5.Cu")
	)
	(gr_line
		(start 108.351574 -50.541428)
		(end 108.351574 -50.563526)
		(stroke
			(width 0.04445)
			(type default)
		)
		(layer "In5.Cu")
	)
	(gr_line
		(start 108.369354 -50.581306)
		(end 108.408724 -50.620676)
		(stroke
			(width 0.04445)
			(type default)
		)
		(layer "In5.Cu")
	)
	(gr_line
		(start 108.387642 -38.781736)
		(end 108.392976 -38.75659)
		(stroke
			(width 0.0508)
			(type default)
		)
		(layer "In5.Cu")
	)
	(gr_line
		(start 108.387642 -38.731444)
		(end 108.392976 -38.75659)
		(stroke
			(width 0.0508)
			(type default)
		)
		(layer "In5.Cu")
	)
	(gr_line
		(start 108.504482 -48.773842)
		(end 108.630466 -48.18126)
		(stroke
			(width 0.0508)
			(type default)
		)
		(layer "In5.Cu")
	)
	(gr_line
		(start 108.599224 -50.620676)
		(end 108.638594 -50.581306)
		(stroke
			(width 0.04445)
			(type default)
		)
		(layer "In5.Cu")
	)
	(gr_line
		(start 108.640372 -50.579528)
		(end 108.656374 -50.563526)
		(stroke
			(width 0.04445)
			(type default)
		)
		(layer "In5.Cu")
	)
	(gr_line
		(start 108.656374 -50.541428)
		(end 108.656374 -50.563526)
		(stroke
			(width 0.04445)
			(type default)
		)
		(layer "In5.Cu")
	)
	(gr_line
		(start 108.797344 -48.874172)
		(end 109.020102 -48.729646)
		(stroke
			(width 0.0508)
			(type default)
		)
		(layer "In5.Cu")
	)
	(gr_line
		(start 108.850938 -19.357848)
		(end 108.86059 -19.372834)
		(stroke
			(width 0.0508)
			(type default)
		)
		(layer "In5.Cu")
	)
	(gr_line
		(start 108.86059 -19.372834)
		(end 108.8644 -19.39036)
		(stroke
			(width 0.0508)
			(type default)
		)
		(layer "In5.Cu")
	)
	(gr_line
		(start 108.938822 -48.208438)
		(end 109.083602 -48.43145)
		(stroke
			(width 0.0508)
			(type default)
		)
		(layer "In5.Cu")
	)
	(gr_line
		(start 109.000036 -52.684172)
		(end 109.000036 -53.000148)
		(stroke
			(width 0.04445)
			(type default)
		)
		(layer "In5.Cu")
	)
	(gr_line
		(start 109.000036 -52.00015)
		(end 109.000036 -52.315872)
		(stroke
			(width 0.04445)
			(type default)
		)
		(layer "In5.Cu")
	)
	(gr_line
		(start 109.013752 -47.843694)
		(end 109.014006 -47.842932)
		(stroke
			(width 0.0508)
			(type default)
		)
		(layer "In5.Cu")
	)
	(gr_line
		(start 109.014006 -47.843186)
		(end 109.018324 -47.822104)
		(stroke
			(width 0.0508)
			(type default)
		)
		(layer "In5.Cu")
	)
	(gr_line
		(start 109.014768 -47.802038)
		(end 109.018324 -47.822104)
		(stroke
			(width 0.0508)
			(type default)
		)
		(layer "In5.Cu")
	)
	(gr_line
		(start 109.020102 -48.729646)
		(end 109.083602 -48.43145)
		(stroke
			(width 0.0508)
			(type default)
		)
		(layer "In5.Cu")
	)
	(gr_arc
		(start 109.088936 -52.595272)
		(mid 109.026041 -52.621296)
		(end 109.000036 -52.684172)
		(stroke
			(width 0.04445)
			(type default)
		)
		(layer "In5.Cu")
	)
	(gr_line
		(start 109.139482 -40.248332)
		(end 109.143292 -40.26916)
		(stroke
			(width 0.0508)
			(type default)
		)
		(layer "In5.Cu")
	)
	(gr_line
		(start 109.139482 -40.248332)
		(end 109.1438 -40.227504)
		(stroke
			(width 0.0508)
			(type default)
		)
		(layer "In5.Cu")
	)
	(gr_arc
		(start 109.220762 -10.347706)
		(mid 109.347563 -10.295183)
		(end 109.400086 -10.168382)
		(stroke
			(width 0.0508)
			(type default)
		)
		(layer "In5.Cu")
	)
	(gr_line
		(start 109.347254 -50.546)
		(end 109.363256 -50.562002)
		(stroke
			(width 0.04445)
			(type default)
		)
		(layer "In5.Cu")
	)
	(gr_line
		(start 109.347254 -50.523902)
		(end 109.347254 -50.546)
		(stroke
			(width 0.04445)
			(type default)
		)
		(layer "In5.Cu")
	)
	(gr_line
		(start 109.365034 -50.56378)
		(end 109.404404 -50.60315)
		(stroke
			(width 0.04445)
			(type default)
		)
		(layer "In5.Cu")
	)
	(gr_arc
		(start 109.400086 -10.83183)
		(mid 109.347572 -10.705023)
		(end 109.220762 -10.652506)
		(stroke
			(width 0.0508)
			(type default)
		)
		(layer "In5.Cu")
	)
	(gr_line
		(start 109.400086 -10.83183)
		(end 109.400086 -11.20013)
		(stroke
			(width 0.0508)
			(type default)
		)
		(layer "In5.Cu")
	)
	(gr_line
		(start 109.400086 -9.800082)
		(end 109.400086 -10.168382)
		(stroke
			(width 0.0508)
			(type default)
		)
		(layer "In5.Cu")
	)
	(gr_line
		(start 109.594904 -50.60315)
		(end 109.634274 -50.56378)
		(stroke
			(width 0.04445)
			(type default)
		)
		(layer "In5.Cu")
	)
	(gr_line
		(start 109.636052 -50.562002)
		(end 109.652054 -50.546)
		(stroke
			(width 0.04445)
			(type default)
		)
		(layer "In5.Cu")
	)
	(gr_line
		(start 109.652054 -50.523902)
		(end 109.652054 -50.546)
		(stroke
			(width 0.04445)
			(type default)
		)
		(layer "In5.Cu")
	)
	(gr_line
		(start 109.70514 -39.052246)
		(end 109.710474 -39.0271)
		(stroke
			(width 0.0508)
			(type default)
		)
		(layer "In5.Cu")
	)
	(gr_line
		(start 109.70514 -39.001954)
		(end 109.710474 -39.0271)
		(stroke
			(width 0.0508)
			(type default)
		)
		(layer "In5.Cu")
	)
	(gr_line
		(start 109.706156 -47.859442)
		(end 109.832648 -47.264828)
		(stroke
			(width 0.0508)
			(type default)
		)
		(layer "In5.Cu")
	)
	(gr_line
		(start 109.999272 -47.958756)
		(end 110.222538 -47.813722)
		(stroke
			(width 0.0508)
			(type default)
		)
		(layer "In5.Cu")
	)
	(gr_line
		(start 110.000034 -51.684174)
		(end 110.000034 -52.00015)
		(stroke
			(width 0.04445)
			(type default)
		)
		(layer "In5.Cu")
	)
	(gr_line
		(start 110.000034 -51.000152)
		(end 110.000034 -51.315874)
		(stroke
			(width 0.04445)
			(type default)
		)
		(layer "In5.Cu")
	)
	(gr_arc
		(start 110.088934 -51.595274)
		(mid 110.026041 -51.621299)
		(end 110.000034 -51.684174)
		(stroke
			(width 0.04445)
			(type default)
		)
		(layer "In5.Cu")
	)
	(gr_line
		(start 110.141004 -47.292768)
		(end 110.285784 -47.515526)
		(stroke
			(width 0.0508)
			(type default)
		)
		(layer "In5.Cu")
	)
	(gr_line
		(start 110.222538 -47.813722)
		(end 110.285784 -47.515526)
		(stroke
			(width 0.0508)
			(type default)
		)
		(layer "In5.Cu")
	)
	(gr_line
		(start 110.295436 -46.55439)
		(end 110.300008 -46.5328)
		(stroke
			(width 0.0508)
			(type default)
		)
		(layer "In5.Cu")
	)
	(gr_line
		(start 110.296452 -46.51248)
		(end 110.300008 -46.5328)
		(stroke
			(width 0.0508)
			(type default)
		)
		(layer "In5.Cu")
	)
	(gr_line
		(start 110.35157 -50.563526)
		(end 110.367572 -50.579528)
		(stroke
			(width 0.04445)
			(type default)
		)
		(layer "In5.Cu")
	)
	(gr_line
		(start 110.35157 -50.541428)
		(end 110.35157 -50.563526)
		(stroke
			(width 0.04445)
			(type default)
		)
		(layer "In5.Cu")
	)
	(gr_line
		(start 110.36935 -50.581306)
		(end 110.40872 -50.620676)
		(stroke
			(width 0.04445)
			(type default)
		)
		(layer "In5.Cu")
	)
	(gr_line
		(start 110.59922 -50.620676)
		(end 110.63859 -50.581306)
		(stroke
			(width 0.04445)
			(type default)
		)
		(layer "In5.Cu")
	)
	(gr_line
		(start 110.604046 -40.006778)
		(end 110.607856 -40.02786)
		(stroke
			(width 0.0508)
			(type default)
		)
		(layer "In5.Cu")
	)
	(gr_line
		(start 110.604046 -40.006778)
		(end 110.608364 -39.98595)
		(stroke
			(width 0.0508)
			(type default)
		)
		(layer "In5.Cu")
	)
	(gr_line
		(start 110.640368 -50.579528)
		(end 110.65637 -50.563526)
		(stroke
			(width 0.04445)
			(type default)
		)
		(layer "In5.Cu")
	)
	(gr_line
		(start 110.65637 -50.541428)
		(end 110.65637 -50.563526)
		(stroke
			(width 0.04445)
			(type default)
		)
		(layer "In5.Cu")
	)
	(gr_line
		(start 110.912402 -103.167434)
		(end 110.937548 -103.172768)
		(stroke
			(width 0.0508)
			(type default)
		)
		(layer "In5.Cu")
	)
	(gr_line
		(start 110.937548 -103.172768)
		(end 110.962694 -103.167434)
		(stroke
			(width 0.0508)
			(type default)
		)
		(layer "In5.Cu")
	)
	(gr_line
		(start 110.950756 -46.817788)
		(end 111.077248 -46.22292)
		(stroke
			(width 0.0508)
			(type default)
		)
		(layer "In5.Cu")
	)
	(gr_line
		(start 111.000032 -52.684172)
		(end 111.000032 -53.000148)
		(stroke
			(width 0.04445)
			(type default)
		)
		(layer "In5.Cu")
	)
	(gr_arc
		(start 111.000032 -52.315872)
		(mid 111.02607 -52.378734)
		(end 111.088932 -52.404772)
		(stroke
			(width 0.04445)
			(type default)
		)
		(layer "In5.Cu")
	)
	(gr_line
		(start 111.000032 -52.00015)
		(end 111.000032 -52.315872)
		(stroke
			(width 0.04445)
			(type default)
		)
		(layer "In5.Cu")
	)
	(gr_line
		(start 111.018828 -39.522146)
		(end 111.024162 -39.497)
		(stroke
			(width 0.0508)
			(type default)
		)
		(layer "In5.Cu")
	)
	(gr_line
		(start 111.018828 -39.471854)
		(end 111.024162 -39.497)
		(stroke
			(width 0.0508)
			(type default)
		)
		(layer "In5.Cu")
	)
	(gr_arc
		(start 111.02086 -11.547602)
		(mid 111.147661 -11.495079)
		(end 111.200184 -11.368278)
		(stroke
			(width 0.0508)
			(type default)
		)
		(layer "In5.Cu")
	)
	(gr_arc
		(start 111.088932 -52.595272)
		(mid 111.02604 -52.621297)
		(end 111.000032 -52.684172)
		(stroke
			(width 0.04445)
			(type default)
		)
		(layer "In5.Cu")
	)
	(gr_arc
		(start 111.200184 -12.031726)
		(mid 111.147668 -11.904922)
		(end 111.02086 -11.852402)
		(stroke
			(width 0.0508)
			(type default)
		)
		(layer "In5.Cu")
	)
	(gr_line
		(start 111.200184 -12.031726)
		(end 111.200184 -12.400026)
		(stroke
			(width 0.0508)
			(type default)
		)
		(layer "In5.Cu")
	)
	(gr_line
		(start 111.200184 -10.999978)
		(end 111.200184 -11.368278)
		(stroke
			(width 0.0508)
			(type default)
		)
		(layer "In5.Cu")
	)
	(gr_line
		(start 111.243872 -46.916848)
		(end 111.466884 -46.771814)
		(stroke
			(width 0.0508)
			(type default)
		)
		(layer "In5.Cu")
	)
	(gr_line
		(start 111.34725 -50.546)
		(end 111.363252 -50.562002)
		(stroke
			(width 0.04445)
			(type default)
		)
		(layer "In5.Cu")
	)
	(gr_line
		(start 111.34725 -50.523902)
		(end 111.34725 -50.546)
		(stroke
			(width 0.04445)
			(type default)
		)
		(layer "In5.Cu")
	)
	(gr_line
		(start 111.36503 -50.56378)
		(end 111.4044 -50.60315)
		(stroke
			(width 0.04445)
			(type default)
		)
		(layer "In5.Cu")
	)
	(gr_line
		(start 111.385604 -46.25086)
		(end 111.530384 -46.473618)
		(stroke
			(width 0.0508)
			(type default)
		)
		(layer "In5.Cu")
	)
	(gr_line
		(start 111.466884 -46.771814)
		(end 111.530384 -46.473618)
		(stroke
			(width 0.0508)
			(type default)
		)
		(layer "In5.Cu")
	)
	(gr_line
		(start 111.545116 -102.081584)
		(end 111.570262 -102.086918)
		(stroke
			(width 0.0508)
			(type default)
		)
		(layer "In5.Cu")
	)
	(gr_line
		(start 111.570262 -102.086918)
		(end 111.595408 -102.081584)
		(stroke
			(width 0.0508)
			(type default)
		)
		(layer "In5.Cu")
	)
	(gr_line
		(start 111.5949 -50.60315)
		(end 111.63427 -50.56378)
		(stroke
			(width 0.04445)
			(type default)
		)
		(layer "In5.Cu")
	)
	(gr_line
		(start 111.636048 -50.562002)
		(end 111.65205 -50.546)
		(stroke
			(width 0.04445)
			(type default)
		)
		(layer "In5.Cu")
	)
	(gr_line
		(start 111.65205 -50.523902)
		(end 111.65205 -50.546)
		(stroke
			(width 0.04445)
			(type default)
		)
		(layer "In5.Cu")
	)
	(gr_line
		(start 111.887762 -47.04207)
		(end 111.891318 -47.024544)
		(stroke
			(width 0.0508)
			(type default)
		)
		(layer "In5.Cu")
	)
	(gr_line
		(start 111.891318 -47.024544)
		(end 111.901478 -47.008796)
		(stroke
			(width 0.0508)
			(type default)
		)
		(layer "In5.Cu")
	)
	(gr_line
		(start 112.00003 -51.684174)
		(end 112.00003 -52.00015)
		(stroke
			(width 0.04445)
			(type default)
		)
		(layer "In5.Cu")
	)
	(gr_line
		(start 112.00003 -51.000152)
		(end 112.00003 -51.315874)
		(stroke
			(width 0.04445)
			(type default)
		)
		(layer "In5.Cu")
	)
	(gr_arc
		(start 112.08893 -51.595274)
		(mid 112.02604 -51.6213)
		(end 112.00003 -51.684174)
		(stroke
			(width 0.04445)
			(type default)
		)
		(layer "In5.Cu")
	)
	(gr_line
		(start 112.351566 -50.563526)
		(end 112.367568 -50.579528)
		(stroke
			(width 0.04445)
			(type default)
		)
		(layer "In5.Cu")
	)
	(gr_line
		(start 112.351566 -50.541428)
		(end 112.351566 -50.563526)
		(stroke
			(width 0.04445)
			(type default)
		)
		(layer "In5.Cu")
	)
	(gr_line
		(start 112.369346 -50.581306)
		(end 112.408716 -50.620676)
		(stroke
			(width 0.04445)
			(type default)
		)
		(layer "In5.Cu")
	)
	(gr_line
		(start 112.504982 -51.501294)
		(end 112.50549 -51.500786)
		(stroke
			(width 0.04445)
			(type default)
		)
		(layer "In5.Cu")
	)
	(gr_line
		(start 112.53089 -42.964862)
		(end 112.53597 -42.988484)
		(stroke
			(width 0.0508)
			(type default)
		)
		(layer "In5.Cu")
	)
	(gr_line
		(start 112.534446 -45.910246)
		(end 112.662462 -45.305218)
		(stroke
			(width 0.0508)
			(type default)
		)
		(layer "In5.Cu")
	)
	(gr_line
		(start 112.53597 -42.988484)
		(end 112.549432 -43.007534)
		(stroke
			(width 0.0508)
			(type default)
		)
		(layer "In5.Cu")
	)
	(gr_line
		(start 112.599216 -50.620676)
		(end 112.638586 -50.581306)
		(stroke
			(width 0.04445)
			(type default)
		)
		(layer "In5.Cu")
	)
	(gr_line
		(start 112.640364 -50.579528)
		(end 112.656366 -50.563526)
		(stroke
			(width 0.04445)
			(type default)
		)
		(layer "In5.Cu")
	)
	(gr_line
		(start 112.656366 -50.541428)
		(end 112.656366 -50.563526)
		(stroke
			(width 0.04445)
			(type default)
		)
		(layer "In5.Cu")
	)
	(gr_line
		(start 112.721136 -47.809658)
		(end 112.724946 -47.792132)
		(stroke
			(width 0.0508)
			(type default)
		)
		(layer "In5.Cu")
	)
	(gr_line
		(start 112.724946 -47.792132)
		(end 112.734598 -47.777146)
		(stroke
			(width 0.0508)
			(type default)
		)
		(layer "In5.Cu")
	)
	(gr_line
		(start 112.772444 -46.228)
		(end 112.782096 -46.213014)
		(stroke
			(width 0.0508)
			(type default)
		)
		(layer "In5.Cu")
	)
	(gr_line
		(start 112.782096 -46.213014)
		(end 112.785906 -46.195488)
		(stroke
			(width 0.0508)
			(type default)
		)
		(layer "In5.Cu")
	)
	(gr_arc
		(start 112.820704 -10.347706)
		(mid 112.947505 -10.295183)
		(end 113.000028 -10.168382)
		(stroke
			(width 0.0508)
			(type default)
		)
		(layer "In5.Cu")
	)
	(gr_line
		(start 112.827816 -46.008798)
		(end 113.051082 -45.863764)
		(stroke
			(width 0.0508)
			(type default)
		)
		(layer "In5.Cu")
	)
	(gr_line
		(start 112.942116 -47.457614)
		(end 113.275364 -46.944534)
		(stroke
			(width 0.0508)
			(type default)
		)
		(layer "In5.Cu")
	)
	(gr_line
		(start 112.968786 -45.34154)
		(end 113.114328 -45.565822)
		(stroke
			(width 0.0508)
			(type default)
		)
		(layer "In5.Cu")
	)
	(gr_line
		(start 112.982756 -43.095672)
		(end 112.999266 -43.11904)
		(stroke
			(width 0.0508)
			(type default)
		)
		(layer "In5.Cu")
	)
	(gr_line
		(start 112.999266 -43.11904)
		(end 113.004346 -43.147742)
		(stroke
			(width 0.0508)
			(type default)
		)
		(layer "In5.Cu")
	)
	(gr_line
		(start 113.000028 -52.684172)
		(end 113.000028 -53.000148)
		(stroke
			(width 0.04445)
			(type default)
		)
		(layer "In5.Cu")
	)
	(gr_arc
		(start 113.000028 -52.315872)
		(mid 113.026066 -52.378734)
		(end 113.088928 -52.404772)
		(stroke
			(width 0.04445)
			(type default)
		)
		(layer "In5.Cu")
	)
	(gr_line
		(start 113.000028 -52.00015)
		(end 113.000028 -52.315872)
		(stroke
			(width 0.04445)
			(type default)
		)
		(layer "In5.Cu")
	)
	(gr_arc
		(start 113.000028 -10.83183)
		(mid 112.947516 -10.705008)
		(end 112.820704 -10.652506)
		(stroke
			(width 0.0508)
			(type default)
		)
		(layer "In5.Cu")
	)
	(gr_line
		(start 113.000028 -10.83183)
		(end 113.000028 -11.20013)
		(stroke
			(width 0.0508)
			(type default)
		)
		(layer "In5.Cu")
	)
	(gr_line
		(start 113.000028 -9.800082)
		(end 113.000028 -10.168382)
		(stroke
			(width 0.0508)
			(type default)
		)
		(layer "In5.Cu")
	)
	(gr_line
		(start 113.051082 -45.863764)
		(end 113.114328 -45.565822)
		(stroke
			(width 0.0508)
			(type default)
		)
		(layer "In5.Cu")
	)
	(gr_arc
		(start 113.088928 -52.595272)
		(mid 113.026038 -52.621299)
		(end 113.000028 -52.684172)
		(stroke
			(width 0.04445)
			(type default)
		)
		(layer "In5.Cu")
	)
	(gr_line
		(start 113.180876 -47.654464)
		(end 113.440972 -47.599092)
		(stroke
			(width 0.0508)
			(type default)
		)
		(layer "In5.Cu")
	)
	(gr_line
		(start 113.347246 -50.546)
		(end 113.363248 -50.562002)
		(stroke
			(width 0.04445)
			(type default)
		)
		(layer "In5.Cu")
	)
	(gr_line
		(start 113.347246 -50.523902)
		(end 113.347246 -50.546)
		(stroke
			(width 0.04445)
			(type default)
		)
		(layer "In5.Cu")
	)
	(gr_line
		(start 113.356898 -41.999662)
		(end 113.36147 -42.020998)
		(stroke
			(width 0.0508)
			(type default)
		)
		(layer "In5.Cu")
	)
	(gr_line
		(start 113.36147 -42.020998)
		(end 113.373916 -42.039032)
		(stroke
			(width 0.0508)
			(type default)
		)
		(layer "In5.Cu")
	)
	(gr_line
		(start 113.365026 -50.56378)
		(end 113.404396 -50.60315)
		(stroke
			(width 0.04445)
			(type default)
		)
		(layer "In5.Cu")
	)
	(gr_line
		(start 113.440972 -47.599092)
		(end 113.607088 -47.343568)
		(stroke
			(width 0.0508)
			(type default)
		)
		(layer "In5.Cu")
	)
	(gr_line
		(start 113.498884 -48.937164)
		(end 113.502694 -48.919638)
		(stroke
			(width 0.0508)
			(type default)
		)
		(layer "In5.Cu")
	)
	(gr_line
		(start 113.500916 -102.316026)
		(end 113.526062 -102.310692)
		(stroke
			(width 0.0508)
			(type default)
		)
		(layer "In5.Cu")
	)
	(gr_line
		(start 113.502694 -48.919638)
		(end 113.512346 -48.904652)
		(stroke
			(width 0.0508)
			(type default)
		)
		(layer "In5.Cu")
	)
	(gr_line
		(start 113.50371 -101.364542)
		(end 113.528856 -101.359208)
		(stroke
			(width 0.0508)
			(type default)
		)
		(layer "In5.Cu")
	)
	(gr_line
		(start 113.526062 -102.310692)
		(end 113.551208 -102.316026)
		(stroke
			(width 0.0508)
			(type default)
		)
		(layer "In5.Cu")
	)
	(gr_line
		(start 113.528856 -101.359208)
		(end 113.554002 -101.364542)
		(stroke
			(width 0.0508)
			(type default)
		)
		(layer "In5.Cu")
	)
	(gr_line
		(start 113.551716 -47.083218)
		(end 113.607088 -47.343568)
		(stroke
			(width 0.0508)
			(type default)
		)
		(layer "In5.Cu")
	)
	(gr_line
		(start 113.594896 -50.60315)
		(end 113.634266 -50.56378)
		(stroke
			(width 0.04445)
			(type default)
		)
		(layer "In5.Cu")
	)
	(gr_line
		(start 113.636044 -50.562002)
		(end 113.652046 -50.546)
		(stroke
			(width 0.04445)
			(type default)
		)
		(layer "In5.Cu")
	)
	(gr_line
		(start 113.652046 -50.523902)
		(end 113.652046 -50.546)
		(stroke
			(width 0.04445)
			(type default)
		)
		(layer "In5.Cu")
	)
	(gr_line
		(start 114.000026 -51.684174)
		(end 114.000026 -52.00015)
		(stroke
			(width 0.04445)
			(type default)
		)
		(layer "In5.Cu")
	)
	(gr_line
		(start 114.000026 -51.000152)
		(end 114.000026 -51.315874)
		(stroke
			(width 0.04445)
			(type default)
		)
		(layer "In5.Cu")
	)
	(gr_arc
		(start 114.088926 -51.595274)
		(mid 114.026038 -51.621301)
		(end 114.000026 -51.684174)
		(stroke
			(width 0.04445)
			(type default)
		)
		(layer "In5.Cu")
	)
	(gr_line
		(start 114.301016 -41.209214)
		(end 114.305842 -41.232836)
		(stroke
			(width 0.0508)
			(type default)
		)
		(layer "In5.Cu")
	)
	(gr_line
		(start 114.305842 -41.232836)
		(end 114.320066 -41.253156)
		(stroke
			(width 0.0508)
			(type default)
		)
		(layer "In5.Cu")
	)
	(gr_line
		(start 114.356642 -50.563526)
		(end 114.372644 -50.579528)
		(stroke
			(width 0.04445)
			(type default)
		)
		(layer "In5.Cu")
	)
	(gr_line
		(start 114.356642 -50.541428)
		(end 114.356642 -50.563526)
		(stroke
			(width 0.04445)
			(type default)
		)
		(layer "In5.Cu")
	)
	(gr_line
		(start 114.356642 -49.868582)
		(end 114.384836 -49.825148)
		(stroke
			(width 0.0508)
			(type default)
		)
		(layer "In5.Cu")
	)
	(gr_line
		(start 114.374422 -50.581306)
		(end 114.413792 -50.620676)
		(stroke
			(width 0.04445)
			(type default)
		)
		(layer "In5.Cu")
	)
	(gr_line
		(start 114.470688 -45.679868)
		(end 114.487198 -45.656246)
		(stroke
			(width 0.0508)
			(type default)
		)
		(layer "In5.Cu")
	)
	(gr_line
		(start 114.487198 -45.656246)
		(end 114.492278 -45.628052)
		(stroke
			(width 0.0508)
			(type default)
		)
		(layer "In5.Cu")
	)
	(gr_line
		(start 114.527838 -47.341028)
		(end 114.858038 -46.83252)
		(stroke
			(width 0.0508)
			(type default)
		)
		(layer "In5.Cu")
	)
	(gr_line
		(start 114.52987 -43.172888)
		(end 114.546126 -43.19651)
		(stroke
			(width 0.0508)
			(type default)
		)
		(layer "In5.Cu")
	)
	(gr_line
		(start 114.546126 -43.19651)
		(end 114.551206 -43.224704)
		(stroke
			(width 0.0508)
			(type default)
		)
		(layer "In5.Cu")
	)
	(gr_line
		(start 114.592354 -49.50587)
		(end 114.92357 -48.996346)
		(stroke
			(width 0.0508)
			(type default)
		)
		(layer "In5.Cu")
	)
	(gr_line
		(start 114.604292 -50.620676)
		(end 114.643662 -50.581306)
		(stroke
			(width 0.04445)
			(type default)
		)
		(layer "In5.Cu")
	)
	(gr_arc
		(start 114.620802 -11.547602)
		(mid 114.747603 -11.495079)
		(end 114.800126 -11.368278)
		(stroke
			(width 0.0508)
			(type default)
		)
		(layer "In5.Cu")
	)
	(gr_line
		(start 114.64544 -50.579528)
		(end 114.661442 -50.563526)
		(stroke
			(width 0.04445)
			(type default)
		)
		(layer "In5.Cu")
	)
	(gr_line
		(start 114.661442 -50.541428)
		(end 114.661442 -50.563526)
		(stroke
			(width 0.04445)
			(type default)
		)
		(layer "In5.Cu")
	)
	(gr_line
		(start 114.765328 -47.539402)
		(end 115.025424 -47.484284)
		(stroke
			(width 0.0508)
			(type default)
		)
		(layer "In5.Cu")
	)
	(gr_arc
		(start 114.800126 -12.031726)
		(mid 114.747613 -11.904907)
		(end 114.620802 -11.852402)
		(stroke
			(width 0.0508)
			(type default)
		)
		(layer "In5.Cu")
	)
	(gr_line
		(start 114.800126 -12.031726)
		(end 114.800126 -12.400026)
		(stroke
			(width 0.0508)
			(type default)
		)
		(layer "In5.Cu")
	)
	(gr_line
		(start 114.800126 -10.999978)
		(end 114.800126 -11.368278)
		(stroke
			(width 0.0508)
			(type default)
		)
		(layer "In5.Cu")
	)
	(gr_line
		(start 114.830606 -49.702974)
		(end 115.090956 -49.647602)
		(stroke
			(width 0.0508)
			(type default)
		)
		(layer "In5.Cu")
	)
	(gr_line
		(start 114.941604 -48.967898)
		(end 115.352068 -48.335946)
		(stroke
			(width 0.0508)
			(type default)
		)
		(layer "In5.Cu")
	)
	(gr_line
		(start 115.025424 -47.484284)
		(end 115.19154 -47.228506)
		(stroke
			(width 0.0508)
			(type default)
		)
		(layer "In5.Cu")
	)
	(gr_line
		(start 115.090956 -49.647602)
		(end 115.257072 -49.392078)
		(stroke
			(width 0.0508)
			(type default)
		)
		(layer "In5.Cu")
	)
	(gr_line
		(start 115.136168 -46.968664)
		(end 115.19154 -47.228506)
		(stroke
			(width 0.0508)
			(type default)
		)
		(layer "In5.Cu")
	)
	(gr_line
		(start 115.200938 -49.128172)
		(end 115.200938 -49.128426)
		(stroke
			(width 0.0508)
			(type default)
		)
		(layer "In5.Cu")
	)
	(gr_line
		(start 115.200938 -49.128172)
		(end 115.607846 -48.502062)
		(stroke
			(width 0.0508)
			(type default)
		)
		(layer "In5.Cu")
	)
	(gr_line
		(start 115.2017 -49.131982)
		(end 115.257072 -49.392078)
		(stroke
			(width 0.0508)
			(type default)
		)
		(layer "In5.Cu")
	)
	(gr_line
		(start 115.791742 -41.075864)
		(end 115.795552 -41.09339)
		(stroke
			(width 0.0508)
			(type default)
		)
		(layer "In5.Cu")
	)
	(gr_line
		(start 115.795552 -41.09339)
		(end 115.805204 -41.108376)
		(stroke
			(width 0.0508)
			(type default)
		)
		(layer "In5.Cu")
	)
	(gr_line
		(start 115.993926 -45.643292)
		(end 116.004594 -45.626782)
		(stroke
			(width 0.0508)
			(type default)
		)
		(layer "In5.Cu")
	)
	(gr_line
		(start 116.000022 -52.684172)
		(end 116.000022 -53.000148)
		(stroke
			(width 0.04445)
			(type default)
		)
		(layer "In5.Cu")
	)
	(gr_arc
		(start 116.000022 -52.315872)
		(mid 116.02606 -52.378734)
		(end 116.088922 -52.404772)
		(stroke
			(width 0.04445)
			(type default)
		)
		(layer "In5.Cu")
	)
	(gr_line
		(start 116.000022 -52.00015)
		(end 116.000022 -52.315872)
		(stroke
			(width 0.04445)
			(type default)
		)
		(layer "In5.Cu")
	)
	(gr_line
		(start 116.004594 -45.626782)
		(end 116.00815 -45.607986)
		(stroke
			(width 0.0508)
			(type default)
		)
		(layer "In5.Cu")
	)
	(gr_line
		(start 116.056664 -43.199812)
		(end 116.073428 -43.223942)
		(stroke
			(width 0.0508)
			(type default)
		)
		(layer "In5.Cu")
	)
	(gr_line
		(start 116.073428 -43.223942)
		(end 116.078508 -43.252644)
		(stroke
			(width 0.0508)
			(type default)
		)
		(layer "In5.Cu")
	)
	(gr_arc
		(start 116.088922 -52.595272)
		(mid 116.026036 -52.621301)
		(end 116.000022 -52.684172)
		(stroke
			(width 0.04445)
			(type default)
		)
		(layer "In5.Cu")
	)
	(gr_line
		(start 116.26977 -103.874824)
		(end 116.294916 -103.86949)
		(stroke
			(width 0.0508)
			(type default)
		)
		(layer "In5.Cu")
	)
	(gr_line
		(start 116.294916 -103.86949)
		(end 116.320062 -103.874824)
		(stroke
			(width 0.0508)
			(type default)
		)
		(layer "In5.Cu")
	)
	(gr_line
		(start 116.34724 -50.546)
		(end 116.363242 -50.562002)
		(stroke
			(width 0.04445)
			(type default)
		)
		(layer "In5.Cu")
	)
	(gr_line
		(start 116.34724 -50.523902)
		(end 116.34724 -50.546)
		(stroke
			(width 0.04445)
			(type default)
		)
		(layer "In5.Cu")
	)
	(gr_line
		(start 116.35994 -104.855772)
		(end 116.385086 -104.850438)
		(stroke
			(width 0.0508)
			(type default)
		)
		(layer "In5.Cu")
	)
	(gr_line
		(start 116.36502 -50.56378)
		(end 116.40439 -50.60315)
		(stroke
			(width 0.04445)
			(type default)
		)
		(layer "In5.Cu")
	)
	(gr_line
		(start 116.385086 -104.850438)
		(end 116.410232 -104.855772)
		(stroke
			(width 0.0508)
			(type default)
		)
		(layer "In5.Cu")
	)
	(gr_arc
		(start 116.420646 -10.347706)
		(mid 116.547411 -10.295166)
		(end 116.59997 -10.168382)
		(stroke
			(width 0.0508)
			(type default)
		)
		(layer "In5.Cu")
	)
	(gr_line
		(start 116.59489 -50.60315)
		(end 116.63426 -50.56378)
		(stroke
			(width 0.04445)
			(type default)
		)
		(layer "In5.Cu")
	)
	(gr_arc
		(start 116.59997 -10.83183)
		(mid 116.547447 -10.705029)
		(end 116.420646 -10.652506)
		(stroke
			(width 0.0508)
			(type default)
		)
		(layer "In5.Cu")
	)
	(gr_line
		(start 116.59997 -10.83183)
		(end 116.59997 -11.20013)
		(stroke
			(width 0.0508)
			(type default)
		)
		(layer "In5.Cu")
	)
	(gr_line
		(start 116.59997 -9.800082)
		(end 116.59997 -10.168382)
		(stroke
			(width 0.0508)
			(type default)
		)
		(layer "In5.Cu")
	)
	(gr_line
		(start 116.636038 -50.562002)
		(end 116.65204 -50.546)
		(stroke
			(width 0.04445)
			(type default)
		)
		(layer "In5.Cu")
	)
	(gr_line
		(start 116.65204 -50.523902)
		(end 116.65204 -50.546)
		(stroke
			(width 0.04445)
			(type default)
		)
		(layer "In5.Cu")
	)
	(gr_line
		(start 116.764054 -48.114458)
		(end 116.767864 -48.096932)
		(stroke
			(width 0.0508)
			(type default)
		)
		(layer "In5.Cu")
	)
	(gr_line
		(start 116.767864 -48.096932)
		(end 116.777516 -48.081946)
		(stroke
			(width 0.0508)
			(type default)
		)
		(layer "In5.Cu")
	)
	(gr_line
		(start 116.98732 -22.862286)
		(end 116.992654 -22.887432)
		(stroke
			(width 0.0508)
			(type default)
		)
		(layer "In5.Cu")
	)
	(gr_line
		(start 116.98732 -22.862286)
		(end 116.992654 -22.83714)
		(stroke
			(width 0.0508)
			(type default)
		)
		(layer "In5.Cu")
	)
	(gr_line
		(start 117.00002 -51.684174)
		(end 117.00002 -52.00015)
		(stroke
			(width 0.04445)
			(type default)
		)
		(layer "In5.Cu")
	)
	(gr_line
		(start 117.00002 -51.000152)
		(end 117.00002 -51.315874)
		(stroke
			(width 0.04445)
			(type default)
		)
		(layer "In5.Cu")
	)
	(gr_arc
		(start 117.08892 -51.595274)
		(mid 117.026036 -51.621304)
		(end 117.00002 -51.684174)
		(stroke
			(width 0.04445)
			(type default)
		)
		(layer "In5.Cu")
	)
	(gr_line
		(start 117.30609 -40.809164)
		(end 117.30736 -40.814752)
		(stroke
			(width 0.0508)
			(type default)
		)
		(layer "In5.Cu")
	)
	(gr_line
		(start 117.30736 -40.814752)
		(end 117.3099 -40.819578)
		(stroke
			(width 0.0508)
			(type default)
		)
		(layer "In5.Cu")
	)
	(gr_line
		(start 117.351556 -50.563526)
		(end 117.367558 -50.579528)
		(stroke
			(width 0.04445)
			(type default)
		)
		(layer "In5.Cu")
	)
	(gr_line
		(start 117.351556 -50.541428)
		(end 117.351556 -50.563526)
		(stroke
			(width 0.04445)
			(type default)
		)
		(layer "In5.Cu")
	)
	(gr_line
		(start 117.369336 -50.581306)
		(end 117.408706 -50.620676)
		(stroke
			(width 0.04445)
			(type default)
		)
		(layer "In5.Cu")
	)
	(gr_line
		(start 117.411246 -47.105824)
		(end 117.743732 -46.59376)
		(stroke
			(width 0.0508)
			(type default)
		)
		(layer "In5.Cu")
	)
	(gr_line
		(start 117.51183 -45.592746)
		(end 117.52834 -45.569124)
		(stroke
			(width 0.0508)
			(type default)
		)
		(layer "In5.Cu")
	)
	(gr_line
		(start 117.52834 -45.569124)
		(end 117.53342 -45.540676)
		(stroke
			(width 0.0508)
			(type default)
		)
		(layer "In5.Cu")
	)
	(gr_line
		(start 117.564916 -48.988218)
		(end 117.568472 -48.971454)
		(stroke
			(width 0.0508)
			(type default)
		)
		(layer "In5.Cu")
	)
	(gr_line
		(start 117.568472 -48.971454)
		(end 117.578124 -48.956468)
		(stroke
			(width 0.0508)
			(type default)
		)
		(layer "In5.Cu")
	)
	(gr_line
		(start 117.57787 -43.2689)
		(end 117.594634 -43.292776)
		(stroke
			(width 0.0508)
			(type default)
		)
		(layer "In5.Cu")
	)
	(gr_line
		(start 117.594634 -43.292776)
		(end 117.599714 -43.321478)
		(stroke
			(width 0.0508)
			(type default)
		)
		(layer "In5.Cu")
	)
	(gr_line
		(start 117.599206 -50.620676)
		(end 117.638576 -50.581306)
		(stroke
			(width 0.04445)
			(type default)
		)
		(layer "In5.Cu")
	)
	(gr_line
		(start 117.640354 -50.579528)
		(end 117.656356 -50.563526)
		(stroke
			(width 0.04445)
			(type default)
		)
		(layer "In5.Cu")
	)
	(gr_line
		(start 117.649752 -47.302674)
		(end 117.910102 -47.247302)
		(stroke
			(width 0.0508)
			(type default)
		)
		(layer "In5.Cu")
	)
	(gr_line
		(start 117.656356 -50.541428)
		(end 117.656356 -50.563526)
		(stroke
			(width 0.04445)
			(type default)
		)
		(layer "In5.Cu")
	)
	(gr_line
		(start 117.910102 -47.247302)
		(end 118.076218 -46.991778)
		(stroke
			(width 0.0508)
			(type default)
		)
		(layer "In5.Cu")
	)
	(gr_line
		(start 118.000018 -52.684172)
		(end 118.000018 -53.000148)
		(stroke
			(width 0.04445)
			(type default)
		)
		(layer "In5.Cu")
	)
	(gr_arc
		(start 118.000018 -52.315872)
		(mid 118.026047 -52.378746)
		(end 118.088918 -52.404772)
		(stroke
			(width 0.04445)
			(type default)
		)
		(layer "In5.Cu")
	)
	(gr_line
		(start 118.000018 -52.00015)
		(end 118.000018 -52.315872)
		(stroke
			(width 0.04445)
			(type default)
		)
		(layer "In5.Cu")
	)
	(gr_line
		(start 118.020846 -46.731428)
		(end 118.076218 -46.991778)
		(stroke
			(width 0.0508)
			(type default)
		)
		(layer "In5.Cu")
	)
	(gr_arc
		(start 118.088918 -52.595272)
		(mid 118.026056 -52.62131)
		(end 118.000018 -52.684172)
		(stroke
			(width 0.04445)
			(type default)
		)
		(layer "In5.Cu")
	)
	(gr_line
		(start 118.181628 -45.91939)
		(end 118.510304 -45.41266)
		(stroke
			(width 0.0508)
			(type default)
		)
		(layer "In5.Cu")
	)
	(gr_arc
		(start 118.220744 -11.547602)
		(mid 118.347545 -11.495079)
		(end 118.400068 -11.368278)
		(stroke
			(width 0.0508)
			(type default)
		)
		(layer "In5.Cu")
	)
	(gr_line
		(start 118.293388 -18.18513)
		(end 118.298722 -18.159984)
		(stroke
			(width 0.0508)
			(type default)
		)
		(layer "In5.Cu")
	)
	(gr_line
		(start 118.293388 -18.134838)
		(end 118.298722 -18.159984)
		(stroke
			(width 0.0508)
			(type default)
		)
		(layer "In5.Cu")
	)
	(gr_line
		(start 118.347236 -50.546)
		(end 118.363238 -50.562002)
		(stroke
			(width 0.04445)
			(type default)
		)
		(layer "In5.Cu")
	)
	(gr_line
		(start 118.347236 -50.523902)
		(end 118.347236 -50.546)
		(stroke
			(width 0.04445)
			(type default)
		)
		(layer "In5.Cu")
	)
	(gr_line
		(start 118.365016 -50.56378)
		(end 118.404386 -50.60315)
		(stroke
			(width 0.04445)
			(type default)
		)
		(layer "In5.Cu")
	)
	(gr_arc
		(start 118.400068 -12.031726)
		(mid 118.347557 -11.904892)
		(end 118.220744 -11.852402)
		(stroke
			(width 0.0508)
			(type default)
		)
		(layer "In5.Cu")
	)
	(gr_line
		(start 118.400068 -12.031726)
		(end 118.400068 -12.400026)
		(stroke
			(width 0.0508)
			(type default)
		)
		(layer "In5.Cu")
	)
	(gr_line
		(start 118.400068 -10.999978)
		(end 118.400068 -11.368278)
		(stroke
			(width 0.0508)
			(type default)
		)
		(layer "In5.Cu")
	)
	(gr_line
		(start 118.429278 -49.80686)
		(end 118.432834 -49.789334)
		(stroke
			(width 0.0508)
			(type default)
		)
		(layer "In5.Cu")
	)
	(gr_line
		(start 118.432834 -49.789334)
		(end 118.442994 -49.773586)
		(stroke
			(width 0.0508)
			(type default)
		)
		(layer "In5.Cu")
	)
	(gr_line
		(start 118.471442 -40.679624)
		(end 118.475252 -40.69715)
		(stroke
			(width 0.0508)
			(type default)
		)
		(layer "In5.Cu")
	)
	(gr_line
		(start 118.475252 -40.69715)
		(end 118.484904 -40.712136)
		(stroke
			(width 0.0508)
			(type default)
		)
		(layer "In5.Cu")
	)
	(gr_line
		(start 118.573296 -45.875448)
		(end 118.766082 -45.578522)
		(stroke
			(width 0.0508)
			(type default)
		)
		(layer "In5.Cu")
	)
	(gr_line
		(start 118.594886 -50.60315)
		(end 118.634256 -50.56378)
		(stroke
			(width 0.04445)
			(type default)
		)
		(layer "In5.Cu")
	)
	(gr_line
		(start 118.636034 -50.562002)
		(end 118.652036 -50.546)
		(stroke
			(width 0.04445)
			(type default)
		)
		(layer "In5.Cu")
	)
	(gr_line
		(start 118.652036 -50.523902)
		(end 118.652036 -50.546)
		(stroke
			(width 0.04445)
			(type default)
		)
		(layer "In5.Cu")
	)
	(gr_line
		(start 118.679468 -47.261018)
		(end 119.0117 -46.749462)
		(stroke
			(width 0.0508)
			(type default)
		)
		(layer "In5.Cu")
	)
	(gr_line
		(start 118.836186 -22.49043)
		(end 118.84152 -22.515576)
		(stroke
			(width 0.0508)
			(type default)
		)
		(layer "In5.Cu")
	)
	(gr_line
		(start 118.836186 -22.49043)
		(end 118.84152 -22.465284)
		(stroke
			(width 0.0508)
			(type default)
		)
		(layer "In5.Cu")
	)
	(gr_line
		(start 118.914672 -102.815898)
		(end 118.939818 -102.821232)
		(stroke
			(width 0.0508)
			(type default)
		)
		(layer "In5.Cu")
	)
	(gr_line
		(start 118.91772 -47.458376)
		(end 119.177816 -47.403004)
		(stroke
			(width 0.0508)
			(type default)
		)
		(layer "In5.Cu")
	)
	(gr_line
		(start 118.939818 -102.821232)
		(end 118.964964 -102.815898)
		(stroke
			(width 0.0508)
			(type default)
		)
		(layer "In5.Cu")
	)
	(gr_line
		(start 119.000016 -51.684174)
		(end 119.000016 -52.00015)
		(stroke
			(width 0.04445)
			(type default)
		)
		(layer "In5.Cu")
	)
	(gr_line
		(start 119.000016 -51.000152)
		(end 119.000016 -51.315874)
		(stroke
			(width 0.04445)
			(type default)
		)
		(layer "In5.Cu")
	)
	(gr_arc
		(start 119.088916 -51.595274)
		(mid 119.026035 -51.621305)
		(end 119.000016 -51.684174)
		(stroke
			(width 0.04445)
			(type default)
		)
		(layer "In5.Cu")
	)
	(gr_line
		(start 119.147844 -44.990766)
		(end 119.175784 -44.947586)
		(stroke
			(width 0.0508)
			(type default)
		)
		(layer "In5.Cu")
	)
	(gr_line
		(start 119.15775 -43.582082)
		(end 119.175784 -43.615102)
		(stroke
			(width 0.0508)
			(type default)
		)
		(layer "In5.Cu")
	)
	(gr_line
		(start 119.177816 -47.403004)
		(end 119.343932 -47.14748)
		(stroke
			(width 0.0508)
			(type default)
		)
		(layer "In5.Cu")
	)
	(gr_line
		(start 119.28856 -46.887638)
		(end 119.343932 -47.14748)
		(stroke
			(width 0.0508)
			(type default)
		)
		(layer "In5.Cu")
	)
	(gr_line
		(start 119.351552 -50.563526)
		(end 119.367554 -50.579528)
		(stroke
			(width 0.04445)
			(type default)
		)
		(layer "In5.Cu")
	)
	(gr_line
		(start 119.351552 -50.541428)
		(end 119.351552 -50.563526)
		(stroke
			(width 0.04445)
			(type default)
		)
		(layer "In5.Cu")
	)
	(gr_line
		(start 119.351552 -50.005234)
		(end 119.379238 -49.962562)
		(stroke
			(width 0.0508)
			(type default)
		)
		(layer "In5.Cu")
	)
	(gr_line
		(start 119.369332 -50.581306)
		(end 119.408702 -50.620676)
		(stroke
			(width 0.04445)
			(type default)
		)
		(layer "In5.Cu")
	)
	(gr_line
		(start 119.453406 -39.650924)
		(end 119.579898 -40.246046)
		(stroke
			(width 0.0508)
			(type default)
		)
		(layer "In5.Cu")
	)
	(gr_line
		(start 119.54637 -103.902256)
		(end 119.571516 -103.90759)
		(stroke
			(width 0.0508)
			(type default)
		)
		(layer "In5.Cu")
	)
	(gr_line
		(start 119.571516 -103.90759)
		(end 119.597424 -103.902256)
		(stroke
			(width 0.0508)
			(type default)
		)
		(layer "In5.Cu")
	)
	(gr_line
		(start 119.599202 -50.620676)
		(end 119.638572 -50.581306)
		(stroke
			(width 0.04445)
			(type default)
		)
		(layer "In5.Cu")
	)
	(gr_line
		(start 119.64035 -50.579528)
		(end 119.656352 -50.563526)
		(stroke
			(width 0.04445)
			(type default)
		)
		(layer "In5.Cu")
	)
	(gr_line
		(start 119.656352 -50.449734)
		(end 119.656352 -50.563526)
		(stroke
			(width 0.04445)
			(type default)
		)
		(layer "In5.Cu")
	)
	(gr_line
		(start 119.659146 -40.619172)
		(end 119.662956 -40.636698)
		(stroke
			(width 0.0508)
			(type default)
		)
		(layer "In5.Cu")
	)
	(gr_line
		(start 119.662956 -40.636698)
		(end 119.672608 -40.651684)
		(stroke
			(width 0.0508)
			(type default)
		)
		(layer "In5.Cu")
	)
	(gr_line
		(start 119.682768 -45.722794)
		(end 119.688864 -45.714666)
		(stroke
			(width 0.0508)
			(type default)
		)
		(layer "In5.Cu")
	)
	(gr_line
		(start 119.688864 -45.714666)
		(end 119.697246 -45.708824)
		(stroke
			(width 0.0508)
			(type default)
		)
		(layer "In5.Cu")
	)
	(gr_line
		(start 119.746522 -39.550848)
		(end 119.969534 -39.695882)
		(stroke
			(width 0.0508)
			(type default)
		)
		(layer "In5.Cu")
	)
	(gr_line
		(start 119.888 -40.21709)
		(end 120.03278 -39.994078)
		(stroke
			(width 0.0508)
			(type default)
		)
		(layer "In5.Cu")
	)
	(gr_line
		(start 119.969534 -39.695882)
		(end 120.03278 -39.994078)
		(stroke
			(width 0.0508)
			(type default)
		)
		(layer "In5.Cu")
	)
	(gr_line
		(start 119.974868 -18.601436)
		(end 119.980202 -18.57629)
		(stroke
			(width 0.0508)
			(type default)
		)
		(layer "In5.Cu")
	)
	(gr_line
		(start 119.974868 -18.551144)
		(end 119.980202 -18.57629)
		(stroke
			(width 0.0508)
			(type default)
		)
		(layer "In5.Cu")
	)
	(gr_line
		(start 120.000014 -52.684172)
		(end 120.000014 -53.000148)
		(stroke
			(width 0.04445)
			(type default)
		)
		(layer "In5.Cu")
	)
	(gr_arc
		(start 120.000014 -52.315872)
		(mid 120.026043 -52.378747)
		(end 120.088914 -52.404772)
		(stroke
			(width 0.04445)
			(type default)
		)
		(layer "In5.Cu")
	)
	(gr_line
		(start 120.000014 -52.00015)
		(end 120.000014 -52.315872)
		(stroke
			(width 0.04445)
			(type default)
		)
		(layer "In5.Cu")
	)
	(gr_arc
		(start 120.020842 -10.347706)
		(mid 120.14761 -10.295167)
		(end 120.200166 -10.168382)
		(stroke
			(width 0.0508)
			(type default)
		)
		(layer "In5.Cu")
	)
	(gr_arc
		(start 120.088914 -52.595272)
		(mid 120.026052 -52.62131)
		(end 120.000014 -52.684172)
		(stroke
			(width 0.04445)
			(type default)
		)
		(layer "In5.Cu")
	)
	(gr_line
		(start 120.158764 -45.7581)
		(end 120.17248 -45.748448)
		(stroke
			(width 0.0508)
			(type default)
		)
		(layer "In5.Cu")
	)
	(gr_line
		(start 120.17248 -45.748448)
		(end 120.182132 -45.734732)
		(stroke
			(width 0.0508)
			(type default)
		)
		(layer "In5.Cu")
	)
	(gr_arc
		(start 120.200166 -10.83183)
		(mid 120.147643 -10.705029)
		(end 120.020842 -10.652506)
		(stroke
			(width 0.0508)
			(type default)
		)
		(layer "In5.Cu")
	)
	(gr_line
		(start 120.200166 -10.83183)
		(end 120.200166 -11.20013)
		(stroke
			(width 0.0508)
			(type default)
		)
		(layer "In5.Cu")
	)
	(gr_line
		(start 120.200166 -9.800082)
		(end 120.200166 -10.168382)
		(stroke
			(width 0.0508)
			(type default)
		)
		(layer "In5.Cu")
	)
	(gr_line
		(start 120.216168 -105.014776)
		(end 120.241314 -105.02011)
		(stroke
			(width 0.0508)
			(type default)
		)
		(layer "In5.Cu")
	)
	(gr_line
		(start 120.241314 -105.02011)
		(end 120.26646 -105.014776)
		(stroke
			(width 0.0508)
			(type default)
		)
		(layer "In5.Cu")
	)
	(gr_line
		(start 120.347232 -50.546)
		(end 120.363234 -50.562002)
		(stroke
			(width 0.04445)
			(type default)
		)
		(layer "In5.Cu")
	)
	(gr_line
		(start 120.347232 -50.523902)
		(end 120.347232 -50.546)
		(stroke
			(width 0.04445)
			(type default)
		)
		(layer "In5.Cu")
	)
	(gr_line
		(start 120.347232 -50.05197)
		(end 120.375172 -50.00879)
		(stroke
			(width 0.0508)
			(type default)
		)
		(layer "In5.Cu")
	)
	(gr_line
		(start 120.351804 -21.724366)
		(end 120.357138 -21.749512)
		(stroke
			(width 0.0508)
			(type default)
		)
		(layer "In5.Cu")
	)
	(gr_line
		(start 120.351804 -21.724366)
		(end 120.357138 -21.69922)
		(stroke
			(width 0.0508)
			(type default)
		)
		(layer "In5.Cu")
	)
	(gr_line
		(start 120.365012 -50.56378)
		(end 120.404382 -50.60315)
		(stroke
			(width 0.04445)
			(type default)
		)
		(layer "In5.Cu")
	)
	(gr_line
		(start 120.594882 -50.60315)
		(end 120.634252 -50.56378)
		(stroke
			(width 0.04445)
			(type default)
		)
		(layer "In5.Cu")
	)
	(gr_line
		(start 120.63603 -50.562002)
		(end 120.652032 -50.546)
		(stroke
			(width 0.04445)
			(type default)
		)
		(layer "In5.Cu")
	)
	(gr_line
		(start 120.638062 -45.082714)
		(end 120.654572 -45.058838)
		(stroke
			(width 0.0508)
			(type default)
		)
		(layer "In5.Cu")
	)
	(gr_line
		(start 120.652032 -50.523902)
		(end 120.652032 -50.546)
		(stroke
			(width 0.04445)
			(type default)
		)
		(layer "In5.Cu")
	)
	(gr_line
		(start 120.654572 -45.058838)
		(end 120.659652 -45.03039)
		(stroke
			(width 0.0508)
			(type default)
		)
		(layer "In5.Cu")
	)
	(gr_line
		(start 120.667018 -43.498008)
		(end 120.699784 -43.544998)
		(stroke
			(width 0.0508)
			(type default)
		)
		(layer "In5.Cu")
	)
	(gr_line
		(start 120.69318 -40.293544)
		(end 120.69699 -40.31107)
		(stroke
			(width 0.0508)
			(type default)
		)
		(layer "In5.Cu")
	)
	(gr_line
		(start 120.69699 -40.31107)
		(end 120.706642 -40.326056)
		(stroke
			(width 0.0508)
			(type default)
		)
		(layer "In5.Cu")
	)
	(gr_line
		(start 120.743726 -106.088434)
		(end 120.768872 -106.093768)
		(stroke
			(width 0.0508)
			(type default)
		)
		(layer "In5.Cu")
	)
	(gr_line
		(start 120.768872 -106.093768)
		(end 120.794018 -106.088434)
		(stroke
			(width 0.0508)
			(type default)
		)
		(layer "In5.Cu")
	)
	(gr_line
		(start 121.000012 -51.684174)
		(end 121.000012 -52.00015)
		(stroke
			(width 0.04445)
			(type default)
		)
		(layer "In5.Cu")
	)
	(gr_arc
		(start 121.000012 -51.315874)
		(mid 121.026042 -51.378748)
		(end 121.088912 -51.404774)
		(stroke
			(width 0.04445)
			(type default)
		)
		(layer "In5.Cu")
	)
	(gr_line
		(start 121.000012 -51.000152)
		(end 121.000012 -51.315874)
		(stroke
			(width 0.04445)
			(type default)
		)
		(layer "In5.Cu")
	)
	(gr_line
		(start 121.073418 -42.80789)
		(end 121.361962 -43.220132)
		(stroke
			(width 0.0508)
			(type default)
		)
		(layer "In5.Cu")
	)
	(gr_arc
		(start 121.088912 -51.595274)
		(mid 121.026033 -51.621306)
		(end 121.000012 -51.684174)
		(stroke
			(width 0.04445)
			(type default)
		)
		(layer "In5.Cu")
	)
	(gr_line
		(start 121.326148 -42.637456)
		(end 121.358406 -42.68724)
		(stroke
			(width 0.0508)
			(type default)
		)
		(layer "In5.Cu")
	)
	(gr_line
		(start 121.351548 -50.563526)
		(end 121.36755 -50.579528)
		(stroke
			(width 0.04445)
			(type default)
		)
		(layer "In5.Cu")
	)
	(gr_line
		(start 121.351548 -50.541428)
		(end 121.351548 -50.563526)
		(stroke
			(width 0.04445)
			(type default)
		)
		(layer "In5.Cu")
	)
	(gr_line
		(start 121.358406 -42.68724)
		(end 121.63044 -43.07586)
		(stroke
			(width 0.0508)
			(type default)
		)
		(layer "In5.Cu")
	)
	(gr_line
		(start 121.361962 -43.220132)
		(end 121.362724 -43.224958)
		(stroke
			(width 0.0508)
			(type default)
		)
		(layer "In5.Cu")
	)
	(gr_line
		(start 121.369328 -50.581306)
		(end 121.408698 -50.620676)
		(stroke
			(width 0.04445)
			(type default)
		)
		(layer "In5.Cu")
	)
	(gr_line
		(start 121.412254 -41.412414)
		(end 121.744486 -41.92397)
		(stroke
			(width 0.0508)
			(type default)
		)
		(layer "In5.Cu")
	)
	(gr_line
		(start 121.426224 -49.855628)
		(end 121.430288 -49.836578)
		(stroke
			(width 0.0508)
			(type default)
		)
		(layer "In5.Cu")
	)
	(gr_line
		(start 121.430288 -49.836578)
		(end 121.440956 -49.820068)
		(stroke
			(width 0.0508)
			(type default)
		)
		(layer "In5.Cu")
	)
	(gr_line
		(start 121.599198 -50.620676)
		(end 121.638568 -50.581306)
		(stroke
			(width 0.04445)
			(type default)
		)
		(layer "In5.Cu")
	)
	(gr_line
		(start 121.61393 -49.553622)
		(end 121.628408 -49.53127)
		(stroke
			(width 0.0508)
			(type default)
		)
		(layer "In5.Cu")
	)
	(gr_line
		(start 121.618756 -45.443648)
		(end 121.63171 -45.423582)
		(stroke
			(width 0.0508)
			(type default)
		)
		(layer "In5.Cu")
	)
	(gr_line
		(start 121.628408 -49.53127)
		(end 121.65076 -49.516792)
		(stroke
			(width 0.0508)
			(type default)
		)
		(layer "In5.Cu")
	)
	(gr_line
		(start 121.63171 -45.423582)
		(end 121.635774 -45.400468)
		(stroke
			(width 0.0508)
			(type default)
		)
		(layer "In5.Cu")
	)
	(gr_line
		(start 121.640346 -50.579528)
		(end 121.656348 -50.563526)
		(stroke
			(width 0.04445)
			(type default)
		)
		(layer "In5.Cu")
	)
	(gr_line
		(start 121.6406 -43.090338)
		(end 121.651268 -43.105578)
		(stroke
			(width 0.0508)
			(type default)
		)
		(layer "In5.Cu")
	)
	(gr_line
		(start 121.650506 -41.215056)
		(end 121.910856 -41.270174)
		(stroke
			(width 0.0508)
			(type default)
		)
		(layer "In5.Cu")
	)
	(gr_line
		(start 121.651268 -43.105578)
		(end 121.655332 -43.128438)
		(stroke
			(width 0.0508)
			(type default)
		)
		(layer "In5.Cu")
	)
	(gr_line
		(start 121.656348 -50.541428)
		(end 121.656348 -50.563526)
		(stroke
			(width 0.04445)
			(type default)
		)
		(layer "In5.Cu")
	)
	(gr_arc
		(start 121.820686 -11.547602)
		(mid 121.947488 -11.495083)
		(end 122.00001 -11.368278)
		(stroke
			(width 0.0508)
			(type default)
		)
		(layer "In5.Cu")
	)
	(gr_line
		(start 121.825258 -16.258794)
		(end 121.830592 -16.233648)
		(stroke
			(width 0.0508)
			(type default)
		)
		(layer "In5.Cu")
	)
	(gr_line
		(start 121.825258 -16.208502)
		(end 121.830592 -16.233648)
		(stroke
			(width 0.0508)
			(type default)
		)
		(layer "In5.Cu")
	)
	(gr_line
		(start 121.910856 -41.270174)
		(end 122.076718 -41.525698)
		(stroke
			(width 0.0508)
			(type default)
		)
		(layer "In5.Cu")
	)
	(gr_line
		(start 121.984262 -42.293032)
		(end 121.98477 -42.29354)
		(stroke
			(width 0.0508)
			(type default)
		)
		(layer "In5.Cu")
	)
	(gr_line
		(start 121.985278 -42.293286)
		(end 121.98477 -42.29354)
		(stroke
			(width 0.0508)
			(type default)
		)
		(layer "In5.Cu")
	)
	(gr_line
		(start 121.985278 -42.293286)
		(end 122.193304 -42.690288)
		(stroke
			(width 0.0508)
			(type default)
		)
		(layer "In5.Cu")
	)
	(gr_line
		(start 122.00001 -52.684172)
		(end 122.00001 -53.000148)
		(stroke
			(width 0.04445)
			(type default)
		)
		(layer "In5.Cu")
	)
	(gr_arc
		(start 122.00001 -52.315872)
		(mid 122.026048 -52.378734)
		(end 122.08891 -52.404772)
		(stroke
			(width 0.04445)
			(type default)
		)
		(layer "In5.Cu")
	)
	(gr_line
		(start 122.00001 -52.00015)
		(end 122.00001 -52.315872)
		(stroke
			(width 0.04445)
			(type default)
		)
		(layer "In5.Cu")
	)
	(gr_arc
		(start 122.00001 -12.031726)
		(mid 121.947496 -11.904913)
		(end 121.820686 -11.852402)
		(stroke
			(width 0.0508)
			(type default)
		)
		(layer "In5.Cu")
	)
	(gr_line
		(start 122.00001 -12.031726)
		(end 122.00001 -12.400026)
		(stroke
			(width 0.0508)
			(type default)
		)
		(layer "In5.Cu")
	)
	(gr_line
		(start 122.00001 -10.999978)
		(end 122.00001 -11.368278)
		(stroke
			(width 0.0508)
			(type default)
		)
		(layer "In5.Cu")
	)
	(gr_line
		(start 122.0216 -41.786048)
		(end 122.076718 -41.525698)
		(stroke
			(width 0.0508)
			(type default)
		)
		(layer "In5.Cu")
	)
	(gr_arc
		(start 122.08891 -52.595272)
		(mid 122.026032 -52.621305)
		(end 122.00001 -52.684172)
		(stroke
			(width 0.04445)
			(type default)
		)
		(layer "In5.Cu")
	)
	(gr_line
		(start 122.231404 -42.113454)
		(end 122.249692 -42.141648)
		(stroke
			(width 0.0508)
			(type default)
		)
		(layer "In5.Cu")
	)
	(gr_line
		(start 122.25528 -42.152062)
		(end 122.255534 -42.152062)
		(stroke
			(width 0.0508)
			(type default)
		)
		(layer "In5.Cu")
	)
	(gr_line
		(start 122.25528 -42.152062)
		(end 122.440446 -42.504868)
		(stroke
			(width 0.0508)
			(type default)
		)
		(layer "In5.Cu")
	)
	(gr_line
		(start 122.255788 -42.151046)
		(end 122.256296 -42.151554)
		(stroke
			(width 0.0508)
			(type default)
		)
		(layer "In5.Cu")
	)
	(gr_line
		(start 122.268234 -49.11598)
		(end 122.28322 -49.106328)
		(stroke
			(width 0.0508)
			(type default)
		)
		(layer "In5.Cu")
	)
	(gr_line
		(start 122.28322 -49.106328)
		(end 122.300746 -49.102518)
		(stroke
			(width 0.0508)
			(type default)
		)
		(layer "In5.Cu")
	)
	(gr_line
		(start 122.303286 -21.772118)
		(end 122.30862 -21.797772)
		(stroke
			(width 0.0508)
			(type default)
		)
		(layer "In5.Cu")
	)
	(gr_line
		(start 122.303286 -21.772118)
		(end 122.30862 -21.74748)
		(stroke
			(width 0.0508)
			(type default)
		)
		(layer "In5.Cu")
	)
	(gr_line
		(start 122.30862 -21.797518)
		(end 122.30862 -21.798026)
		(stroke
			(width 0.0508)
			(type default)
		)
		(layer "In5.Cu")
	)
	(gr_line
		(start 122.315732 -21.71319)
		(end 122.422158 -21.213318)
		(stroke
			(width 0.0508)
			(type default)
		)
		(layer "In5.Cu")
	)
	(gr_line
		(start 122.34926 -50.634138)
		(end 122.365262 -50.65014)
		(stroke
			(width 0.04445)
			(type default)
		)
		(layer "In5.Cu")
	)
	(gr_line
		(start 122.34926 -50.61204)
		(end 122.34926 -50.634138)
		(stroke
			(width 0.04445)
			(type default)
		)
		(layer "In5.Cu")
	)
	(gr_line
		(start 122.363738 -46.946312)
		(end 122.695716 -46.43501)
		(stroke
			(width 0.0508)
			(type default)
		)
		(layer "In5.Cu")
	)
	(gr_line
		(start 122.36704 -50.651918)
		(end 122.40641 -50.691288)
		(stroke
			(width 0.04445)
			(type default)
		)
		(layer "In5.Cu")
	)
	(gr_line
		(start 122.39244 -50.24247)
		(end 122.395996 -50.225706)
		(stroke
			(width 0.0508)
			(type default)
		)
		(layer "In5.Cu")
	)
	(gr_line
		(start 122.395996 -50.225706)
		(end 122.405648 -50.21072)
		(stroke
			(width 0.0508)
			(type default)
		)
		(layer "In5.Cu")
	)
	(gr_line
		(start 122.493786 -50.074576)
		(end 122.509026 -50.051208)
		(stroke
			(width 0.0508)
			(type default)
		)
		(layer "In5.Cu")
	)
	(gr_line
		(start 122.509026 -50.051208)
		(end 122.532394 -50.036222)
		(stroke
			(width 0.0508)
			(type default)
		)
		(layer "In5.Cu")
	)
	(gr_line
		(start 122.59691 -50.691288)
		(end 122.63628 -50.651918)
		(stroke
			(width 0.04445)
			(type default)
		)
		(layer "In5.Cu")
	)
	(gr_line
		(start 122.601736 -47.144178)
		(end 122.862086 -47.088806)
		(stroke
			(width 0.0508)
			(type default)
		)
		(layer "In5.Cu")
	)
	(gr_line
		(start 122.614944 -21.771864)
		(end 122.7201 -21.276818)
		(stroke
			(width 0.0508)
			(type default)
		)
		(layer "In5.Cu")
	)
	(gr_line
		(start 122.638058 -50.65014)
		(end 122.65406 -50.634138)
		(stroke
			(width 0.04445)
			(type default)
		)
		(layer "In5.Cu")
	)
	(gr_line
		(start 122.644154 -42.893488)
		(end 122.648218 -42.901108)
		(stroke
			(width 0.0508)
			(type default)
		)
		(layer "In5.Cu")
	)
	(gr_line
		(start 122.648218 -42.901108)
		(end 122.649742 -42.909744)
		(stroke
			(width 0.0508)
			(type default)
		)
		(layer "In5.Cu")
	)
	(gr_line
		(start 122.65406 -50.61204)
		(end 122.65406 -50.634138)
		(stroke
			(width 0.04445)
			(type default)
		)
		(layer "In5.Cu")
	)
	(gr_line
		(start 122.749564 -49.895506)
		(end 122.76455 -49.885854)
		(stroke
			(width 0.0508)
			(type default)
		)
		(layer "In5.Cu")
	)
	(gr_line
		(start 122.76455 -49.885854)
		(end 122.78233 -49.882044)
		(stroke
			(width 0.0508)
			(type default)
		)
		(layer "In5.Cu")
	)
	(gr_line
		(start 122.774202 -44.841922)
		(end 122.782584 -44.821602)
		(stroke
			(width 0.0508)
			(type default)
		)
		(layer "In5.Cu")
	)
	(gr_line
		(start 122.862086 -47.088806)
		(end 123.027948 -46.833282)
		(stroke
			(width 0.0508)
			(type default)
		)
		(layer "In5.Cu")
	)
	(gr_line
		(start 122.97283 -46.572678)
		(end 123.027948 -46.833282)
		(stroke
			(width 0.0508)
			(type default)
		)
		(layer "In5.Cu")
	)
	(gr_line
		(start 123.000008 -51.684174)
		(end 123.000008 -52.00015)
		(stroke
			(width 0.04445)
			(type default)
		)
		(layer "In5.Cu")
	)
	(gr_arc
		(start 123.000008 -51.315874)
		(mid 123.026037 -51.37875)
		(end 123.088908 -51.404774)
		(stroke
			(width 0.04445)
			(type default)
		)
		(layer "In5.Cu")
	)
	(gr_line
		(start 123.000008 -51.000152)
		(end 123.000008 -51.315874)
		(stroke
			(width 0.04445)
			(type default)
		)
		(layer "In5.Cu")
	)
	(gr_arc
		(start 123.088908 -51.595274)
		(mid 123.026032 -51.621308)
		(end 123.000008 -51.684174)
		(stroke
			(width 0.04445)
			(type default)
		)
		(layer "In5.Cu")
	)
	(gr_line
		(start 123.129802 -49.807876)
		(end 123.156218 -49.802034)
		(stroke
			(width 0.0508)
			(type default)
		)
		(layer "In5.Cu")
	)
	(gr_line
		(start 123.156218 -49.802034)
		(end 123.18238 -49.807622)
		(stroke
			(width 0.0508)
			(type default)
		)
		(layer "In5.Cu")
	)
	(gr_line
		(start 123.428506 -48.862996)
		(end 124.023882 -48.736504)
		(stroke
			(width 0.0508)
			(type default)
		)
		(layer "In5.Cu")
	)
	(gr_line
		(start 123.456446 -49.171098)
		(end 123.679458 -49.316132)
		(stroke
			(width 0.0508)
			(type default)
		)
		(layer "In5.Cu")
	)
	(gr_arc
		(start 123.620784 -10.347706)
		(mid 123.747585 -10.295183)
		(end 123.800108 -10.168382)
		(stroke
			(width 0.0508)
			(type default)
		)
		(layer "In5.Cu")
	)
	(gr_line
		(start 123.67641 -45.517816)
		(end 123.693682 -45.493178)
		(stroke
			(width 0.0508)
			(type default)
		)
		(layer "In5.Cu")
	)
	(gr_line
		(start 123.679458 -49.316132)
		(end 123.977654 -49.252632)
		(stroke
			(width 0.0508)
			(type default)
		)
		(layer "In5.Cu")
	)
	(gr_line
		(start 123.693682 -45.493178)
		(end 123.698508 -45.464476)
		(stroke
			(width 0.0508)
			(type default)
		)
		(layer "In5.Cu")
	)
	(gr_line
		(start 123.759976 -16.385032)
		(end 123.76531 -16.359886)
		(stroke
			(width 0.0508)
			(type default)
		)
		(layer "In5.Cu")
	)
	(gr_line
		(start 123.759976 -16.33474)
		(end 123.76531 -16.359886)
		(stroke
			(width 0.0508)
			(type default)
		)
		(layer "In5.Cu")
	)
	(gr_arc
		(start 123.800108 -10.83183)
		(mid 123.747595 -10.705015)
		(end 123.620784 -10.652506)
		(stroke
			(width 0.0508)
			(type default)
		)
		(layer "In5.Cu")
	)
	(gr_line
		(start 123.800108 -10.83183)
		(end 123.800108 -11.20013)
		(stroke
			(width 0.0508)
			(type default)
		)
		(layer "In5.Cu")
	)
	(gr_line
		(start 123.800108 -9.800082)
		(end 123.800108 -10.168382)
		(stroke
			(width 0.0508)
			(type default)
		)
		(layer "In5.Cu")
	)
	(gr_line
		(start 123.977654 -49.252632)
		(end 124.122688 -49.02962)
		(stroke
			(width 0.0508)
			(type default)
		)
		(layer "In5.Cu")
	)
	(gr_line
		(start 124.000006 -52.684172)
		(end 124.000006 -53.000148)
		(stroke
			(width 0.04445)
			(type default)
		)
		(layer "In5.Cu")
	)
	(gr_arc
		(start 124.000006 -52.315872)
		(mid 124.026035 -52.37875)
		(end 124.088906 -52.404772)
		(stroke
			(width 0.04445)
			(type default)
		)
		(layer "In5.Cu")
	)
	(gr_line
		(start 124.000006 -52.00015)
		(end 124.000006 -52.315872)
		(stroke
			(width 0.04445)
			(type default)
		)
		(layer "In5.Cu")
	)
	(gr_line
		(start 124.04344 -50.302414)
		(end 124.068586 -50.307748)
		(stroke
			(width 0.0508)
			(type default)
		)
		(layer "In5.Cu")
	)
	(gr_line
		(start 124.068586 -50.307748)
		(end 124.093732 -50.302414)
		(stroke
			(width 0.0508)
			(type default)
		)
		(layer "In5.Cu")
	)
	(gr_arc
		(start 124.088906 -52.595272)
		(mid 124.02603 -52.621306)
		(end 124.000006 -52.684172)
		(stroke
			(width 0.04445)
			(type default)
		)
		(layer "In5.Cu")
	)
	(gr_line
		(start 124.60478 -41.7322)
		(end 124.60859 -41.749726)
		(stroke
			(width 0.0508)
			(type default)
		)
		(layer "In5.Cu")
	)
	(gr_line
		(start 124.60859 -41.749726)
		(end 124.618242 -41.764712)
		(stroke
			(width 0.0508)
			(type default)
		)
		(layer "In5.Cu")
	)
	(gr_line
		(start 124.75337 -19.463512)
		(end 124.758704 -19.488658)
		(stroke
			(width 0.0508)
			(type default)
		)
		(layer "In5.Cu")
	)
	(gr_line
		(start 124.75337 -19.463512)
		(end 124.758704 -19.438366)
		(stroke
			(width 0.0508)
			(type default)
		)
		(layer "In5.Cu")
	)
	(gr_line
		(start 124.895356 -48.862996)
		(end 124.912882 -48.859186)
		(stroke
			(width 0.0508)
			(type default)
		)
		(layer "In5.Cu")
	)
	(gr_line
		(start 124.912882 -48.859186)
		(end 124.927868 -48.849534)
		(stroke
			(width 0.0508)
			(type default)
		)
		(layer "In5.Cu")
	)
	(gr_line
		(start 125.29947 -48.608488)
		(end 125.322838 -48.593502)
		(stroke
			(width 0.0508)
			(type default)
		)
		(layer "In5.Cu")
	)
	(gr_line
		(start 125.322838 -48.593502)
		(end 125.337824 -48.570388)
		(stroke
			(width 0.0508)
			(type default)
		)
		(layer "In5.Cu")
	)
	(gr_arc
		(start 125.420882 -11.547602)
		(mid 125.547687 -11.495084)
		(end 125.600206 -11.368278)
		(stroke
			(width 0.0508)
			(type default)
		)
		(layer "In5.Cu")
	)
	(gr_line
		(start 125.502416 -48.31715)
		(end 125.50648 -48.3108)
		(stroke
			(width 0.0508)
			(type default)
		)
		(layer "In5.Cu")
	)
	(gr_line
		(start 125.50648 -48.3108)
		(end 125.508258 -48.303942)
		(stroke
			(width 0.0508)
			(type default)
		)
		(layer "In5.Cu")
	)
	(gr_line
		(start 125.530102 -17.275302)
		(end 125.535436 -17.250156)
		(stroke
			(width 0.0508)
			(type default)
		)
		(layer "In5.Cu")
	)
	(gr_line
		(start 125.530102 -17.22501)
		(end 125.535436 -17.250156)
		(stroke
			(width 0.0508)
			(type default)
		)
		(layer "In5.Cu")
	)
	(gr_line
		(start 125.54712 -42.635424)
		(end 125.55728 -42.651172)
		(stroke
			(width 0.0508)
			(type default)
		)
		(layer "In5.Cu")
	)
	(gr_line
		(start 125.55728 -42.651172)
		(end 125.560836 -42.668698)
		(stroke
			(width 0.0508)
			(type default)
		)
		(layer "In5.Cu")
	)
	(gr_arc
		(start 125.600206 -12.031726)
		(mid 125.547691 -11.904914)
		(end 125.420882 -11.852402)
		(stroke
			(width 0.0508)
			(type default)
		)
		(layer "In5.Cu")
	)
	(gr_line
		(start 125.600206 -12.031726)
		(end 125.600206 -12.400026)
		(stroke
			(width 0.0508)
			(type default)
		)
		(layer "In5.Cu")
	)
	(gr_line
		(start 125.600206 -10.999978)
		(end 125.600206 -11.368278)
		(stroke
			(width 0.0508)
			(type default)
		)
		(layer "In5.Cu")
	)
	(gr_line
		(start 126.132336 -45.399452)
		(end 126.13767 -45.374052)
		(stroke
			(width 0.0508)
			(type default)
		)
		(layer "In5.Cu")
	)
	(gr_line
		(start 126.132336 -45.348906)
		(end 126.13767 -45.374052)
		(stroke
			(width 0.0508)
			(type default)
		)
		(layer "In5.Cu")
	)
	(gr_line
		(start 126.13767 -49.868328)
		(end 126.150624 -49.865534)
		(stroke
			(width 0.0508)
			(type default)
		)
		(layer "In5.Cu")
	)
	(gr_line
		(start 126.15037 -49.86528)
		(end 126.150624 -49.865534)
		(stroke
			(width 0.0508)
			(type default)
		)
		(layer "In5.Cu")
	)
	(gr_line
		(start 126.15037 -49.86528)
		(end 126.16053 -49.859184)
		(stroke
			(width 0.0508)
			(type default)
		)
		(layer "In5.Cu")
	)
	(gr_line
		(start 126.378208 -40.944038)
		(end 126.382018 -40.961564)
		(stroke
			(width 0.0508)
			(type default)
		)
		(layer "In5.Cu")
	)
	(gr_line
		(start 126.382018 -40.961564)
		(end 126.39167 -40.97655)
		(stroke
			(width 0.0508)
			(type default)
		)
		(layer "In5.Cu")
	)
	(gr_arc
		(start 127.220726 -10.347706)
		(mid 127.347504 -10.295173)
		(end 127.40005 -10.168382)
		(stroke
			(width 0.0508)
			(type default)
		)
		(layer "In5.Cu")
	)
	(gr_line
		(start 127.271272 -48.693324)
		(end 127.603758 -48.181006)
		(stroke
			(width 0.0508)
			(type default)
		)
		(layer "In5.Cu")
	)
	(gr_line
		(start 127.313944 -49.162208)
		(end 127.340868 -49.145952)
		(stroke
			(width 0.0508)
			(type default)
		)
		(layer "In5.Cu")
	)
	(gr_line
		(start 127.340868 -49.145952)
		(end 127.358394 -49.119028)
		(stroke
			(width 0.0508)
			(type default)
		)
		(layer "In5.Cu")
	)
	(gr_line
		(start 127.34925 -50.665126)
		(end 127.365252 -50.681128)
		(stroke
			(width 0.04445)
			(type default)
		)
		(layer "In5.Cu")
	)
	(gr_line
		(start 127.34925 -50.643028)
		(end 127.34925 -50.665126)
		(stroke
			(width 0.04445)
			(type default)
		)
		(layer "In5.Cu")
	)
	(gr_line
		(start 127.34925 -50.404268)
		(end 127.37719 -50.361088)
		(stroke
			(width 0.0508)
			(type default)
		)
		(layer "In5.Cu")
	)
	(gr_line
		(start 127.36703 -50.682906)
		(end 127.4064 -50.722276)
		(stroke
			(width 0.04445)
			(type default)
		)
		(layer "In5.Cu")
	)
	(gr_arc
		(start 127.40005 -10.83183)
		(mid 127.347539 -10.705)
		(end 127.220726 -10.652506)
		(stroke
			(width 0.0508)
			(type default)
		)
		(layer "In5.Cu")
	)
	(gr_line
		(start 127.40005 -10.83183)
		(end 127.40005 -11.20013)
		(stroke
			(width 0.0508)
			(type default)
		)
		(layer "In5.Cu")
	)
	(gr_line
		(start 127.40005 -9.800082)
		(end 127.40005 -10.168382)
		(stroke
			(width 0.0508)
			(type default)
		)
		(layer "In5.Cu")
	)
	(gr_line
		(start 127.510032 -48.889666)
		(end 127.770382 -48.834294)
		(stroke
			(width 0.0508)
			(type default)
		)
		(layer "In5.Cu")
	)
	(gr_line
		(start 127.5969 -50.722276)
		(end 127.63627 -50.682906)
		(stroke
			(width 0.04445)
			(type default)
		)
		(layer "In5.Cu")
	)
	(gr_line
		(start 127.638048 -50.681128)
		(end 127.65405 -50.665126)
		(stroke
			(width 0.04445)
			(type default)
		)
		(layer "In5.Cu")
	)
	(gr_line
		(start 127.65405 -50.643028)
		(end 127.65405 -50.665126)
		(stroke
			(width 0.04445)
			(type default)
		)
		(layer "In5.Cu")
	)
	(gr_line
		(start 127.690118 -49.878996)
		(end 127.704596 -49.856644)
		(stroke
			(width 0.0508)
			(type default)
		)
		(layer "In5.Cu")
	)
	(gr_line
		(start 127.704596 -49.856644)
		(end 127.727202 -49.841912)
		(stroke
			(width 0.0508)
			(type default)
		)
		(layer "In5.Cu")
	)
	(gr_line
		(start 127.770382 -48.834294)
		(end 127.936498 -48.57877)
		(stroke
			(width 0.0508)
			(type default)
		)
		(layer "In5.Cu")
	)
	(gr_line
		(start 127.881126 -48.31842)
		(end 127.936498 -48.57877)
		(stroke
			(width 0.0508)
			(type default)
		)
		(layer "In5.Cu")
	)
	(gr_line
		(start 127.98425 -42.868596)
		(end 127.993902 -42.883582)
		(stroke
			(width 0.0508)
			(type default)
		)
		(layer "In5.Cu")
	)
	(gr_line
		(start 127.993902 -42.883582)
		(end 127.997712 -42.901108)
		(stroke
			(width 0.0508)
			(type default)
		)
		(layer "In5.Cu")
	)
	(gr_line
		(start 128.300226 -47.668688)
		(end 128.310386 -47.65294)
		(stroke
			(width 0.0508)
			(type default)
		)
		(layer "In5.Cu")
	)
	(gr_line
		(start 128.310386 -47.65294)
		(end 128.313942 -47.635414)
		(stroke
			(width 0.0508)
			(type default)
		)
		(layer "In5.Cu")
	)
	(gr_line
		(start 128.653794 -46.04004)
		(end 128.659128 -46.01464)
		(stroke
			(width 0.0508)
			(type default)
		)
		(layer "In5.Cu")
	)
	(gr_line
		(start 128.653794 -45.989494)
		(end 128.659128 -46.01464)
		(stroke
			(width 0.0508)
			(type default)
		)
		(layer "In5.Cu")
	)
	(gr_line
		(start 128.693926 -49.214024)
		(end 128.708912 -49.204372)
		(stroke
			(width 0.0508)
			(type default)
		)
		(layer "In5.Cu")
	)
	(gr_line
		(start 128.708912 -49.204372)
		(end 128.726438 -49.200562)
		(stroke
			(width 0.0508)
			(type default)
		)
		(layer "In5.Cu")
	)
	(gr_line
		(start 128.999996 -72.00011)
		(end 129.315718 -72.00011)
		(stroke
			(width 0.04445)
			(type default)
		)
		(layer "In5.Cu")
	)
	(gr_line
		(start 128.999996 -70.000114)
		(end 129.315718 -70.000114)
		(stroke
			(width 0.04445)
			(type default)
		)
		(layer "In5.Cu")
	)
	(gr_line
		(start 128.999996 -68.000118)
		(end 129.314448 -68.000118)
		(stroke
			(width 0.04445)
			(type default)
		)
		(layer "In5.Cu")
	)
	(gr_line
		(start 128.999996 -65.000124)
		(end 129.315718 -65.000124)
		(stroke
			(width 0.04445)
			(type default)
		)
		(layer "In5.Cu")
	)
	(gr_line
		(start 128.999996 -63.000128)
		(end 129.315718 -63.000128)
		(stroke
			(width 0.04445)
			(type default)
		)
		(layer "In5.Cu")
	)
	(gr_line
		(start 128.999996 -61.000132)
		(end 129.315718 -61.000132)
		(stroke
			(width 0.04445)
			(type default)
		)
		(layer "In5.Cu")
	)
	(gr_arc
		(start 129.020824 -11.547602)
		(mid 129.147602 -11.495069)
		(end 129.200148 -11.368278)
		(stroke
			(width 0.0508)
			(type default)
		)
		(layer "In5.Cu")
	)
	(gr_line
		(start 129.086102 -49.43602)
		(end 129.103628 -49.43221)
		(stroke
			(width 0.0508)
			(type default)
		)
		(layer "In5.Cu")
	)
	(gr_line
		(start 129.103628 -49.43221)
		(end 129.118614 -49.422558)
		(stroke
			(width 0.0508)
			(type default)
		)
		(layer "In5.Cu")
	)
	(gr_arc
		(start 129.200148 -12.031726)
		(mid 129.147636 -11.904899)
		(end 129.020824 -11.852402)
		(stroke
			(width 0.0508)
			(type default)
		)
		(layer "In5.Cu")
	)
	(gr_line
		(start 129.200148 -12.031726)
		(end 129.200148 -12.400026)
		(stroke
			(width 0.0508)
			(type default)
		)
		(layer "In5.Cu")
	)
	(gr_line
		(start 129.200148 -10.999978)
		(end 129.200148 -11.368278)
		(stroke
			(width 0.0508)
			(type default)
		)
		(layer "In5.Cu")
	)
	(gr_line
		(start 129.25425 -50.5968)
		(end 129.29362 -50.63617)
		(stroke
			(width 0.04445)
			(type default)
		)
		(layer "In5.Cu")
	)
	(gr_line
		(start 129.25425 -50.4063)
		(end 129.29362 -50.36693)
		(stroke
			(width 0.04445)
			(type default)
		)
		(layer "In5.Cu")
	)
	(gr_line
		(start 129.295398 -50.637948)
		(end 129.3114 -50.65395)
		(stroke
			(width 0.04445)
			(type default)
		)
		(layer "In5.Cu")
	)
	(gr_line
		(start 129.295398 -50.365152)
		(end 129.3114 -50.34915)
		(stroke
			(width 0.04445)
			(type default)
		)
		(layer "In5.Cu")
	)
	(gr_line
		(start 129.3114 -50.65395)
		(end 129.333498 -50.65395)
		(stroke
			(width 0.04445)
			(type default)
		)
		(layer "In5.Cu")
	)
	(gr_line
		(start 129.3114 -50.34915)
		(end 129.333498 -50.34915)
		(stroke
			(width 0.04445)
			(type default)
		)
		(layer "In5.Cu")
	)
	(gr_arc
		(start 129.403348 -68.089018)
		(mid 129.377319 -68.026128)
		(end 129.314448 -68.000118)
		(stroke
			(width 0.04445)
			(type default)
		)
		(layer "In5.Cu")
	)
	(gr_arc
		(start 129.404618 -72.08901)
		(mid 129.378584 -72.026135)
		(end 129.315718 -72.00011)
		(stroke
			(width 0.04445)
			(type default)
		)
		(layer "In5.Cu")
	)
	(gr_arc
		(start 129.404618 -70.089014)
		(mid 129.378586 -70.026137)
		(end 129.315718 -70.000114)
		(stroke
			(width 0.04445)
			(type default)
		)
		(layer "In5.Cu")
	)
	(gr_arc
		(start 129.404618 -65.089024)
		(mid 129.378589 -65.02614)
		(end 129.315718 -65.000124)
		(stroke
			(width 0.04445)
			(type default)
		)
		(layer "In5.Cu")
	)
	(gr_arc
		(start 129.404618 -63.089028)
		(mid 129.37858 -63.026166)
		(end 129.315718 -63.000128)
		(stroke
			(width 0.04445)
			(type default)
		)
		(layer "In5.Cu")
	)
	(gr_arc
		(start 129.404618 -61.089032)
		(mid 129.378592 -61.026143)
		(end 129.315718 -61.000132)
		(stroke
			(width 0.04445)
			(type default)
		)
		(layer "In5.Cu")
	)
	(gr_line
		(start 129.660396 -50.65395)
		(end 129.722626 -50.59172)
		(stroke
			(width 0.0508)
			(type default)
		)
		(layer "In5.Cu")
	)
	(gr_arc
		(start 129.682748 -68.000118)
		(mid 129.619862 -68.02614)
		(end 129.593848 -68.089018)
		(stroke
			(width 0.04445)
			(type default)
		)
		(layer "In5.Cu")
	)
	(gr_line
		(start 129.682748 -68.000118)
		(end 129.999994 -68.000118)
		(stroke
			(width 0.04445)
			(type default)
		)
		(layer "In5.Cu")
	)
	(gr_line
		(start 129.684018 -72.00011)
		(end 129.999994 -72.00011)
		(stroke
			(width 0.04445)
			(type default)
		)
		(layer "In5.Cu")
	)
	(gr_arc
		(start 129.684018 -70.000114)
		(mid 129.62115 -70.026147)
		(end 129.595118 -70.089014)
		(stroke
			(width 0.04445)
			(type default)
		)
		(layer "In5.Cu")
	)
	(gr_line
		(start 129.684018 -70.000114)
		(end 129.999994 -70.000114)
		(stroke
			(width 0.04445)
			(type default)
		)
		(layer "In5.Cu")
	)
	(gr_line
		(start 129.684018 -65.000124)
		(end 129.999994 -65.000124)
		(stroke
			(width 0.04445)
			(type default)
		)
		(layer "In5.Cu")
	)
	(gr_arc
		(start 129.684018 -63.000128)
		(mid 129.621156 -63.026166)
		(end 129.595118 -63.089028)
		(stroke
			(width 0.04445)
			(type default)
		)
		(layer "In5.Cu")
	)
	(gr_line
		(start 129.684018 -63.000128)
		(end 129.999994 -63.000128)
		(stroke
			(width 0.04445)
			(type default)
		)
		(layer "In5.Cu")
	)
	(gr_arc
		(start 129.684018 -61.000132)
		(mid 129.621156 -61.026166)
		(end 129.595118 -61.089032)
		(stroke
			(width 0.04445)
			(type default)
		)
		(layer "In5.Cu")
	)
	(gr_line
		(start 129.684018 -61.000132)
		(end 129.999994 -61.000132)
		(stroke
			(width 0.04445)
			(type default)
		)
		(layer "In5.Cu")
	)
	(gr_line
		(start 129.75717 -16.259556)
		(end 129.94513 -16.447516)
		(stroke
			(width 0.0508)
			(type default)
		)
		(layer "In5.Cu")
	)
	(gr_line
		(start 129.75717 -15.954756)
		(end 129.75717 -16.259556)
		(stroke
			(width 0.0508)
			(type default)
		)
		(layer "In5.Cu")
	)
	(gr_line
		(start 129.75717 -15.954756)
		(end 129.94513 -15.766796)
		(stroke
			(width 0.0508)
			(type default)
		)
		(layer "In5.Cu")
	)
	(gr_line
		(start 129.75717 -15.268956)
		(end 129.94513 -15.456916)
		(stroke
			(width 0.0508)
			(type default)
		)
		(layer "In5.Cu")
	)
	(gr_line
		(start 129.75717 -14.964156)
		(end 129.75717 -15.268956)
		(stroke
			(width 0.0508)
			(type default)
		)
		(layer "In5.Cu")
	)
	(gr_line
		(start 129.75717 -14.964156)
		(end 129.94513 -14.776196)
		(stroke
			(width 0.0508)
			(type default)
		)
		(layer "In5.Cu")
	)
	(gr_line
		(start 129.97815 -48.441356)
		(end 130.03149 -48.35906)
		(stroke
			(width 0.0508)
			(type default)
		)
		(layer "In5.Cu")
	)
	(gr_line
		(start 129.999994 -73.000108)
		(end 130.315716 -73.000108)
		(stroke
			(width 0.04445)
			(type default)
		)
		(layer "In5.Cu")
	)
	(gr_line
		(start 129.999994 -71.000112)
		(end 130.315716 -71.000112)
		(stroke
			(width 0.04445)
			(type default)
		)
		(layer "In5.Cu")
	)
	(gr_line
		(start 129.999994 -69.000116)
		(end 130.290316 -69.000116)
		(stroke
			(width 0.04445)
			(type default)
		)
		(layer "In5.Cu")
	)
	(gr_line
		(start 129.999994 -66.000122)
		(end 130.315716 -66.000122)
		(stroke
			(width 0.04445)
			(type default)
		)
		(layer "In5.Cu")
	)
	(gr_line
		(start 129.999994 -64.000126)
		(end 130.315716 -64.000126)
		(stroke
			(width 0.04445)
			(type default)
		)
		(layer "In5.Cu")
	)
	(gr_line
		(start 129.999994 -62.00013)
		(end 130.315716 -62.00013)
		(stroke
			(width 0.04445)
			(type default)
		)
		(layer "In5.Cu")
	)
	(gr_line
		(start 130.03149 -48.35906)
		(end 130.15214 -48.172878)
		(stroke
			(width 0.0508)
			(type default)
		)
		(layer "In5.Cu")
	)
	(gr_line
		(start 130.108198 -48.7807)
		(end 130.13055 -48.766222)
		(stroke
			(width 0.0508)
			(type default)
		)
		(layer "In5.Cu")
	)
	(gr_line
		(start 130.13055 -48.766222)
		(end 130.145028 -48.74387)
		(stroke
			(width 0.0508)
			(type default)
		)
		(layer "In5.Cu")
	)
	(gr_line
		(start 130.19913 -48.660304)
		(end 130.410966 -48.333914)
		(stroke
			(width 0.0508)
			(type default)
		)
		(layer "In5.Cu")
	)
	(gr_line
		(start 130.2512 -45.331888)
		(end 130.269488 -45.417994)
		(stroke
			(width 0.0508)
			(type default)
		)
		(layer "In5.Cu")
	)
	(gr_line
		(start 130.25247 -16.071596)
		(end 130.25247 -16.142716)
		(stroke
			(width 0.0508)
			(type default)
		)
		(layer "In5.Cu")
	)
	(gr_line
		(start 130.25247 -15.080996)
		(end 130.25247 -15.152116)
		(stroke
			(width 0.0508)
			(type default)
		)
		(layer "In5.Cu")
	)
	(gr_line
		(start 130.269488 -45.417994)
		(end 130.360928 -45.839888)
		(stroke
			(width 0.0508)
			(type default)
		)
		(layer "In5.Cu")
	)
	(gr_line
		(start 130.359912 -49.523142)
		(end 130.398012 -49.485042)
		(stroke
			(width 0.0508)
			(type default)
		)
		(layer "In5.Cu")
	)
	(gr_line
		(start 130.360928 -45.839888)
		(end 130.377692 -45.924216)
		(stroke
			(width 0.0508)
			(type default)
		)
		(layer "In5.Cu")
	)
	(gr_line
		(start 130.366516 -73.605898)
		(end 130.366516 -73.72985)
		(stroke
			(width 0.0508)
			(type default)
		)
		(layer "In5.Cu")
	)
	(gr_line
		(start 130.366516 -73.5838)
		(end 130.366516 -73.605898)
		(stroke
			(width 0.04445)
			(type default)
		)
		(layer "In5.Cu")
	)
	(gr_line
		(start 130.366516 -73.5838)
		(end 130.395218 -73.555098)
		(stroke
			(width 0.04445)
			(type default)
		)
		(layer "In5.Cu")
	)
	(gr_line
		(start 130.367532 -60.27039)
		(end 130.383534 -60.286392)
		(stroke
			(width 0.04445)
			(type default)
		)
		(layer "In5.Cu")
	)
	(gr_line
		(start 130.367532 -60.248292)
		(end 130.367532 -60.27039)
		(stroke
			(width 0.04445)
			(type default)
		)
		(layer "In5.Cu")
	)
	(gr_line
		(start 130.367532 -60.098432)
		(end 130.367532 -60.248292)
		(stroke
			(width 0.0508)
			(type default)
		)
		(layer "In5.Cu")
	)
	(gr_line
		(start 130.377692 -45.923962)
		(end 130.377692 -45.924216)
		(stroke
			(width 0.0508)
			(type default)
		)
		(layer "In5.Cu")
	)
	(gr_arc
		(start 130.379216 -69.089016)
		(mid 130.353184 -69.026138)
		(end 130.290316 -69.000116)
		(stroke
			(width 0.04445)
			(type default)
		)
		(layer "In5.Cu")
	)
	(gr_line
		(start 130.385312 -60.28817)
		(end 130.40614 -60.308998)
		(stroke
			(width 0.04445)
			(type default)
		)
		(layer "In5.Cu")
	)
	(gr_line
		(start 130.396996 -73.55332)
		(end 130.404616 -73.5457)
		(stroke
			(width 0.04445)
			(type default)
		)
		(layer "In5.Cu")
	)
	(gr_line
		(start 130.398012 -49.485042)
		(end 130.450336 -49.473866)
		(stroke
			(width 0.0508)
			(type default)
		)
		(layer "In5.Cu")
	)
	(gr_arc
		(start 130.404616 -73.089008)
		(mid 130.378582 -73.026135)
		(end 130.315716 -73.000108)
		(stroke
			(width 0.04445)
			(type default)
		)
		(layer "In5.Cu")
	)
	(gr_arc
		(start 130.404616 -71.089012)
		(mid 130.378578 -71.02615)
		(end 130.315716 -71.000112)
		(stroke
			(width 0.04445)
			(type default)
		)
		(layer "In5.Cu")
	)
	(gr_arc
		(start 130.404616 -66.089022)
		(mid 130.378587 -66.02614)
		(end 130.315716 -66.000122)
		(stroke
			(width 0.04445)
			(type default)
		)
		(layer "In5.Cu")
	)
	(gr_arc
		(start 130.404616 -64.089026)
		(mid 130.378588 -64.026142)
		(end 130.315716 -64.000126)
		(stroke
			(width 0.04445)
			(type default)
		)
		(layer "In5.Cu")
	)
	(gr_arc
		(start 130.404616 -62.08903)
		(mid 130.378589 -62.026143)
		(end 130.315716 -62.00013)
		(stroke
			(width 0.04445)
			(type default)
		)
		(layer "In5.Cu")
	)
	(gr_line
		(start 130.429762 -48.304704)
		(end 130.438652 -48.291242)
		(stroke
			(width 0.0508)
			(type default)
		)
		(layer "In5.Cu")
	)
	(gr_line
		(start 130.438652 -48.291242)
		(end 130.442208 -48.274478)
		(stroke
			(width 0.0508)
			(type default)
		)
		(layer "In5.Cu")
	)
	(gr_line
		(start 130.544316 -45.232828)
		(end 130.767582 -45.377862)
		(stroke
			(width 0.0508)
			(type default)
		)
		(layer "In5.Cu")
	)
	(gr_line
		(start 130.595116 -73.4822)
		(end 130.666236 -73.55332)
		(stroke
			(width 0.04445)
			(type default)
		)
		(layer "In5.Cu")
	)
	(gr_line
		(start 130.595116 -73.358248)
		(end 130.595116 -73.4822)
		(stroke
			(width 0.04445)
			(type default)
		)
		(layer "In5.Cu")
	)
	(gr_line
		(start 130.59664 -60.346082)
		(end 130.59664 -60.495942)
		(stroke
			(width 0.04445)
			(type default)
		)
		(layer "In5.Cu")
	)
	(gr_line
		(start 130.59664 -60.346082)
		(end 130.654552 -60.28817)
		(stroke
			(width 0.04445)
			(type default)
		)
		(layer "In5.Cu")
	)
	(gr_line
		(start 130.65633 -60.286392)
		(end 130.672332 -60.27039)
		(stroke
			(width 0.04445)
			(type default)
		)
		(layer "In5.Cu")
	)
	(gr_arc
		(start 130.658616 -69.000116)
		(mid 130.595754 -69.026154)
		(end 130.569716 -69.089016)
		(stroke
			(width 0.04445)
			(type default)
		)
		(layer "In5.Cu")
	)
	(gr_line
		(start 130.658616 -69.000116)
		(end 130.999992 -69.000116)
		(stroke
			(width 0.04445)
			(type default)
		)
		(layer "In5.Cu")
	)
	(gr_line
		(start 130.668014 -73.555098)
		(end 130.671316 -73.5584)
		(stroke
			(width 0.04445)
			(type default)
		)
		(layer "In5.Cu")
	)
	(gr_line
		(start 130.671316 -73.5584)
		(end 130.671316 -73.605898)
		(stroke
			(width 0.04445)
			(type default)
		)
		(layer "In5.Cu")
	)
	(gr_line
		(start 130.672332 -60.248292)
		(end 130.672332 -60.27039)
		(stroke
			(width 0.04445)
			(type default)
		)
		(layer "In5.Cu")
	)
	(gr_arc
		(start 130.684016 -73.000108)
		(mid 130.621154 -73.026146)
		(end 130.595116 -73.089008)
		(stroke
			(width 0.04445)
			(type default)
		)
		(layer "In5.Cu")
	)
	(gr_line
		(start 130.684016 -73.000108)
		(end 130.999992 -73.000108)
		(stroke
			(width 0.04445)
			(type default)
		)
		(layer "In5.Cu")
	)
	(gr_arc
		(start 130.684016 -71.000112)
		(mid 130.621148 -71.026145)
		(end 130.595116 -71.089012)
		(stroke
			(width 0.04445)
			(type default)
		)
		(layer "In5.Cu")
	)
	(gr_line
		(start 130.684016 -71.000112)
		(end 130.999992 -71.000112)
		(stroke
			(width 0.04445)
			(type default)
		)
		(layer "In5.Cu")
	)
	(gr_arc
		(start 130.684016 -66.000122)
		(mid 130.621154 -66.02616)
		(end 130.595116 -66.089022)
		(stroke
			(width 0.04445)
			(type default)
		)
		(layer "In5.Cu")
	)
	(gr_line
		(start 130.684016 -66.000122)
		(end 130.999992 -66.000122)
		(stroke
			(width 0.04445)
			(type default)
		)
		(layer "In5.Cu")
	)
	(gr_arc
		(start 130.684016 -64.000126)
		(mid 130.621153 -64.02616)
		(end 130.595116 -64.089026)
		(stroke
			(width 0.04445)
			(type default)
		)
		(layer "In5.Cu")
	)
	(gr_line
		(start 130.684016 -64.000126)
		(end 130.999992 -64.000126)
		(stroke
			(width 0.04445)
			(type default)
		)
		(layer "In5.Cu")
	)
	(gr_line
		(start 130.684016 -62.00013)
		(end 130.999992 -62.00013)
		(stroke
			(width 0.04445)
			(type default)
		)
		(layer "In5.Cu")
	)
	(gr_line
		(start 130.686048 -45.89907)
		(end 130.830828 -45.676058)
		(stroke
			(width 0.0508)
			(type default)
		)
		(layer "In5.Cu")
	)
	(gr_line
		(start 130.767582 -45.377862)
		(end 130.830828 -45.676058)
		(stroke
			(width 0.0508)
			(type default)
		)
		(layer "In5.Cu")
	)
	(gr_line
		(start 130.80619 -46.56328)
		(end 130.811524 -46.538642)
		(stroke
			(width 0.0508)
			(type default)
		)
		(layer "In5.Cu")
	)
	(gr_line
		(start 130.806698 -46.514258)
		(end 130.811524 -46.538642)
		(stroke
			(width 0.0508)
			(type default)
		)
		(layer "In5.Cu")
	)
	(gr_arc
		(start 130.820668 -10.347706)
		(mid 130.947469 -10.295183)
		(end 130.999992 -10.168382)
		(stroke
			(width 0.0508)
			(type default)
		)
		(layer "In5.Cu")
	)
	(gr_line
		(start 130.889756 -52.714398)
		(end 130.893566 -52.696872)
		(stroke
			(width 0.0508)
			(type default)
		)
		(layer "In5.Cu")
	)
	(gr_line
		(start 130.893566 -52.696872)
		(end 130.903218 -52.681886)
		(stroke
			(width 0.0508)
			(type default)
		)
		(layer "In5.Cu")
	)
	(gr_arc
		(start 130.999992 -10.83183)
		(mid 130.947478 -10.705021)
		(end 130.820668 -10.652506)
		(stroke
			(width 0.0508)
			(type default)
		)
		(layer "In5.Cu")
	)
	(gr_line
		(start 130.999992 -10.83183)
		(end 130.999992 -11.20013)
		(stroke
			(width 0.0508)
			(type default)
		)
		(layer "In5.Cu")
	)
	(gr_line
		(start 130.999992 -9.800082)
		(end 130.999992 -10.168382)
		(stroke
			(width 0.0508)
			(type default)
		)
		(layer "In5.Cu")
	)
	(gr_line
		(start 131.029456 -52.137818)
		(end 131.084574 -52.398168)
		(stroke
			(width 0.0508)
			(type default)
		)
		(layer "In5.Cu")
	)
	(gr_line
		(start 131.029456 -52.137818)
		(end 131.195572 -51.882294)
		(stroke
			(width 0.0508)
			(type default)
		)
		(layer "In5.Cu")
	)
	(gr_line
		(start 131.037838 -66.82105)
		(end 131.077208 -66.86042)
		(stroke
			(width 0.04445)
			(type default)
		)
		(layer "In5.Cu")
	)
	(gr_line
		(start 131.037838 -66.63055)
		(end 131.077208 -66.59118)
		(stroke
			(width 0.04445)
			(type default)
		)
		(layer "In5.Cu")
	)
	(gr_line
		(start 131.078986 -66.862198)
		(end 131.094988 -66.8782)
		(stroke
			(width 0.04445)
			(type default)
		)
		(layer "In5.Cu")
	)
	(gr_line
		(start 131.078986 -66.589402)
		(end 131.094988 -66.5734)
		(stroke
			(width 0.04445)
			(type default)
		)
		(layer "In5.Cu")
	)
	(gr_line
		(start 131.094988 -66.8782)
		(end 131.117086 -66.8782)
		(stroke
			(width 0.04445)
			(type default)
		)
		(layer "In5.Cu")
	)
	(gr_line
		(start 131.094988 -66.5734)
		(end 131.117086 -66.5734)
		(stroke
			(width 0.04445)
			(type default)
		)
		(layer "In5.Cu")
	)
	(gr_line
		(start 131.188206 -69.597016)
		(end 131.339844 -69.597016)
		(stroke
			(width 0.04445)
			(type default)
		)
		(layer "In5.Cu")
	)
	(gr_line
		(start 131.195572 -51.882294)
		(end 131.455668 -51.826922)
		(stroke
			(width 0.0508)
			(type default)
		)
		(layer "In5.Cu")
	)
	(gr_line
		(start 131.21005 -68.59524)
		(end 131.24942 -68.63461)
		(stroke
			(width 0.04445)
			(type default)
		)
		(layer "In5.Cu")
	)
	(gr_line
		(start 131.21005 -68.40474)
		(end 131.24942 -68.36537)
		(stroke
			(width 0.04445)
			(type default)
		)
		(layer "In5.Cu")
	)
	(gr_line
		(start 131.251198 -68.636388)
		(end 131.2672 -68.65239)
		(stroke
			(width 0.04445)
			(type default)
		)
		(layer "In5.Cu")
	)
	(gr_line
		(start 131.251198 -68.363592)
		(end 131.2672 -68.34759)
		(stroke
			(width 0.04445)
			(type default)
		)
		(layer "In5.Cu")
	)
	(gr_line
		(start 131.2672 -68.65239)
		(end 131.289298 -68.65239)
		(stroke
			(width 0.04445)
			(type default)
		)
		(layer "In5.Cu")
	)
	(gr_line
		(start 131.2672 -68.34759)
		(end 131.289298 -68.34759)
		(stroke
			(width 0.04445)
			(type default)
		)
		(layer "In5.Cu")
	)
	(gr_line
		(start 131.269486 -63.59398)
		(end 131.308856 -63.63335)
		(stroke
			(width 0.04445)
			(type default)
		)
		(layer "In5.Cu")
	)
	(gr_line
		(start 131.269486 -63.40348)
		(end 131.308856 -63.36411)
		(stroke
			(width 0.04445)
			(type default)
		)
		(layer "In5.Cu")
	)
	(gr_line
		(start 131.274058 -72.593962)
		(end 131.313428 -72.633332)
		(stroke
			(width 0.04445)
			(type default)
		)
		(layer "In5.Cu")
	)
	(gr_line
		(start 131.274058 -72.403462)
		(end 131.313428 -72.364092)
		(stroke
			(width 0.04445)
			(type default)
		)
		(layer "In5.Cu")
	)
	(gr_line
		(start 131.287774 -70.594728)
		(end 131.327144 -70.634098)
		(stroke
			(width 0.04445)
			(type default)
		)
		(layer "In5.Cu")
	)
	(gr_line
		(start 131.287774 -70.404228)
		(end 131.327144 -70.364858)
		(stroke
			(width 0.04445)
			(type default)
		)
		(layer "In5.Cu")
	)
	(gr_line
		(start 131.289044 -71.597012)
		(end 131.328414 -71.636382)
		(stroke
			(width 0.04445)
			(type default)
		)
		(layer "In5.Cu")
	)
	(gr_line
		(start 131.289044 -71.406512)
		(end 131.328414 -71.367142)
		(stroke
			(width 0.04445)
			(type default)
		)
		(layer "In5.Cu")
	)
	(gr_line
		(start 131.310634 -63.635128)
		(end 131.326636 -63.65113)
		(stroke
			(width 0.04445)
			(type default)
		)
		(layer "In5.Cu")
	)
	(gr_line
		(start 131.310634 -63.362332)
		(end 131.326636 -63.34633)
		(stroke
			(width 0.04445)
			(type default)
		)
		(layer "In5.Cu")
	)
	(gr_line
		(start 131.315206 -72.63511)
		(end 131.331208 -72.651112)
		(stroke
			(width 0.04445)
			(type default)
		)
		(layer "In5.Cu")
	)
	(gr_line
		(start 131.315206 -72.362314)
		(end 131.331208 -72.346312)
		(stroke
			(width 0.04445)
			(type default)
		)
		(layer "In5.Cu")
	)
	(gr_line
		(start 131.326636 -63.65113)
		(end 131.348734 -63.65113)
		(stroke
			(width 0.04445)
			(type default)
		)
		(layer "In5.Cu")
	)
	(gr_line
		(start 131.326636 -63.34633)
		(end 131.348734 -63.34633)
		(stroke
			(width 0.04445)
			(type default)
		)
		(layer "In5.Cu")
	)
	(gr_line
		(start 131.328922 -70.635876)
		(end 131.344924 -70.651878)
		(stroke
			(width 0.04445)
			(type default)
		)
		(layer "In5.Cu")
	)
	(gr_line
		(start 131.328922 -70.36308)
		(end 131.344924 -70.347078)
		(stroke
			(width 0.04445)
			(type default)
		)
		(layer "In5.Cu")
	)
	(gr_line
		(start 131.330192 -71.63816)
		(end 131.346194 -71.654162)
		(stroke
			(width 0.04445)
			(type default)
		)
		(layer "In5.Cu")
	)
	(gr_line
		(start 131.330192 -71.365364)
		(end 131.346194 -71.349362)
		(stroke
			(width 0.04445)
			(type default)
		)
		(layer "In5.Cu")
	)
	(gr_line
		(start 131.331208 -72.651112)
		(end 131.353306 -72.651112)
		(stroke
			(width 0.04445)
			(type default)
		)
		(layer "In5.Cu")
	)
	(gr_line
		(start 131.331208 -72.346312)
		(end 131.445 -72.346312)
		(stroke
			(width 0.04445)
			(type default)
		)
		(layer "In5.Cu")
	)
	(gr_line
		(start 131.339844 -69.597016)
		(end 131.395978 -69.65315)
		(stroke
			(width 0.04445)
			(type default)
		)
		(layer "In5.Cu")
	)
	(gr_line
		(start 131.344924 -70.651878)
		(end 131.458716 -70.651878)
		(stroke
			(width 0.04445)
			(type default)
		)
		(layer "In5.Cu")
	)
	(gr_line
		(start 131.344924 -70.347078)
		(end 131.367022 -70.347078)
		(stroke
			(width 0.04445)
			(type default)
		)
		(layer "In5.Cu")
	)
	(gr_line
		(start 131.346194 -71.654162)
		(end 131.368292 -71.654162)
		(stroke
			(width 0.04445)
			(type default)
		)
		(layer "In5.Cu")
	)
	(gr_line
		(start 131.346194 -71.349362)
		(end 131.459986 -71.349362)
		(stroke
			(width 0.04445)
			(type default)
		)
		(layer "In5.Cu")
	)
	(gr_line
		(start 131.361942 -52.535582)
		(end 131.694174 -52.024026)
		(stroke
			(width 0.0508)
			(type default)
		)
		(layer "In5.Cu")
	)
	(gr_line
		(start 131.366768 -49.591214)
		(end 131.384294 -49.587404)
		(stroke
			(width 0.0508)
			(type default)
		)
		(layer "In5.Cu")
	)
	(gr_line
		(start 131.373372 -69.406516)
		(end 131.395978 -69.38391)
		(stroke
			(width 0.04445)
			(type default)
		)
		(layer "In5.Cu")
	)
	(gr_line
		(start 131.384294 -49.587404)
		(end 131.39928 -49.577752)
		(stroke
			(width 0.0508)
			(type default)
		)
		(layer "In5.Cu")
	)
	(gr_line
		(start 131.393184 -62.59576)
		(end 131.432554 -62.63513)
		(stroke
			(width 0.04445)
			(type default)
		)
		(layer "In5.Cu")
	)
	(gr_line
		(start 131.393184 -62.40526)
		(end 131.432554 -62.36589)
		(stroke
			(width 0.04445)
			(type default)
		)
		(layer "In5.Cu")
	)
	(gr_line
		(start 131.397756 -69.654928)
		(end 131.413758 -69.67093)
		(stroke
			(width 0.04445)
			(type default)
		)
		(layer "In5.Cu")
	)
	(gr_line
		(start 131.397756 -69.382132)
		(end 131.413758 -69.36613)
		(stroke
			(width 0.04445)
			(type default)
		)
		(layer "In5.Cu")
	)
	(gr_line
		(start 131.413758 -69.67093)
		(end 131.435856 -69.67093)
		(stroke
			(width 0.04445)
			(type default)
		)
		(layer "In5.Cu")
	)
	(gr_line
		(start 131.413758 -69.36613)
		(end 131.435856 -69.36613)
		(stroke
			(width 0.04445)
			(type default)
		)
		(layer "In5.Cu")
	)
	(gr_line
		(start 131.434332 -62.636908)
		(end 131.450334 -62.65291)
		(stroke
			(width 0.04445)
			(type default)
		)
		(layer "In5.Cu")
	)
	(gr_line
		(start 131.434332 -62.364112)
		(end 131.450334 -62.34811)
		(stroke
			(width 0.04445)
			(type default)
		)
		(layer "In5.Cu")
	)
	(gr_line
		(start 131.435856 -69.36613)
		(end 131.587494 -69.36613)
		(stroke
			(width 0.0508)
			(type default)
		)
		(layer "In5.Cu")
	)
	(gr_line
		(start 131.450334 -62.65291)
		(end 131.472432 -62.65291)
		(stroke
			(width 0.04445)
			(type default)
		)
		(layer "In5.Cu")
	)
	(gr_line
		(start 131.450334 -62.34811)
		(end 131.472432 -62.34811)
		(stroke
			(width 0.04445)
			(type default)
		)
		(layer "In5.Cu")
	)
	(gr_line
		(start 131.509262 -64.59474)
		(end 131.548632 -64.63411)
		(stroke
			(width 0.04445)
			(type default)
		)
		(layer "In5.Cu")
	)
	(gr_line
		(start 131.509262 -64.40424)
		(end 131.548632 -64.36487)
		(stroke
			(width 0.04445)
			(type default)
		)
		(layer "In5.Cu")
	)
	(gr_line
		(start 131.51485 -65.5955)
		(end 131.55422 -65.63487)
		(stroke
			(width 0.04445)
			(type default)
		)
		(layer "In5.Cu")
	)
	(gr_line
		(start 131.51485 -65.405)
		(end 131.55422 -65.36563)
		(stroke
			(width 0.04445)
			(type default)
		)
		(layer "In5.Cu")
	)
	(gr_line
		(start 131.55041 -64.635888)
		(end 131.566412 -64.65189)
		(stroke
			(width 0.04445)
			(type default)
		)
		(layer "In5.Cu")
	)
	(gr_line
		(start 131.55041 -64.363092)
		(end 131.566412 -64.34709)
		(stroke
			(width 0.04445)
			(type default)
		)
		(layer "In5.Cu")
	)
	(gr_line
		(start 131.555998 -65.636648)
		(end 131.572 -65.65265)
		(stroke
			(width 0.04445)
			(type default)
		)
		(layer "In5.Cu")
	)
	(gr_line
		(start 131.555998 -65.363852)
		(end 131.572 -65.34785)
		(stroke
			(width 0.04445)
			(type default)
		)
		(layer "In5.Cu")
	)
	(gr_line
		(start 131.566412 -64.65189)
		(end 131.58851 -64.65189)
		(stroke
			(width 0.04445)
			(type default)
		)
		(layer "In5.Cu")
	)
	(gr_line
		(start 131.566412 -64.34709)
		(end 131.58851 -64.34709)
		(stroke
			(width 0.04445)
			(type default)
		)
		(layer "In5.Cu")
	)
	(gr_line
		(start 131.572 -65.65265)
		(end 131.594098 -65.65265)
		(stroke
			(width 0.04445)
			(type default)
		)
		(layer "In5.Cu")
	)
	(gr_line
		(start 131.572 -65.34785)
		(end 131.594098 -65.34785)
		(stroke
			(width 0.04445)
			(type default)
		)
		(layer "In5.Cu")
	)
	(gr_line
		(start 131.588764 -67.862704)
		(end 131.588764 -68.128642)
		(stroke
			(width 0.0508)
			(type default)
		)
		(layer "In5.Cu")
	)
	(gr_line
		(start 131.588764 -67.862704)
		(end 131.804156 -67.647058)
		(stroke
			(width 0.0508)
			(type default)
		)
		(layer "In5.Cu")
	)
	(gr_line
		(start 131.804156 -67.647058)
		(end 132.070348 -67.647058)
		(stroke
			(width 0.0508)
			(type default)
		)
		(layer "In5.Cu")
	)
	(gr_line
		(start 132.021834 -68.130166)
		(end 132.071872 -68.080128)
		(stroke
			(width 0.0508)
			(type default)
		)
		(layer "In5.Cu")
	)
	(gr_line
		(start 132.189982 -52.412392)
		(end 132.193792 -52.394866)
		(stroke
			(width 0.0508)
			(type default)
		)
		(layer "In5.Cu")
	)
	(gr_line
		(start 132.193792 -52.394866)
		(end 132.203444 -52.37988)
		(stroke
			(width 0.0508)
			(type default)
		)
		(layer "In5.Cu")
	)
	(gr_line
		(start 132.289042 -67.162172)
		(end 132.289042 -67.428364)
		(stroke
			(width 0.0508)
			(type default)
		)
		(layer "In5.Cu")
	)
	(gr_line
		(start 132.289042 -67.162172)
		(end 132.504688 -66.94678)
		(stroke
			(width 0.0508)
			(type default)
		)
		(layer "In5.Cu")
	)
	(gr_line
		(start 132.504688 -66.94678)
		(end 132.770626 -66.94678)
		(stroke
			(width 0.0508)
			(type default)
		)
		(layer "In5.Cu")
	)
	(gr_arc
		(start 132.620766 -11.547602)
		(mid 132.747567 -11.495079)
		(end 132.80009 -11.368278)
		(stroke
			(width 0.0508)
			(type default)
		)
		(layer "In5.Cu")
	)
	(gr_line
		(start 132.709666 -48.726598)
		(end 132.732272 -48.711866)
		(stroke
			(width 0.0508)
			(type default)
		)
		(layer "In5.Cu")
	)
	(gr_line
		(start 132.722112 -67.429888)
		(end 132.77215 -67.37985)
		(stroke
			(width 0.0508)
			(type default)
		)
		(layer "In5.Cu")
	)
	(gr_line
		(start 132.732272 -48.711866)
		(end 132.747004 -48.68926)
		(stroke
			(width 0.0508)
			(type default)
		)
		(layer "In5.Cu")
	)
	(gr_arc
		(start 132.80009 -12.031726)
		(mid 132.747567 -11.904925)
		(end 132.620766 -11.852402)
		(stroke
			(width 0.0508)
			(type default)
		)
		(layer "In5.Cu")
	)
	(gr_line
		(start 132.80009 -12.031726)
		(end 132.80009 -12.400026)
		(stroke
			(width 0.0508)
			(type default)
		)
		(layer "In5.Cu")
	)
	(gr_line
		(start 132.80009 -10.999978)
		(end 132.80009 -11.368278)
		(stroke
			(width 0.0508)
			(type default)
		)
		(layer "In5.Cu")
	)
	(gr_line
		(start 132.877814 -53.074316)
		(end 132.881624 -53.05679)
		(stroke
			(width 0.0508)
			(type default)
		)
		(layer "In5.Cu")
	)
	(gr_line
		(start 132.881624 -53.05679)
		(end 132.891276 -53.041804)
		(stroke
			(width 0.0508)
			(type default)
		)
		(layer "In5.Cu")
	)
	(gr_line
		(start 132.913374 -27.567382)
		(end 132.918708 -27.592528)
		(stroke
			(width 0.0508)
			(type default)
		)
		(layer "In5.Cu")
	)
	(gr_line
		(start 132.913374 -27.567382)
		(end 132.918708 -27.542236)
		(stroke
			(width 0.0508)
			(type default)
		)
		(layer "In5.Cu")
	)
	(gr_line
		(start 132.998972 -48.301402)
		(end 133.008624 -48.286416)
		(stroke
			(width 0.0508)
			(type default)
		)
		(layer "In5.Cu")
	)
	(gr_line
		(start 133.008624 -48.286416)
		(end 133.012434 -48.26889)
		(stroke
			(width 0.0508)
			(type default)
		)
		(layer "In5.Cu")
	)
	(gr_line
		(start 133.18363 -52.241958)
		(end 133.238748 -52.502054)
		(stroke
			(width 0.0508)
			(type default)
		)
		(layer "In5.Cu")
	)
	(gr_line
		(start 133.18363 -52.241958)
		(end 133.349492 -51.98618)
		(stroke
			(width 0.0508)
			(type default)
		)
		(layer "In5.Cu")
	)
	(gr_line
		(start 133.293358 -54.294024)
		(end 133.297168 -54.276498)
		(stroke
			(width 0.0508)
			(type default)
		)
		(layer "In5.Cu")
	)
	(gr_line
		(start 133.297168 -54.276498)
		(end 133.30682 -54.261512)
		(stroke
			(width 0.0508)
			(type default)
		)
		(layer "In5.Cu")
	)
	(gr_line
		(start 133.349492 -51.98618)
		(end 133.609842 -51.930808)
		(stroke
			(width 0.0508)
			(type default)
		)
		(layer "In5.Cu")
	)
	(gr_line
		(start 133.401054 -46.439328)
		(end 133.406388 -46.414182)
		(stroke
			(width 0.0508)
			(type default)
		)
		(layer "In5.Cu")
	)
	(gr_line
		(start 133.401054 -46.389036)
		(end 133.406388 -46.414182)
		(stroke
			(width 0.0508)
			(type default)
		)
		(layer "In5.Cu")
	)
	(gr_line
		(start 133.515862 -52.639722)
		(end 133.635496 -52.455572)
		(stroke
			(width 0.0508)
			(type default)
		)
		(layer "In5.Cu")
	)
	(gr_line
		(start 133.635496 -52.455572)
		(end 133.63575 -52.455318)
		(stroke
			(width 0.0508)
			(type default)
		)
		(layer "In5.Cu")
	)
	(gr_line
		(start 133.63575 -52.455318)
		(end 133.848602 -52.127658)
		(stroke
			(width 0.0508)
			(type default)
		)
		(layer "In5.Cu")
	)
	(gr_line
		(start 133.72084 -25.235154)
		(end 133.726174 -25.210008)
		(stroke
			(width 0.0508)
			(type default)
		)
		(layer "In5.Cu")
	)
	(gr_line
		(start 133.72084 -25.184862)
		(end 133.726174 -25.210008)
		(stroke
			(width 0.0508)
			(type default)
		)
		(layer "In5.Cu")
	)
	(gr_line
		(start 133.723126 -51.411124)
		(end 133.778498 -51.67122)
		(stroke
			(width 0.0508)
			(type default)
		)
		(layer "In5.Cu")
	)
	(gr_line
		(start 133.723126 -51.411124)
		(end 133.889242 -51.1556)
		(stroke
			(width 0.0508)
			(type default)
		)
		(layer "In5.Cu")
	)
	(gr_line
		(start 133.734556 -55.378604)
		(end 133.762496 -55.335424)
		(stroke
			(width 0.0508)
			(type default)
		)
		(layer "In5.Cu")
	)
	(gr_line
		(start 133.889242 -51.1556)
		(end 134.149338 -51.100228)
		(stroke
			(width 0.0508)
			(type default)
		)
		(layer "In5.Cu")
	)
	(gr_line
		(start 134.05612 -51.808126)
		(end 134.38759 -51.297586)
		(stroke
			(width 0.0508)
			(type default)
		)
		(layer "In5.Cu")
	)
	(gr_line
		(start 134.150862 -48.241458)
		(end 134.160514 -48.226472)
		(stroke
			(width 0.0508)
			(type default)
		)
		(layer "In5.Cu")
	)
	(gr_line
		(start 134.160514 -48.226472)
		(end 134.164324 -48.208946)
		(stroke
			(width 0.0508)
			(type default)
		)
		(layer "In5.Cu")
	)
	(gr_line
		(start 134.16153 -29.113734)
		(end 134.166864 -29.13888)
		(stroke
			(width 0.0508)
			(type default)
		)
		(layer "In5.Cu")
	)
	(gr_line
		(start 134.16153 -29.113734)
		(end 134.166864 -29.088588)
		(stroke
			(width 0.0508)
			(type default)
		)
		(layer "In5.Cu")
	)
	(gr_arc
		(start 134.420864 -10.347706)
		(mid 134.547682 -10.295195)
		(end 134.600188 -10.168382)
		(stroke
			(width 0.0508)
			(type default)
		)
		(layer "In5.Cu")
	)
	(gr_line
		(start 134.450328 -52.150518)
		(end 134.505446 -52.410614)
		(stroke
			(width 0.0508)
			(type default)
		)
		(layer "In5.Cu")
	)
	(gr_line
		(start 134.450328 -52.150518)
		(end 134.61619 -51.89474)
		(stroke
			(width 0.0508)
			(type default)
		)
		(layer "In5.Cu")
	)
	(gr_arc
		(start 134.600188 -10.83183)
		(mid 134.547674 -10.705022)
		(end 134.420864 -10.652506)
		(stroke
			(width 0.0508)
			(type default)
		)
		(layer "In5.Cu")
	)
	(gr_line
		(start 134.600188 -10.83183)
		(end 134.600188 -11.20013)
		(stroke
			(width 0.0508)
			(type default)
		)
		(layer "In5.Cu")
	)
	(gr_line
		(start 134.600188 -9.800082)
		(end 134.600188 -10.168382)
		(stroke
			(width 0.0508)
			(type default)
		)
		(layer "In5.Cu")
	)
	(gr_line
		(start 134.61619 -51.89474)
		(end 134.876286 -51.839622)
		(stroke
			(width 0.0508)
			(type default)
		)
		(layer "In5.Cu")
	)
	(gr_line
		(start 134.782814 -52.548028)
		(end 135.113776 -52.03825)
		(stroke
			(width 0.0508)
			(type default)
		)
		(layer "In5.Cu")
	)
	(gr_line
		(start 134.802626 -45.20438)
		(end 134.80796 -45.179234)
		(stroke
			(width 0.0508)
			(type default)
		)
		(layer "In5.Cu")
	)
	(gr_line
		(start 134.802626 -45.154088)
		(end 134.80796 -45.179234)
		(stroke
			(width 0.0508)
			(type default)
		)
		(layer "In5.Cu")
	)
	(gr_line
		(start 134.98957 -51.319684)
		(end 135.044688 -51.580288)
		(stroke
			(width 0.0508)
			(type default)
		)
		(layer "In5.Cu")
	)
	(gr_line
		(start 134.98957 -51.319684)
		(end 135.155432 -51.06416)
		(stroke
			(width 0.0508)
			(type default)
		)
		(layer "In5.Cu")
	)
	(gr_line
		(start 135.155432 -51.06416)
		(end 135.416036 -51.008788)
		(stroke
			(width 0.0508)
			(type default)
		)
		(layer "In5.Cu")
	)
	(gr_line
		(start 135.172958 -52.813458)
		(end 135.228076 -53.073808)
		(stroke
			(width 0.0508)
			(type default)
		)
		(layer "In5.Cu")
	)
	(gr_line
		(start 135.172958 -52.813458)
		(end 135.33882 -52.55768)
		(stroke
			(width 0.0508)
			(type default)
		)
		(layer "In5.Cu")
	)
	(gr_line
		(start 135.19912 -48.327056)
		(end 135.208772 -48.31207)
		(stroke
			(width 0.0508)
			(type default)
		)
		(layer "In5.Cu")
	)
	(gr_line
		(start 135.208772 -48.31207)
		(end 135.212582 -48.294544)
		(stroke
			(width 0.0508)
			(type default)
		)
		(layer "In5.Cu")
	)
	(gr_line
		(start 135.322056 -51.717448)
		(end 135.654034 -51.206146)
		(stroke
			(width 0.0508)
			(type default)
		)
		(layer "In5.Cu")
	)
	(gr_line
		(start 135.33882 -52.55768)
		(end 135.59917 -52.502562)
		(stroke
			(width 0.0508)
			(type default)
		)
		(layer "In5.Cu")
	)
	(gr_line
		(start 135.43915 -24.569674)
		(end 135.444484 -24.544528)
		(stroke
			(width 0.0508)
			(type default)
		)
		(layer "In5.Cu")
	)
	(gr_line
		(start 135.43915 -24.519382)
		(end 135.444484 -24.544528)
		(stroke
			(width 0.0508)
			(type default)
		)
		(layer "In5.Cu")
	)
	(gr_line
		(start 135.454898 -29.738066)
		(end 135.460232 -29.763212)
		(stroke
			(width 0.0508)
			(type default)
		)
		(layer "In5.Cu")
	)
	(gr_line
		(start 135.454898 -29.738066)
		(end 135.460232 -29.71292)
		(stroke
			(width 0.0508)
			(type default)
		)
		(layer "In5.Cu")
	)
	(gr_line
		(start 135.50519 -53.211476)
		(end 135.836914 -52.700428)
		(stroke
			(width 0.0508)
			(type default)
		)
		(layer "In5.Cu")
	)
	(gr_line
		(start 135.712454 -51.982624)
		(end 135.767826 -52.242974)
		(stroke
			(width 0.0508)
			(type default)
		)
		(layer "In5.Cu")
	)
	(gr_line
		(start 135.712454 -51.982624)
		(end 135.878316 -51.726846)
		(stroke
			(width 0.0508)
			(type default)
		)
		(layer "In5.Cu")
	)
	(gr_line
		(start 135.814562 -56.867806)
		(end 135.818626 -56.838342)
		(stroke
			(width 0.0508)
			(type default)
		)
		(layer "In5.Cu")
	)
	(gr_line
		(start 135.818626 -56.838342)
		(end 135.834882 -56.813196)
		(stroke
			(width 0.0508)
			(type default)
		)
		(layer "In5.Cu")
	)
	(gr_line
		(start 135.878316 -51.726846)
		(end 136.138666 -51.671474)
		(stroke
			(width 0.0508)
			(type default)
		)
		(layer "In5.Cu")
	)
	(gr_line
		(start 135.947912 -44.83354)
		(end 135.953246 -44.808394)
		(stroke
			(width 0.0508)
			(type default)
		)
		(layer "In5.Cu")
	)
	(gr_line
		(start 135.947912 -44.783248)
		(end 135.953246 -44.808394)
		(stroke
			(width 0.0508)
			(type default)
		)
		(layer "In5.Cu")
	)
	(gr_line
		(start 135.965692 -99.20224)
		(end 135.983218 -99.19843)
		(stroke
			(width 0.0508)
			(type default)
		)
		(layer "In5.Cu")
	)
	(gr_line
		(start 135.983218 -99.19843)
		(end 135.998204 -99.188778)
		(stroke
			(width 0.0508)
			(type default)
		)
		(layer "In5.Cu")
	)
	(gr_line
		(start 136.044178 -52.381658)
		(end 136.377934 -51.867562)
		(stroke
			(width 0.0508)
			(type default)
		)
		(layer "In5.Cu")
	)
	(gr_line
		(start 136.108948 -56.041798)
		(end 136.164066 -56.302148)
		(stroke
			(width 0.0508)
			(type default)
		)
		(layer "In5.Cu")
	)
	(gr_line
		(start 136.108948 -56.041798)
		(end 136.275064 -55.786274)
		(stroke
			(width 0.0508)
			(type default)
		)
		(layer "In5.Cu")
	)
	(gr_line
		(start 136.197848 -48.509936)
		(end 136.2075 -48.49495)
		(stroke
			(width 0.0508)
			(type default)
		)
		(layer "In5.Cu")
	)
	(gr_line
		(start 136.2075 -48.49495)
		(end 136.21131 -48.477424)
		(stroke
			(width 0.0508)
			(type default)
		)
		(layer "In5.Cu")
	)
	(gr_arc
		(start 136.220708 -11.547602)
		(mid 136.347509 -11.495079)
		(end 136.400032 -11.368278)
		(stroke
			(width 0.0508)
			(type default)
		)
		(layer "In5.Cu")
	)
	(gr_line
		(start 136.238488 -101.619812)
		(end 136.256014 -101.616002)
		(stroke
			(width 0.0508)
			(type default)
		)
		(layer "In5.Cu")
	)
	(gr_line
		(start 136.256014 -101.616002)
		(end 136.271 -101.60635)
		(stroke
			(width 0.0508)
			(type default)
		)
		(layer "In5.Cu")
	)
	(gr_line
		(start 136.275064 -55.786274)
		(end 136.53516 -55.730902)
		(stroke
			(width 0.0508)
			(type default)
		)
		(layer "In5.Cu")
	)
	(gr_line
		(start 136.310116 -102.790498)
		(end 136.327642 -102.786688)
		(stroke
			(width 0.0508)
			(type default)
		)
		(layer "In5.Cu")
	)
	(gr_line
		(start 136.327642 -102.786688)
		(end 136.342628 -102.777036)
		(stroke
			(width 0.0508)
			(type default)
		)
		(layer "In5.Cu")
	)
	(gr_arc
		(start 136.400032 -12.031726)
		(mid 136.347519 -11.904905)
		(end 136.220708 -11.852402)
		(stroke
			(width 0.0508)
			(type default)
		)
		(layer "In5.Cu")
	)
	(gr_line
		(start 136.400032 -12.031726)
		(end 136.400032 -12.400026)
		(stroke
			(width 0.0508)
			(type default)
		)
		(layer "In5.Cu")
	)
	(gr_line
		(start 136.400032 -10.999978)
		(end 136.400032 -11.368278)
		(stroke
			(width 0.0508)
			(type default)
		)
		(layer "In5.Cu")
	)
	(gr_line
		(start 136.441942 -56.438546)
		(end 136.772904 -55.928768)
		(stroke
			(width 0.0508)
			(type default)
		)
		(layer "In5.Cu")
	)
	(gr_line
		(start 136.503918 -100.308918)
		(end 136.521444 -100.305108)
		(stroke
			(width 0.0508)
			(type default)
		)
		(layer "In5.Cu")
	)
	(gr_line
		(start 136.50849 -57.915556)
		(end 136.5123 -57.89803)
		(stroke
			(width 0.0508)
			(type default)
		)
		(layer "In5.Cu")
	)
	(gr_line
		(start 136.5123 -57.89803)
		(end 136.521952 -57.883044)
		(stroke
			(width 0.0508)
			(type default)
		)
		(layer "In5.Cu")
	)
	(gr_line
		(start 136.521444 -100.305108)
		(end 136.53643 -100.295456)
		(stroke
			(width 0.0508)
			(type default)
		)
		(layer "In5.Cu")
	)
	(gr_line
		(start 136.648698 -55.211218)
		(end 136.703816 -55.471314)
		(stroke
			(width 0.0508)
			(type default)
		)
		(layer "In5.Cu")
	)
	(gr_line
		(start 136.648698 -55.211218)
		(end 136.81456 -54.95544)
		(stroke
			(width 0.0508)
			(type default)
		)
		(layer "In5.Cu")
	)
	(gr_line
		(start 136.666224 -29.766768)
		(end 136.671558 -29.791914)
		(stroke
			(width 0.0508)
			(type default)
		)
		(layer "In5.Cu")
	)
	(gr_line
		(start 136.666224 -29.766768)
		(end 136.671558 -29.741622)
		(stroke
			(width 0.0508)
			(type default)
		)
		(layer "In5.Cu")
	)
	(gr_line
		(start 136.81456 -54.95544)
		(end 137.074656 -54.900322)
		(stroke
			(width 0.0508)
			(type default)
		)
		(layer "In5.Cu")
	)
	(gr_line
		(start 136.934956 -45.072554)
		(end 136.94029 -45.047408)
		(stroke
			(width 0.0508)
			(type default)
		)
		(layer "In5.Cu")
	)
	(gr_line
		(start 136.934956 -45.022262)
		(end 136.94029 -45.047408)
		(stroke
			(width 0.0508)
			(type default)
		)
		(layer "In5.Cu")
	)
	(gr_line
		(start 136.981692 -55.607712)
		(end 137.312146 -55.09895)
		(stroke
			(width 0.0508)
			(type default)
		)
		(layer "In5.Cu")
	)
	(gr_line
		(start 137.077196 -59.094878)
		(end 137.081006 -59.077352)
		(stroke
			(width 0.0508)
			(type default)
		)
		(layer "In5.Cu")
	)
	(gr_line
		(start 137.081006 -59.077352)
		(end 137.090658 -59.062366)
		(stroke
			(width 0.0508)
			(type default)
		)
		(layer "In5.Cu")
	)
	(gr_line
		(start 137.086594 -49.00041)
		(end 137.097262 -48.9839)
		(stroke
			(width 0.0508)
			(type default)
		)
		(layer "In5.Cu")
	)
	(gr_line
		(start 137.097262 -48.9839)
		(end 137.101072 -48.96612)
		(stroke
			(width 0.0508)
			(type default)
		)
		(layer "In5.Cu")
	)
	(gr_line
		(start 137.15238 -23.216616)
		(end 137.157714 -23.19147)
		(stroke
			(width 0.0508)
			(type default)
		)
		(layer "In5.Cu")
	)
	(gr_line
		(start 137.15238 -23.166324)
		(end 137.157714 -23.19147)
		(stroke
			(width 0.0508)
			(type default)
		)
		(layer "In5.Cu")
	)
	(gr_line
		(start 137.367772 -58.285634)
		(end 137.423398 -58.545222)
		(stroke
			(width 0.0508)
			(type default)
		)
		(layer "In5.Cu")
	)
	(gr_line
		(start 137.367772 -58.285634)
		(end 137.533634 -58.029856)
		(stroke
			(width 0.0508)
			(type default)
		)
		(layer "In5.Cu")
	)
	(gr_line
		(start 137.533634 -58.029856)
		(end 137.794238 -57.97423)
		(stroke
			(width 0.0508)
			(type default)
		)
		(layer "In5.Cu")
	)
	(gr_line
		(start 137.69975 -58.684668)
		(end 138.032744 -58.170826)
		(stroke
			(width 0.0508)
			(type default)
		)
		(layer "In5.Cu")
	)
	(gr_line
		(start 137.746486 -30.796992)
		(end 137.75182 -30.822138)
		(stroke
			(width 0.0508)
			(type default)
		)
		(layer "In5.Cu")
	)
	(gr_line
		(start 137.746486 -30.796992)
		(end 137.75182 -30.771846)
		(stroke
			(width 0.0508)
			(type default)
		)
		(layer "In5.Cu")
	)
	(gr_line
		(start 137.891012 -45.249338)
		(end 137.896346 -45.224192)
		(stroke
			(width 0.0508)
			(type default)
		)
		(layer "In5.Cu")
	)
	(gr_line
		(start 137.891012 -45.199046)
		(end 137.896346 -45.224192)
		(stroke
			(width 0.0508)
			(type default)
		)
		(layer "In5.Cu")
	)
	(gr_line
		(start 137.907014 -57.454546)
		(end 137.962386 -57.71515)
		(stroke
			(width 0.0508)
			(type default)
		)
		(layer "In5.Cu")
	)
	(gr_line
		(start 137.907014 -57.454546)
		(end 138.072876 -57.199022)
		(stroke
			(width 0.0508)
			(type default)
		)
		(layer "In5.Cu")
	)
	(gr_line
		(start 138.014456 -49.34712)
		(end 138.026648 -49.328578)
		(stroke
			(width 0.0508)
			(type default)
		)
		(layer "In5.Cu")
	)
	(gr_arc
		(start 138.020806 -10.347706)
		(mid 138.147607 -10.295183)
		(end 138.20013 -10.168382)
		(stroke
			(width 0.0508)
			(type default)
		)
		(layer "In5.Cu")
	)
	(gr_line
		(start 138.026648 -49.328578)
		(end 138.030966 -49.308258)
		(stroke
			(width 0.0508)
			(type default)
		)
		(layer "In5.Cu")
	)
	(gr_line
		(start 138.060684 -53.946806)
		(end 138.070336 -53.93182)
		(stroke
			(width 0.0508)
			(type default)
		)
		(layer "In5.Cu")
	)
	(gr_line
		(start 138.070336 -53.93182)
		(end 138.074146 -53.914294)
		(stroke
			(width 0.0508)
			(type default)
		)
		(layer "In5.Cu")
	)
	(gr_line
		(start 138.072876 -57.199022)
		(end 138.333226 -57.14365)
		(stroke
			(width 0.0508)
			(type default)
		)
		(layer "In5.Cu")
	)
	(gr_arc
		(start 138.20013 -10.83183)
		(mid 138.147618 -10.705007)
		(end 138.020806 -10.652506)
		(stroke
			(width 0.0508)
			(type default)
		)
		(layer "In5.Cu")
	)
	(gr_line
		(start 138.20013 -10.83183)
		(end 138.20013 -11.20013)
		(stroke
			(width 0.0508)
			(type default)
		)
		(layer "In5.Cu")
	)
	(gr_line
		(start 138.20013 -9.800082)
		(end 138.20013 -10.168382)
		(stroke
			(width 0.0508)
			(type default)
		)
		(layer "In5.Cu")
	)
	(gr_line
		(start 138.240008 -57.851802)
		(end 138.571986 -57.339992)
		(stroke
			(width 0.0508)
			(type default)
		)
		(layer "In5.Cu")
	)
	(gr_line
		(start 138.479022 -76.52512)
		(end 138.735562 -76.52512)
		(stroke
			(width 0.0508)
			(type default)
		)
		(layer "In5.Cu")
	)
	(gr_line
		(start 138.486134 -78.427834)
		(end 138.742674 -78.427834)
		(stroke
			(width 0.0508)
			(type default)
		)
		(layer "In5.Cu")
	)
	(gr_line
		(start 138.500612 -80.197452)
		(end 138.757152 -80.197452)
		(stroke
			(width 0.0508)
			(type default)
		)
		(layer "In5.Cu")
	)
	(gr_line
		(start 138.751056 -67.4878)
		(end 138.794236 -67.45986)
		(stroke
			(width 0.0508)
			(type default)
		)
		(layer "In5.Cu")
	)
	(gr_line
		(start 138.754612 -97.398078)
		(end 138.777218 -97.383346)
		(stroke
			(width 0.0508)
			(type default)
		)
		(layer "In5.Cu")
	)
	(gr_line
		(start 138.76274 -21.368004)
		(end 138.768074 -21.342858)
		(stroke
			(width 0.0508)
			(type default)
		)
		(layer "In5.Cu")
	)
	(gr_line
		(start 138.76274 -21.317712)
		(end 138.768074 -21.342858)
		(stroke
			(width 0.0508)
			(type default)
		)
		(layer "In5.Cu")
	)
	(gr_line
		(start 138.777218 -97.383346)
		(end 138.79195 -97.36074)
		(stroke
			(width 0.0508)
			(type default)
		)
		(layer "In5.Cu")
	)
	(gr_line
		(start 138.79195 -68.9864)
		(end 138.83513 -68.95846)
		(stroke
			(width 0.0508)
			(type default)
		)
		(layer "In5.Cu")
	)
	(gr_line
		(start 138.843258 -82.308446)
		(end 139.099798 -82.308446)
		(stroke
			(width 0.0508)
			(type default)
		)
		(layer "In5.Cu")
	)
	(gr_arc
		(start 138.850624 -76.572618)
		(mid 138.797823 -76.537405)
		(end 138.735562 -76.52512)
		(stroke
			(width 0.0508)
			(type default)
		)
		(layer "In5.Cu")
	)
	(gr_line
		(start 138.850624 -76.572618)
		(end 138.850878 -76.572872)
		(stroke
			(width 0.0508)
			(type default)
		)
		(layer "In5.Cu")
	)
	(gr_arc
		(start 138.857736 -78.475332)
		(mid 138.80493 -78.440141)
		(end 138.742674 -78.427834)
		(stroke
			(width 0.0508)
			(type default)
		)
		(layer "In5.Cu")
	)
	(gr_line
		(start 138.857736 -78.475332)
		(end 138.85799 -78.475586)
		(stroke
			(width 0.0508)
			(type default)
		)
		(layer "In5.Cu")
	)
	(gr_arc
		(start 138.872214 -80.24495)
		(mid 138.819415 -80.209734)
		(end 138.757152 -80.197452)
		(stroke
			(width 0.0508)
			(type default)
		)
		(layer "In5.Cu")
	)
	(gr_line
		(start 138.872214 -80.24495)
		(end 138.872468 -80.245204)
		(stroke
			(width 0.0508)
			(type default)
		)
		(layer "In5.Cu")
	)
	(gr_arc
		(start 138.898122 -76.687426)
		(mid 138.88583 -76.625478)
		(end 138.850878 -76.572872)
		(stroke
			(width 0.0508)
			(type default)
		)
		(layer "In5.Cu")
	)
	(gr_arc
		(start 138.905234 -78.59014)
		(mid 138.892963 -78.52818)
		(end 138.85799 -78.475586)
		(stroke
			(width 0.0508)
			(type default)
		)
		(layer "In5.Cu")
	)
	(gr_arc
		(start 138.919712 -80.359758)
		(mid 138.90743 -80.297804)
		(end 138.872468 -80.245204)
		(stroke
			(width 0.0508)
			(type default)
		)
		(layer "In5.Cu")
	)
	(gr_line
		(start 138.973052 -44.875958)
		(end 138.978386 -44.850812)
		(stroke
			(width 0.0508)
			(type default)
		)
		(layer "In5.Cu")
	)
	(gr_line
		(start 138.973052 -44.825666)
		(end 138.978386 -44.850812)
		(stroke
			(width 0.0508)
			(type default)
		)
		(layer "In5.Cu")
	)
	(gr_line
		(start 138.979402 -68.498212)
		(end 139.034774 -68.238116)
		(stroke
			(width 0.0508)
			(type default)
		)
		(layer "In5.Cu")
	)
	(gr_line
		(start 139.001754 -70.5104)
		(end 139.044426 -70.482714)
		(stroke
			(width 0.0508)
			(type default)
		)
		(layer "In5.Cu")
	)
	(gr_line
		(start 139.034774 -68.238116)
		(end 139.290298 -68.072254)
		(stroke
			(width 0.0508)
			(type default)
		)
		(layer "In5.Cu")
	)
	(gr_line
		(start 139.041124 -54.564788)
		(end 139.050776 -54.549802)
		(stroke
			(width 0.0508)
			(type default)
		)
		(layer "In5.Cu")
	)
	(gr_line
		(start 139.050776 -54.549802)
		(end 139.054586 -54.532276)
		(stroke
			(width 0.0508)
			(type default)
		)
		(layer "In5.Cu")
	)
	(gr_line
		(start 139.092178 -30.779974)
		(end 139.097512 -30.80512)
		(stroke
			(width 0.0508)
			(type default)
		)
		(layer "In5.Cu")
	)
	(gr_line
		(start 139.092178 -30.779974)
		(end 139.097512 -30.754828)
		(stroke
			(width 0.0508)
			(type default)
		)
		(layer "In5.Cu")
	)
	(gr_line
		(start 139.177268 -68.73621)
		(end 139.687808 -68.404994)
		(stroke
			(width 0.0508)
			(type default)
		)
		(layer "In5.Cu")
	)
	(gr_line
		(start 139.204954 -72.136)
		(end 139.248134 -72.10806)
		(stroke
			(width 0.0508)
			(type default)
		)
		(layer "In5.Cu")
	)
	(gr_arc
		(start 139.21486 -82.355944)
		(mid 139.162057 -82.320747)
		(end 139.099798 -82.308446)
		(stroke
			(width 0.0508)
			(type default)
		)
		(layer "In5.Cu")
	)
	(gr_line
		(start 139.21486 -82.355944)
		(end 139.215114 -82.356198)
		(stroke
			(width 0.0508)
			(type default)
		)
		(layer "In5.Cu")
	)
	(gr_arc
		(start 139.254992 -76.57719)
		(mid 139.216521 -76.634627)
		(end 139.202922 -76.702412)
		(stroke
			(width 0.0508)
			(type default)
		)
		(layer "In5.Cu")
	)
	(gr_line
		(start 139.254992 -76.57719)
		(end 139.27709 -76.555092)
		(stroke
			(width 0.0508)
			(type default)
		)
		(layer "In5.Cu")
	)
	(gr_arc
		(start 139.262104 -78.479904)
		(mid 139.223633 -78.537341)
		(end 139.210034 -78.605126)
		(stroke
			(width 0.0508)
			(type default)
		)
		(layer "In5.Cu")
	)
	(gr_line
		(start 139.262104 -78.479904)
		(end 139.284202 -78.457806)
		(stroke
			(width 0.0508)
			(type default)
		)
		(layer "In5.Cu")
	)
	(gr_arc
		(start 139.262358 -82.470752)
		(mid 139.250077 -82.408797)
		(end 139.215114 -82.356198)
		(stroke
			(width 0.0508)
			(type default)
		)
		(layer "In5.Cu")
	)
	(gr_arc
		(start 139.276582 -80.249522)
		(mid 139.238088 -80.306953)
		(end 139.224512 -80.374744)
		(stroke
			(width 0.0508)
			(type default)
		)
		(layer "In5.Cu")
	)
	(gr_line
		(start 139.276582 -80.249522)
		(end 139.29868 -80.227424)
		(stroke
			(width 0.0508)
			(type default)
		)
		(layer "In5.Cu")
	)
	(gr_line
		(start 139.290298 -68.072254)
		(end 139.550394 -68.127626)
		(stroke
			(width 0.0508)
			(type default)
		)
		(layer "In5.Cu")
	)
	(gr_arc
		(start 139.348972 -76.52512)
		(mid 139.310062 -76.532971)
		(end 139.27709 -76.555092)
		(stroke
			(width 0.0508)
			(type default)
		)
		(layer "In5.Cu")
	)
	(gr_line
		(start 139.348972 -76.52512)
		(end 139.622022 -76.52512)
		(stroke
			(width 0.0508)
			(type default)
		)
		(layer "In5.Cu")
	)
	(gr_arc
		(start 139.356084 -78.427834)
		(mid 139.317174 -78.435685)
		(end 139.284202 -78.457806)
		(stroke
			(width 0.0508)
			(type default)
		)
		(layer "In5.Cu")
	)
	(gr_line
		(start 139.356084 -78.427834)
		(end 139.629134 -78.427834)
		(stroke
			(width 0.0508)
			(type default)
		)
		(layer "In5.Cu")
	)
	(gr_arc
		(start 139.370562 -80.197452)
		(mid 139.331626 -80.205254)
		(end 139.29868 -80.227424)
		(stroke
			(width 0.0508)
			(type default)
		)
		(layer "In5.Cu")
	)
	(gr_line
		(start 139.370562 -80.197452)
		(end 139.643612 -80.197452)
		(stroke
			(width 0.0508)
			(type default)
		)
		(layer "In5.Cu")
	)
	(gr_arc
		(start 139.619228 -82.360516)
		(mid 139.580757 -82.417953)
		(end 139.567158 -82.485738)
		(stroke
			(width 0.0508)
			(type default)
		)
		(layer "In5.Cu")
	)
	(gr_line
		(start 139.619228 -82.360516)
		(end 139.641326 -82.338418)
		(stroke
			(width 0.0508)
			(type default)
		)
		(layer "In5.Cu")
	)
	(gr_arc
		(start 139.713208 -82.308446)
		(mid 139.674298 -82.316297)
		(end 139.641326 -82.338418)
		(stroke
			(width 0.0508)
			(type default)
		)
		(layer "In5.Cu")
	)
	(gr_line
		(start 139.713208 -82.308446)
		(end 139.986258 -82.308446)
		(stroke
			(width 0.0508)
			(type default)
		)
		(layer "In5.Cu")
	)
	(gr_line
		(start 139.71905 -98.228658)
		(end 139.741656 -98.213926)
		(stroke
			(width 0.0508)
			(type default)
		)
		(layer "In5.Cu")
	)
	(gr_line
		(start 139.741656 -98.213926)
		(end 139.756134 -98.191574)
		(stroke
			(width 0.0508)
			(type default)
		)
		(layer "In5.Cu")
	)
	(gr_line
		(start 139.809982 -67.959224)
		(end 139.865354 -67.698874)
		(stroke
			(width 0.0508)
			(type default)
		)
		(layer "In5.Cu")
	)
	(gr_arc
		(start 139.82065 -11.547602)
		(mid 139.947411 -11.49506)
		(end 139.999974 -11.368278)
		(stroke
			(width 0.0508)
			(type default)
		)
		(layer "In5.Cu")
	)
	(gr_line
		(start 139.82192 -66.426334)
		(end 139.877038 -66.166238)
		(stroke
			(width 0.0508)
			(type default)
		)
		(layer "In5.Cu")
	)
	(gr_line
		(start 139.865354 -67.698874)
		(end 140.121132 -67.533012)
		(stroke
			(width 0.0508)
			(type default)
		)
		(layer "In5.Cu")
	)
	(gr_line
		(start 139.866116 -55.345838)
		(end 139.875768 -55.330852)
		(stroke
			(width 0.0508)
			(type default)
		)
		(layer "In5.Cu")
	)
	(gr_line
		(start 139.875768 -55.330852)
		(end 139.879578 -55.313326)
		(stroke
			(width 0.0508)
			(type default)
		)
		(layer "In5.Cu")
	)
	(gr_line
		(start 139.877038 -66.166238)
		(end 140.132816 -66.000376)
		(stroke
			(width 0.0508)
			(type default)
		)
		(layer "In5.Cu")
	)
	(gr_arc
		(start 139.999974 -12.031726)
		(mid 139.947463 -11.90489)
		(end 139.82065 -11.852402)
		(stroke
			(width 0.0508)
			(type default)
		)
		(layer "In5.Cu")
	)
	(gr_line
		(start 139.999974 -12.031726)
		(end 139.999974 -12.400026)
		(stroke
			(width 0.0508)
			(type default)
		)
		(layer "In5.Cu")
	)
	(gr_line
		(start 139.999974 -10.999978)
		(end 139.999974 -11.368278)
		(stroke
			(width 0.0508)
			(type default)
		)
		(layer "In5.Cu")
	)
	(gr_line
		(start 140.007848 -68.196968)
		(end 140.444728 -67.913504)
		(stroke
			(width 0.0508)
			(type default)
		)
		(layer "In5.Cu")
	)
	(gr_line
		(start 140.019024 -66.66484)
		(end 140.531596 -66.3321)
		(stroke
			(width 0.0508)
			(type default)
		)
		(layer "In5.Cu")
	)
	(gr_line
		(start 140.08608 -44.445682)
		(end 140.091414 -44.420536)
		(stroke
			(width 0.0508)
			(type default)
		)
		(layer "In5.Cu")
	)
	(gr_line
		(start 140.08608 -44.39539)
		(end 140.091414 -44.420536)
		(stroke
			(width 0.0508)
			(type default)
		)
		(layer "In5.Cu")
	)
	(gr_line
		(start 140.121132 -67.533012)
		(end 140.380974 -67.58813)
		(stroke
			(width 0.0508)
			(type default)
		)
		(layer "In5.Cu")
	)
	(gr_line
		(start 140.132816 -66.000376)
		(end 140.393166 -66.055494)
		(stroke
			(width 0.0508)
			(type default)
		)
		(layer "In5.Cu")
	)
	(gr_line
		(start 140.142468 -20.987512)
		(end 140.147802 -20.962366)
		(stroke
			(width 0.0508)
			(type default)
		)
		(layer "In5.Cu")
	)
	(gr_line
		(start 140.142468 -20.93722)
		(end 140.147802 -20.962366)
		(stroke
			(width 0.0508)
			(type default)
		)
		(layer "In5.Cu")
	)
	(gr_line
		(start 140.184124 -31.661354)
		(end 140.189458 -31.6865)
		(stroke
			(width 0.0508)
			(type default)
		)
		(layer "In5.Cu")
	)
	(gr_line
		(start 140.184124 -31.661354)
		(end 140.189458 -31.636208)
		(stroke
			(width 0.0508)
			(type default)
		)
		(layer "In5.Cu")
	)
	(gr_line
		(start 140.444728 -67.91325)
		(end 140.444728 -67.913504)
		(stroke
			(width 0.0508)
			(type default)
		)
		(layer "In5.Cu")
	)
	(gr_line
		(start 140.444728 -67.91325)
		(end 140.51661 -67.86626)
		(stroke
			(width 0.0508)
			(type default)
		)
		(layer "In5.Cu")
	)
	(gr_line
		(start 140.501624 -98.858832)
		(end 140.523214 -98.845116)
		(stroke
			(width 0.0508)
			(type default)
		)
		(layer "In5.Cu")
	)
	(gr_line
		(start 140.523214 -98.845116)
		(end 140.53693 -98.823526)
		(stroke
			(width 0.0508)
			(type default)
		)
		(layer "In5.Cu")
	)
	(gr_line
		(start 140.524738 -69.154802)
		(end 140.58011 -68.894452)
		(stroke
			(width 0.0508)
			(type default)
		)
		(layer "In5.Cu")
	)
	(gr_line
		(start 140.58011 -68.894452)
		(end 140.835634 -68.728336)
		(stroke
			(width 0.0508)
			(type default)
		)
		(layer "In5.Cu")
	)
	(gr_line
		(start 140.652754 -65.887092)
		(end 140.708126 -65.626742)
		(stroke
			(width 0.0508)
			(type default)
		)
		(layer "In5.Cu")
	)
	(gr_line
		(start 140.708126 -65.626742)
		(end 140.96365 -65.46088)
		(stroke
			(width 0.0508)
			(type default)
		)
		(layer "In5.Cu")
	)
	(gr_line
		(start 140.72108 -69.393816)
		(end 141.232382 -69.061584)
		(stroke
			(width 0.0508)
			(type default)
		)
		(layer "In5.Cu")
	)
	(gr_line
		(start 140.828268 -70.715886)
		(end 140.883386 -70.45579)
		(stroke
			(width 0.0508)
			(type default)
		)
		(layer "In5.Cu")
	)
	(gr_line
		(start 140.835634 -68.728336)
		(end 141.09573 -68.783708)
		(stroke
			(width 0.0508)
			(type default)
		)
		(layer "In5.Cu")
	)
	(gr_line
		(start 140.849604 -66.125852)
		(end 141.361414 -65.79362)
		(stroke
			(width 0.0508)
			(type default)
		)
		(layer "In5.Cu")
	)
	(gr_line
		(start 140.883386 -70.45579)
		(end 141.139164 -70.289928)
		(stroke
			(width 0.0508)
			(type default)
		)
		(layer "In5.Cu")
	)
	(gr_line
		(start 140.96365 -65.46088)
		(end 141.224 -65.516252)
		(stroke
			(width 0.0508)
			(type default)
		)
		(layer "In5.Cu")
	)
	(gr_line
		(start 140.979652 -80.874362)
		(end 140.98651 -80.876394)
		(stroke
			(width 0.0508)
			(type default)
		)
		(layer "In5.Cu")
	)
	(gr_line
		(start 141.025626 -70.954138)
		(end 141.536674 -70.622414)
		(stroke
			(width 0.0508)
			(type default)
		)
		(layer "In5.Cu")
	)
	(gr_line
		(start 141.073632 -45.033184)
		(end 141.078966 -45.008038)
		(stroke
			(width 0.0508)
			(type default)
		)
		(layer "In5.Cu")
	)
	(gr_line
		(start 141.073632 -44.982892)
		(end 141.078966 -45.008038)
		(stroke
			(width 0.0508)
			(type default)
		)
		(layer "In5.Cu")
	)
	(gr_line
		(start 141.139164 -70.289928)
		(end 141.39926 -70.345046)
		(stroke
			(width 0.0508)
			(type default)
		)
		(layer "In5.Cu")
	)
	(gr_line
		(start 141.355572 -68.615052)
		(end 141.410944 -68.354702)
		(stroke
			(width 0.0508)
			(type default)
		)
		(layer "In5.Cu")
	)
	(gr_line
		(start 141.39164 -99.49815)
		(end 141.412976 -99.48418)
		(stroke
			(width 0.0508)
			(type default)
		)
		(layer "In5.Cu")
	)
	(gr_line
		(start 141.410944 -68.354702)
		(end 141.666468 -68.188586)
		(stroke
			(width 0.0508)
			(type default)
		)
		(layer "In5.Cu")
	)
	(gr_line
		(start 141.412976 -99.48418)
		(end 141.426438 -99.463098)
		(stroke
			(width 0.0508)
			(type default)
		)
		(layer "In5.Cu")
	)
	(gr_line
		(start 141.477238 -51.343306)
		(end 141.482572 -51.36896)
		(stroke
			(width 0.0508)
			(type default)
		)
		(layer "In5.Cu")
	)
	(gr_line
		(start 141.477238 -51.343306)
		(end 141.482572 -51.31816)
		(stroke
			(width 0.0508)
			(type default)
		)
		(layer "In5.Cu")
	)
	(gr_line
		(start 141.498828 -83.312254)
		(end 141.509242 -83.315048)
		(stroke
			(width 0.0508)
			(type default)
		)
		(layer "In5.Cu")
	)
	(gr_line
		(start 141.509242 -83.315048)
		(end 141.518386 -83.32089)
		(stroke
			(width 0.0508)
			(type default)
		)
		(layer "In5.Cu")
	)
	(gr_line
		(start 141.547342 -31.645098)
		(end 141.552676 -31.670244)
		(stroke
			(width 0.0508)
			(type default)
		)
		(layer "In5.Cu")
	)
	(gr_line
		(start 141.547342 -31.645098)
		(end 141.552676 -31.619952)
		(stroke
			(width 0.0508)
			(type default)
		)
		(layer "In5.Cu")
	)
	(gr_line
		(start 141.552676 -68.853558)
		(end 142.064486 -68.521072)
		(stroke
			(width 0.0508)
			(type default)
		)
		(layer "In5.Cu")
	)
	(gr_line
		(start 141.586204 -79.133446)
		(end 141.629384 -79.161386)
		(stroke
			(width 0.0508)
			(type default)
		)
		(layer "In5.Cu")
	)
	(gr_arc
		(start 141.620748 -10.347706)
		(mid 141.747549 -10.295183)
		(end 141.800072 -10.168382)
		(stroke
			(width 0.0508)
			(type default)
		)
		(layer "In5.Cu")
	)
	(gr_line
		(start 141.659102 -70.17639)
		(end 141.714474 -69.916294)
		(stroke
			(width 0.0508)
			(type default)
		)
		(layer "In5.Cu")
	)
	(gr_line
		(start 141.666468 -68.188586)
		(end 141.926818 -68.243958)
		(stroke
			(width 0.0508)
			(type default)
		)
		(layer "In5.Cu")
	)
	(gr_line
		(start 141.714474 -69.916294)
		(end 141.969998 -69.750432)
		(stroke
			(width 0.0508)
			(type default)
		)
		(layer "In5.Cu")
	)
	(gr_line
		(start 141.750034 -19.73707)
		(end 141.755368 -19.711924)
		(stroke
			(width 0.0508)
			(type default)
		)
		(layer "In5.Cu")
	)
	(gr_line
		(start 141.750034 -19.686778)
		(end 141.755368 -19.711924)
		(stroke
			(width 0.0508)
			(type default)
		)
		(layer "In5.Cu")
	)
	(gr_arc
		(start 141.800072 -10.83183)
		(mid 141.747563 -10.704992)
		(end 141.620748 -10.652506)
		(stroke
			(width 0.0508)
			(type default)
		)
		(layer "In5.Cu")
	)
	(gr_line
		(start 141.800072 -10.83183)
		(end 141.800072 -11.20013)
		(stroke
			(width 0.0508)
			(type default)
		)
		(layer "In5.Cu")
	)
	(gr_line
		(start 141.800072 -9.800082)
		(end 141.800072 -10.168382)
		(stroke
			(width 0.0508)
			(type default)
		)
		(layer "In5.Cu")
	)
	(gr_line
		(start 141.857476 -70.414134)
		(end 142.368524 -70.08241)
		(stroke
			(width 0.0508)
			(type default)
		)
		(layer "In5.Cu")
	)
	(gr_line
		(start 141.94282 -92.51061)
		(end 141.95298 -92.494862)
		(stroke
			(width 0.0508)
			(type default)
		)
		(layer "In5.Cu")
	)
	(gr_line
		(start 141.95298 -92.494862)
		(end 141.956536 -92.477336)
		(stroke
			(width 0.0508)
			(type default)
		)
		(layer "In5.Cu")
	)
	(gr_line
		(start 141.969998 -69.750432)
		(end 142.230348 -69.80555)
		(stroke
			(width 0.0508)
			(type default)
		)
		(layer "In5.Cu")
	)
	(gr_line
		(start 142.117826 -89.33815)
		(end 142.181326 -89.039954)
		(stroke
			(width 0.0508)
			(type default)
		)
		(layer "In5.Cu")
	)
	(gr_line
		(start 142.117826 -89.33815)
		(end 142.262606 -89.560908)
		(stroke
			(width 0.0508)
			(type default)
		)
		(layer "In5.Cu")
	)
	(gr_line
		(start 142.181326 -89.039954)
		(end 142.404338 -88.89492)
		(stroke
			(width 0.0508)
			(type default)
		)
		(layer "In5.Cu")
	)
	(gr_line
		(start 142.243556 -44.191682)
		(end 142.24889 -44.166536)
		(stroke
			(width 0.0508)
			(type default)
		)
		(layer "In5.Cu")
	)
	(gr_line
		(start 142.243556 -44.14139)
		(end 142.24889 -44.166536)
		(stroke
			(width 0.0508)
			(type default)
		)
		(layer "In5.Cu")
	)
	(gr_line
		(start 142.30858 -81.287874)
		(end 142.377668 -81.309464)
		(stroke
			(width 0.0508)
			(type default)
		)
		(layer "In5.Cu")
	)
	(gr_line
		(start 142.32382 -88.36914)
		(end 142.38732 -88.070944)
		(stroke
			(width 0.0508)
			(type default)
		)
		(layer "In5.Cu")
	)
	(gr_line
		(start 142.32382 -88.36914)
		(end 142.468854 -88.592152)
		(stroke
			(width 0.0508)
			(type default)
		)
		(layer "In5.Cu")
	)
	(gr_line
		(start 142.347188 -83.858354)
		(end 142.370556 -83.87334)
		(stroke
			(width 0.0508)
			(type default)
		)
		(layer "In5.Cu")
	)
	(gr_line
		(start 142.370556 -83.87334)
		(end 142.385542 -83.896454)
		(stroke
			(width 0.0508)
			(type default)
		)
		(layer "In5.Cu")
	)
	(gr_line
		(start 142.377668 -81.309464)
		(end 142.417546 -81.370678)
		(stroke
			(width 0.0508)
			(type default)
		)
		(layer "In5.Cu")
	)
	(gr_line
		(start 142.38732 -88.070944)
		(end 142.610332 -87.926164)
		(stroke
			(width 0.0508)
			(type default)
		)
		(layer "In5.Cu")
	)
	(gr_line
		(start 142.413482 -65.110614)
		(end 142.435834 -65.096136)
		(stroke
			(width 0.0508)
			(type default)
		)
		(layer "In5.Cu")
	)
	(gr_line
		(start 142.435834 -65.096136)
		(end 142.450312 -65.073784)
		(stroke
			(width 0.0508)
			(type default)
		)
		(layer "In5.Cu")
	)
	(gr_line
		(start 142.489936 -69.637148)
		(end 142.545054 -69.377052)
		(stroke
			(width 0.0508)
			(type default)
		)
		(layer "In5.Cu")
	)
	(gr_line
		(start 142.527782 -84.115402)
		(end 142.537942 -84.13115)
		(stroke
			(width 0.0508)
			(type default)
		)
		(layer "In5.Cu")
	)
	(gr_line
		(start 142.537942 -84.13115)
		(end 142.541498 -84.148676)
		(stroke
			(width 0.0508)
			(type default)
		)
		(layer "In5.Cu")
	)
	(gr_line
		(start 142.545054 -69.377052)
		(end 142.800832 -69.21119)
		(stroke
			(width 0.0508)
			(type default)
		)
		(layer "In5.Cu")
	)
	(gr_line
		(start 142.553944 -50.734468)
		(end 142.559278 -50.759614)
		(stroke
			(width 0.0508)
			(type default)
		)
		(layer "In5.Cu")
	)
	(gr_line
		(start 142.553944 -50.734468)
		(end 142.559278 -50.709322)
		(stroke
			(width 0.0508)
			(type default)
		)
		(layer "In5.Cu")
	)
	(gr_line
		(start 142.570962 -89.58961)
		(end 142.697962 -88.99271)
		(stroke
			(width 0.0508)
			(type default)
		)
		(layer "In5.Cu")
	)
	(gr_line
		(start 142.670276 -80.64881)
		(end 142.725648 -80.388714)
		(stroke
			(width 0.0508)
			(type default)
		)
		(layer "In5.Cu")
	)
	(gr_line
		(start 142.670276 -80.64881)
		(end 142.836392 -80.904334)
		(stroke
			(width 0.0508)
			(type default)
		)
		(layer "In5.Cu")
	)
	(gr_line
		(start 142.687802 -69.874892)
		(end 143.198596 -69.543422)
		(stroke
			(width 0.0508)
			(type default)
		)
		(layer "In5.Cu")
	)
	(gr_line
		(start 142.723616 -31.924244)
		(end 142.72895 -31.94939)
		(stroke
			(width 0.0508)
			(type default)
		)
		(layer "In5.Cu")
	)
	(gr_line
		(start 142.723616 -31.924244)
		(end 142.72895 -31.899098)
		(stroke
			(width 0.0508)
			(type default)
		)
		(layer "In5.Cu")
	)
	(gr_line
		(start 142.759176 -79.895446)
		(end 142.780766 -79.909162)
		(stroke
			(width 0.0508)
			(type default)
		)
		(layer "In5.Cu")
	)
	(gr_line
		(start 142.776956 -88.620854)
		(end 142.903702 -88.025224)
		(stroke
			(width 0.0508)
			(type default)
		)
		(layer "In5.Cu")
	)
	(gr_line
		(start 142.780766 -79.909162)
		(end 142.795498 -79.931768)
		(stroke
			(width 0.0508)
			(type default)
		)
		(layer "In5.Cu")
	)
	(gr_line
		(start 142.800832 -93.501718)
		(end 142.810484 -93.486732)
		(stroke
			(width 0.0508)
			(type default)
		)
		(layer "In5.Cu")
	)
	(gr_line
		(start 142.800832 -69.21119)
		(end 143.060928 -69.266308)
		(stroke
			(width 0.0508)
			(type default)
		)
		(layer "In5.Cu")
	)
	(gr_line
		(start 142.810484 -93.486732)
		(end 142.814294 -93.469206)
		(stroke
			(width 0.0508)
			(type default)
		)
		(layer "In5.Cu")
	)
	(gr_line
		(start 142.836392 -80.904334)
		(end 143.096488 -80.959706)
		(stroke
			(width 0.0508)
			(type default)
		)
		(layer "In5.Cu")
	)
	(gr_line
		(start 143.00327 -80.251554)
		(end 143.33601 -80.763872)
		(stroke
			(width 0.0508)
			(type default)
		)
		(layer "In5.Cu")
	)
	(gr_line
		(start 143.046704 -78.462886)
		(end 143.06931 -78.477618)
		(stroke
			(width 0.0508)
			(type default)
		)
		(layer "In5.Cu")
	)
	(gr_line
		(start 143.06931 -78.477618)
		(end 143.084042 -78.500224)
		(stroke
			(width 0.0508)
			(type default)
		)
		(layer "In5.Cu")
	)
	(gr_line
		(start 143.129254 -86.964012)
		(end 143.134588 -86.938866)
		(stroke
			(width 0.0508)
			(type default)
		)
		(layer "In5.Cu")
	)
	(gr_line
		(start 143.129254 -86.91372)
		(end 143.134588 -86.938866)
		(stroke
			(width 0.0508)
			(type default)
		)
		(layer "In5.Cu")
	)
	(gr_line
		(start 143.13027 -66.170048)
		(end 143.152622 -66.15557)
		(stroke
			(width 0.0508)
			(type default)
		)
		(layer "In5.Cu")
	)
	(gr_line
		(start 143.152622 -66.15557)
		(end 143.1671 -66.133218)
		(stroke
			(width 0.0508)
			(type default)
		)
		(layer "In5.Cu")
	)
	(gr_line
		(start 143.209772 -81.479644)
		(end 143.265144 -81.219294)
		(stroke
			(width 0.0508)
			(type default)
		)
		(layer "In5.Cu")
	)
	(gr_line
		(start 143.209772 -81.479644)
		(end 143.375888 -81.735168)
		(stroke
			(width 0.0508)
			(type default)
		)
		(layer "In5.Cu")
	)
	(gr_line
		(start 143.228822 -44.569634)
		(end 143.234156 -44.544488)
		(stroke
			(width 0.0508)
			(type default)
		)
		(layer "In5.Cu")
	)
	(gr_line
		(start 143.228822 -44.519342)
		(end 143.234156 -44.544488)
		(stroke
			(width 0.0508)
			(type default)
		)
		(layer "In5.Cu")
	)
	(gr_line
		(start 143.228822 -18.800572)
		(end 143.234156 -18.775426)
		(stroke
			(width 0.0508)
			(type default)
		)
		(layer "In5.Cu")
	)
	(gr_line
		(start 143.228822 -18.75028)
		(end 143.234156 -18.775426)
		(stroke
			(width 0.0508)
			(type default)
		)
		(layer "In5.Cu")
	)
	(gr_line
		(start 143.255746 -63.832994)
		(end 143.265398 -63.818008)
		(stroke
			(width 0.0508)
			(type default)
		)
		(layer "In5.Cu")
	)
	(gr_line
		(start 143.265398 -63.818008)
		(end 143.269208 -63.800482)
		(stroke
			(width 0.0508)
			(type default)
		)
		(layer "In5.Cu")
	)
	(gr_line
		(start 143.36268 -84.502752)
		(end 143.425926 -84.800694)
		(stroke
			(width 0.0508)
			(type default)
		)
		(layer "In5.Cu")
	)
	(gr_line
		(start 143.36268 -84.502752)
		(end 143.50746 -84.27974)
		(stroke
			(width 0.0508)
			(type default)
		)
		(layer "In5.Cu")
	)
	(gr_line
		(start 143.375888 -81.735168)
		(end 143.636238 -81.79054)
		(stroke
			(width 0.0508)
			(type default)
		)
		(layer "In5.Cu")
	)
	(gr_arc
		(start 143.420846 -11.547602)
		(mid 143.54761 -11.495062)
		(end 143.60017 -11.368278)
		(stroke
			(width 0.0508)
			(type default)
		)
		(layer "In5.Cu")
	)
	(gr_line
		(start 143.425926 -84.800694)
		(end 143.648938 -84.945728)
		(stroke
			(width 0.0508)
			(type default)
		)
		(layer "In5.Cu")
	)
	(gr_line
		(start 143.477742 -80.01635)
		(end 143.533114 -79.756)
		(stroke
			(width 0.0508)
			(type default)
		)
		(layer "In5.Cu")
	)
	(gr_line
		(start 143.477742 -80.01635)
		(end 143.643858 -80.271874)
		(stroke
			(width 0.0508)
			(type default)
		)
		(layer "In5.Cu")
	)
	(gr_line
		(start 143.542258 -81.081626)
		(end 143.875506 -81.594452)
		(stroke
			(width 0.0508)
			(type default)
		)
		(layer "In5.Cu")
	)
	(gr_line
		(start 143.568674 -85.471508)
		(end 143.63192 -85.769704)
		(stroke
			(width 0.0508)
			(type default)
		)
		(layer "In5.Cu")
	)
	(gr_line
		(start 143.568674 -85.471508)
		(end 143.713454 -85.248496)
		(stroke
			(width 0.0508)
			(type default)
		)
		(layer "In5.Cu")
	)
	(gr_line
		(start 143.575786 -83.152996)
		(end 143.585692 -83.16849)
		(stroke
			(width 0.0508)
			(type default)
		)
		(layer "In5.Cu")
	)
	(gr_line
		(start 143.585692 -83.16849)
		(end 143.589248 -83.185508)
		(stroke
			(width 0.0508)
			(type default)
		)
		(layer "In5.Cu")
	)
	(gr_arc
		(start 143.60017 -12.031726)
		(mid 143.547659 -11.904892)
		(end 143.420846 -11.852402)
		(stroke
			(width 0.0508)
			(type default)
		)
		(layer "In5.Cu")
	)
	(gr_line
		(start 143.60017 -12.031726)
		(end 143.60017 -12.400026)
		(stroke
			(width 0.0508)
			(type default)
		)
		(layer "In5.Cu")
	)
	(gr_line
		(start 143.60017 -10.999978)
		(end 143.60017 -11.368278)
		(stroke
			(width 0.0508)
			(type default)
		)
		(layer "In5.Cu")
	)
	(gr_line
		(start 143.630396 -94.060264)
		(end 143.640048 -94.045278)
		(stroke
			(width 0.0508)
			(type default)
		)
		(layer "In5.Cu")
	)
	(gr_line
		(start 143.63192 -85.769704)
		(end 143.854932 -85.914738)
		(stroke
			(width 0.0508)
			(type default)
		)
		(layer "In5.Cu")
	)
	(gr_line
		(start 143.640048 -94.045278)
		(end 143.643858 -94.027752)
		(stroke
			(width 0.0508)
			(type default)
		)
		(layer "In5.Cu")
	)
	(gr_line
		(start 143.643858 -80.271874)
		(end 143.904208 -80.327246)
		(stroke
			(width 0.0508)
			(type default)
		)
		(layer "In5.Cu")
	)
	(gr_line
		(start 143.67129 -67.477386)
		(end 143.693896 -67.462654)
		(stroke
			(width 0.0508)
			(type default)
		)
		(layer "In5.Cu")
	)
	(gr_line
		(start 143.693896 -67.462654)
		(end 143.708628 -67.440048)
		(stroke
			(width 0.0508)
			(type default)
		)
		(layer "In5.Cu")
	)
	(gr_line
		(start 143.71828 -50.447956)
		(end 143.723614 -50.473102)
		(stroke
			(width 0.0508)
			(type default)
		)
		(layer "In5.Cu")
	)
	(gr_line
		(start 143.71828 -50.447956)
		(end 143.723614 -50.42281)
		(stroke
			(width 0.0508)
			(type default)
		)
		(layer "In5.Cu")
	)
	(gr_line
		(start 143.810736 -79.619094)
		(end 144.142968 -80.13065)
		(stroke
			(width 0.0508)
			(type default)
		)
		(layer "In5.Cu")
	)
	(gr_line
		(start 143.815308 -61.230256)
		(end 143.820896 -61.204348)
		(stroke
			(width 0.0508)
			(type default)
		)
		(layer "In5.Cu")
	)
	(gr_line
		(start 143.815562 -61.17844)
		(end 143.820896 -61.204348)
		(stroke
			(width 0.0508)
			(type default)
		)
		(layer "In5.Cu")
	)
	(gr_line
		(start 143.815816 -84.251038)
		(end 143.942308 -84.846414)
		(stroke
			(width 0.0508)
			(type default)
		)
		(layer "In5.Cu")
	)
	(gr_line
		(start 143.920718 -32.438594)
		(end 143.926052 -32.46374)
		(stroke
			(width 0.0508)
			(type default)
		)
		(layer "In5.Cu")
	)
	(gr_line
		(start 143.920718 -32.438594)
		(end 143.926052 -32.413448)
		(stroke
			(width 0.0508)
			(type default)
		)
		(layer "In5.Cu")
	)
	(gr_line
		(start 144.017492 -80.847184)
		(end 144.07261 -80.586834)
		(stroke
			(width 0.0508)
			(type default)
		)
		(layer "In5.Cu")
	)
	(gr_line
		(start 144.017492 -80.847184)
		(end 144.183608 -81.102708)
		(stroke
			(width 0.0508)
			(type default)
		)
		(layer "In5.Cu")
	)
	(gr_line
		(start 144.021556 -85.219794)
		(end 144.148302 -85.816186)
		(stroke
			(width 0.0508)
			(type default)
		)
		(layer "In5.Cu")
	)
	(gr_line
		(start 144.049242 -64.774572)
		(end 144.058894 -64.759586)
		(stroke
			(width 0.0508)
			(type default)
		)
		(layer "In5.Cu")
	)
	(gr_line
		(start 144.058894 -64.759586)
		(end 144.062704 -64.74206)
		(stroke
			(width 0.0508)
			(type default)
		)
		(layer "In5.Cu")
	)
	(gr_line
		(start 144.183608 -81.102708)
		(end 144.443704 -81.15808)
		(stroke
			(width 0.0508)
			(type default)
		)
		(layer "In5.Cu")
	)
	(gr_line
		(start 144.288764 -86.527894)
		(end 144.294098 -86.502748)
		(stroke
			(width 0.0508)
			(type default)
		)
		(layer "In5.Cu")
	)
	(gr_line
		(start 144.288764 -86.477602)
		(end 144.294098 -86.502748)
		(stroke
			(width 0.0508)
			(type default)
		)
		(layer "In5.Cu")
	)
	(gr_line
		(start 144.349724 -80.449166)
		(end 144.682464 -80.96123)
		(stroke
			(width 0.0508)
			(type default)
		)
		(layer "In5.Cu")
	)
	(gr_line
		(start 144.385792 -43.583098)
		(end 144.391126 -43.557952)
		(stroke
			(width 0.0508)
			(type default)
		)
		(layer "In5.Cu")
	)
	(gr_line
		(start 144.385792 -43.532806)
		(end 144.391126 -43.557952)
		(stroke
			(width 0.0508)
			(type default)
		)
		(layer "In5.Cu")
	)
	(gr_line
		(start 144.454626 -82.4865)
		(end 144.464278 -82.501486)
		(stroke
			(width 0.0508)
			(type default)
		)
		(layer "In5.Cu")
	)
	(gr_line
		(start 144.464278 -82.501486)
		(end 144.468088 -82.519012)
		(stroke
			(width 0.0508)
			(type default)
		)
		(layer "In5.Cu")
	)
	(gr_line
		(start 144.490694 -68.704714)
		(end 144.513046 -68.690236)
		(stroke
			(width 0.0508)
			(type default)
		)
		(layer "In5.Cu")
	)
	(gr_line
		(start 144.513046 -68.690236)
		(end 144.527778 -68.66763)
		(stroke
			(width 0.0508)
			(type default)
		)
		(layer "In5.Cu")
	)
	(gr_line
		(start 144.723104 -94.405958)
		(end 144.73301 -94.390718)
		(stroke
			(width 0.0508)
			(type default)
		)
		(layer "In5.Cu")
	)
	(gr_line
		(start 144.73301 -94.390718)
		(end 144.736566 -94.373192)
		(stroke
			(width 0.0508)
			(type default)
		)
		(layer "In5.Cu")
	)
	(gr_line
		(start 144.849596 -49.933352)
		(end 144.85493 -49.958498)
		(stroke
			(width 0.0508)
			(type default)
		)
		(layer "In5.Cu")
	)
	(gr_line
		(start 144.849596 -49.933352)
		(end 144.85493 -49.908206)
		(stroke
			(width 0.0508)
			(type default)
		)
		(layer "In5.Cu")
	)
	(gr_line
		(start 144.947132 -60.578238)
		(end 144.952466 -60.553092)
		(stroke
			(width 0.0508)
			(type default)
		)
		(layer "In5.Cu")
	)
	(gr_line
		(start 144.947132 -60.527946)
		(end 144.952466 -60.553092)
		(stroke
			(width 0.0508)
			(type default)
		)
		(layer "In5.Cu")
	)
	(gr_line
		(start 145.128234 -81.647792)
		(end 145.137886 -81.662778)
		(stroke
			(width 0.0508)
			(type default)
		)
		(layer "In5.Cu")
	)
	(gr_line
		(start 145.137886 -81.662778)
		(end 145.141696 -81.680304)
		(stroke
			(width 0.0508)
			(type default)
		)
		(layer "In5.Cu")
	)
	(gr_arc
		(start 145.22069 -10.347706)
		(mid 145.347491 -10.295186)
		(end 145.400014 -10.168382)
		(stroke
			(width 0.0508)
			(type default)
		)
		(layer "In5.Cu")
	)
	(gr_line
		(start 145.239994 -65.082166)
		(end 145.249646 -65.06718)
		(stroke
			(width 0.0508)
			(type default)
		)
		(layer "In5.Cu")
	)
	(gr_line
		(start 145.249646 -65.06718)
		(end 145.253456 -65.049654)
		(stroke
			(width 0.0508)
			(type default)
		)
		(layer "In5.Cu")
	)
	(gr_line
		(start 145.273522 -86.360254)
		(end 145.278856 -86.335108)
		(stroke
			(width 0.0508)
			(type default)
		)
		(layer "In5.Cu")
	)
	(gr_line
		(start 145.273522 -86.309962)
		(end 145.278856 -86.335108)
		(stroke
			(width 0.0508)
			(type default)
		)
		(layer "In5.Cu")
	)
	(gr_arc
		(start 145.400014 -10.83183)
		(mid 145.347491 -10.705029)
		(end 145.22069 -10.652506)
		(stroke
			(width 0.0508)
			(type default)
		)
		(layer "In5.Cu")
	)
	(gr_line
		(start 145.400014 -10.83183)
		(end 145.400014 -11.20013)
		(stroke
			(width 0.0508)
			(type default)
		)
		(layer "In5.Cu")
	)
	(gr_line
		(start 145.400014 -9.800082)
		(end 145.400014 -10.168382)
		(stroke
			(width 0.0508)
			(type default)
		)
		(layer "In5.Cu")
	)
	(gr_line
		(start 145.496534 -43.55211)
		(end 145.501868 -43.526964)
		(stroke
			(width 0.0508)
			(type default)
		)
		(layer "In5.Cu")
	)
	(gr_line
		(start 145.496534 -43.501818)
		(end 145.501868 -43.526964)
		(stroke
			(width 0.0508)
			(type default)
		)
		(layer "In5.Cu")
	)
	(gr_line
		(start 146.188176 -60.649612)
		(end 146.19351 -60.624466)
		(stroke
			(width 0.0508)
			(type default)
		)
		(layer "In5.Cu")
	)
	(gr_line
		(start 146.188176 -60.59932)
		(end 146.19351 -60.624466)
		(stroke
			(width 0.0508)
			(type default)
		)
		(layer "In5.Cu")
	)
	(gr_line
		(start 146.282664 -87.10041)
		(end 146.287998 -87.075264)
		(stroke
			(width 0.0508)
			(type default)
		)
		(layer "In5.Cu")
	)
	(gr_line
		(start 146.282664 -87.050118)
		(end 146.287998 -87.075264)
		(stroke
			(width 0.0508)
			(type default)
		)
		(layer "In5.Cu")
	)
	(gr_line
		(start 146.37893 -65.81775)
		(end 146.388582 -65.802764)
		(stroke
			(width 0.0508)
			(type default)
		)
		(layer "In5.Cu")
	)
	(gr_line
		(start 146.388582 -65.802764)
		(end 146.392392 -65.785238)
		(stroke
			(width 0.0508)
			(type default)
		)
		(layer "In5.Cu")
	)
	(gr_line
		(start 146.550634 -43.396154)
		(end 146.555968 -43.371008)
		(stroke
			(width 0.0508)
			(type default)
		)
		(layer "In5.Cu")
	)
	(gr_line
		(start 146.550634 -43.345862)
		(end 146.555968 -43.371008)
		(stroke
			(width 0.0508)
			(type default)
		)
		(layer "In5.Cu")
	)
	(gr_arc
		(start 147.020788 -11.547602)
		(mid 147.147589 -11.495079)
		(end 147.200112 -11.368278)
		(stroke
			(width 0.0508)
			(type default)
		)
		(layer "In5.Cu")
	)
	(gr_arc
		(start 147.200112 -12.031726)
		(mid 147.147598 -11.904912)
		(end 147.020788 -11.852402)
		(stroke
			(width 0.0508)
			(type default)
		)
		(layer "In5.Cu")
	)
	(gr_line
		(start 147.200112 -12.031726)
		(end 147.200112 -12.400026)
		(stroke
			(width 0.0508)
			(type default)
		)
		(layer "In5.Cu")
	)
	(gr_line
		(start 147.200112 -10.999978)
		(end 147.200112 -11.368278)
		(stroke
			(width 0.0508)
			(type default)
		)
		(layer "In5.Cu")
	)
	(gr_line
		(start 147.45589 -60.777882)
		(end 147.461224 -60.752736)
		(stroke
			(width 0.0508)
			(type default)
		)
		(layer "In5.Cu")
	)
	(gr_line
		(start 147.45589 -60.72759)
		(end 147.461224 -60.752736)
		(stroke
			(width 0.0508)
			(type default)
		)
		(layer "In5.Cu")
	)
	(gr_arc
		(start 148.820632 -10.347706)
		(mid 148.947433 -10.295183)
		(end 148.999956 -10.168382)
		(stroke
			(width 0.0508)
			(type default)
		)
		(layer "In5.Cu")
	)
	(gr_arc
		(start 148.999956 -10.83183)
		(mid 148.947446 -10.704998)
		(end 148.820632 -10.652506)
		(stroke
			(width 0.0508)
			(type default)
		)
		(layer "In5.Cu")
	)
	(gr_line
		(start 148.999956 -10.83183)
		(end 148.999956 -11.20013)
		(stroke
			(width 0.0508)
			(type default)
		)
		(layer "In5.Cu")
	)
	(gr_line
		(start 148.999956 -9.800082)
		(end 148.999956 -10.168382)
		(stroke
			(width 0.0508)
			(type default)
		)
		(layer "In5.Cu")
	)
	(gr_line
		(start 165.898322 -20.56384)
		(end 165.908228 -20.616418)
		(stroke
			(width 0.06985)
			(type default)
		)
		(layer "In5.Cu")
	)
	(gr_line
		(start 165.898322 -20.56384)
		(end 165.917372 -20.514564)
		(stroke
			(width 0.06985)
			(type default)
		)
		(layer "In5.Cu")
	)
	(gr_line
		(start 166.014146 -21.185886)
		(end 166.021258 -21.223986)
		(stroke
			(width 0.06985)
			(type default)
		)
		(layer "In5.Cu")
	)
	(gr_line
		(start 166.021258 -21.223986)
		(end 166.045134 -21.255228)
		(stroke
			(width 0.06985)
			(type default)
		)
		(layer "In5.Cu")
	)
	(gr_arc
		(start 166.125398 -23.166832)
		(mid 166.207244 -23.364378)
		(end 166.404798 -23.446232)
		(stroke
			(width 0.06985)
			(type default)
		)
		(layer "In5.Cu")
	)
	(gr_line
		(start 166.251636 -19.646646)
		(end 166.292784 -19.539458)
		(stroke
			(width 0.06985)
			(type default)
		)
		(layer "In5.Cu")
	)
	(gr_line
		(start 166.292784 -19.539458)
		(end 166.402512 -19.50212)
		(stroke
			(width 0.06985)
			(type default)
		)
		(layer "In5.Cu")
	)
	(gr_arc
		(start 166.404798 -23.776432)
		(mid 166.207232 -23.858266)
		(end 166.125398 -24.055832)
		(stroke
			(width 0.06985)
			(type default)
		)
		(layer "In5.Cu")
	)
	(gr_line
		(start 167.19677 -22.220174)
		(end 167.214804 -22.243796)
		(stroke
			(width 0.06985)
			(type default)
		)
		(layer "In5.Cu")
	)
	(gr_line
		(start 167.214804 -22.243796)
		(end 167.221662 -22.273006)
		(stroke
			(width 0.06985)
			(type default)
		)
		(layer "In5.Cu")
	)
	(gr_arc
		(start 168.159938 -23.123906)
		(mid 168.241777 -23.321454)
		(end 168.439338 -23.403306)
		(stroke
			(width 0.06985)
			(type default)
		)
		(layer "In5.Cu")
	)
	(gr_line
		(start 168.264586 -20.968208)
		(end 168.270682 -20.996656)
		(stroke
			(width 0.06985)
			(type default)
		)
		(layer "In5.Cu")
	)
	(gr_line
		(start 168.264586 -20.968208)
		(end 168.270682 -20.940014)
		(stroke
			(width 0.06985)
			(type default)
		)
		(layer "In5.Cu")
	)
	(gr_line
		(start 168.370504 -21.467064)
		(end 168.373044 -21.478494)
		(stroke
			(width 0.06985)
			(type default)
		)
		(layer "In5.Cu")
	)
	(gr_line
		(start 168.373044 -21.478494)
		(end 168.378378 -21.487638)
		(stroke
			(width 0.06985)
			(type default)
		)
		(layer "In5.Cu")
	)
	(gr_line
		(start 168.40835 -20.283932)
		(end 168.412922 -20.262342)
		(stroke
			(width 0.06985)
			(type default)
		)
		(layer "In5.Cu")
	)
	(gr_line
		(start 168.412922 -20.262342)
		(end 168.42486 -20.2438)
		(stroke
			(width 0.06985)
			(type default)
		)
		(layer "In5.Cu")
	)
	(gr_arc
		(start 168.439338 -23.733506)
		(mid 168.241772 -23.81534)
		(end 168.159938 -24.012906)
		(stroke
			(width 0.06985)
			(type default)
		)
		(layer "In5.Cu")
	)
	(gr_line
		(start 168.638474 -19.914616)
		(end 168.672256 -19.862546)
		(stroke
			(width 0.06985)
			(type default)
		)
		(layer "In5.Cu")
	)
	(gr_line
		(start 168.672256 -19.862546)
		(end 168.729406 -19.838416)
		(stroke
			(width 0.06985)
			(type default)
		)
		(layer "In5.Cu")
	)
	(gr_line
		(start 169.062146 -18.946622)
		(end 169.064686 -18.94586)
		(stroke
			(width 0.06985)
			(type default)
		)
		(layer "In5.Cu")
	)
	(gr_line
		(start 169.064686 -18.94586)
		(end 169.06748 -18.944082)
		(stroke
			(width 0.06985)
			(type default)
		)
		(layer "In5.Cu")
	)
	(gr_line
		(start 169.311066 -22.480016)
		(end 169.333164 -22.51964)
		(stroke
			(width 0.06985)
			(type default)
		)
		(layer "In5.Cu")
	)
	(gr_arc
		(start 170.217084 -23.11527)
		(mid 170.298907 -23.312861)
		(end 170.496484 -23.39467)
		(stroke
			(width 0.06985)
			(type default)
		)
		(layer "In5.Cu")
	)
	(gr_arc
		(start 170.496484 -23.72487)
		(mid 170.298918 -23.806704)
		(end 170.217084 -24.00427)
		(stroke
			(width 0.06985)
			(type default)
		)
		(layer "In5.Cu")
	)
	(gr_line
		(start 171.142152 -22.338284)
		(end 171.174918 -22.288754)
		(stroke
			(width 0.06985)
			(type default)
		)
		(layer "In5.Cu")
	)
	(gr_arc
		(start 172.26915 -23.112984)
		(mid 172.350984 -23.31055)
		(end 172.54855 -23.392384)
		(stroke
			(width 0.06985)
			(type default)
		)
		(layer "In5.Cu")
	)
	(gr_arc
		(start 172.54855 -23.722584)
		(mid 172.350946 -23.8044)
		(end 172.26915 -24.001984)
		(stroke
			(width 0.06985)
			(type default)
		)
		(layer "In5.Cu")
	)
	(gr_line
		(start 172.948346 -17.896078)
		(end 172.995844 -17.652746)
		(stroke
			(width 0.06985)
			(type default)
		)
		(layer "In5.Cu")
	)
	(gr_line
		(start 172.995844 -17.652746)
		(end 173.343316 -17.418304)
		(stroke
			(width 0.06985)
			(type default)
		)
		(layer "In5.Cu")
	)
	(gr_line
		(start 173.072552 -19.429476)
		(end 173.086776 -19.40814)
		(stroke
			(width 0.06985)
			(type default)
		)
		(layer "In5.Cu")
	)
	(gr_line
		(start 173.086776 -19.40814)
		(end 173.107858 -19.393916)
		(stroke
			(width 0.06985)
			(type default)
		)
		(layer "In5.Cu")
	)
	(gr_line
		(start 173.164246 -18.15211)
		(end 173.742604 -17.76222)
		(stroke
			(width 0.06985)
			(type default)
		)
		(layer "In5.Cu")
	)
	(gr_line
		(start 173.192694 -22.220682)
		(end 173.235112 -22.164802)
		(stroke
			(width 0.06985)
			(type default)
		)
		(layer "In5.Cu")
	)
	(gr_line
		(start 173.343316 -17.418304)
		(end 173.586902 -17.465548)
		(stroke
			(width 0.06985)
			(type default)
		)
		(layer "In5.Cu")
	)
	(gr_line
		(start 173.85284 -15.717012)
		(end 173.87697 -15.700756)
		(stroke
			(width 0.06985)
			(type default)
		)
		(layer "In5.Cu")
	)
	(gr_line
		(start 173.87697 -15.700756)
		(end 173.892464 -15.67688)
		(stroke
			(width 0.06985)
			(type default)
		)
		(layer "In5.Cu")
	)
	(gr_line
		(start 173.938184 -17.22882)
		(end 173.985682 -16.985234)
		(stroke
			(width 0.06985)
			(type default)
		)
		(layer "In5.Cu")
	)
	(gr_line
		(start 173.985682 -16.985234)
		(end 174.333154 -16.750792)
		(stroke
			(width 0.06985)
			(type default)
		)
		(layer "In5.Cu")
	)
	(gr_line
		(start 174.154084 -17.484598)
		(end 174.731934 -17.094962)
		(stroke
			(width 0.06985)
			(type default)
		)
		(layer "In5.Cu")
	)
	(gr_line
		(start 174.281084 -20.336764)
		(end 174.282862 -20.330922)
		(stroke
			(width 0.06985)
			(type default)
		)
		(layer "In5.Cu")
	)
	(gr_line
		(start 174.282862 -20.330922)
		(end 174.286418 -20.325334)
		(stroke
			(width 0.06985)
			(type default)
		)
		(layer "In5.Cu")
	)
	(gr_arc
		(start 174.314866 -23.112476)
		(mid 174.3967 -23.310042)
		(end 174.594266 -23.391876)
		(stroke
			(width 0.06985)
			(type default)
		)
		(layer "In5.Cu")
	)
	(gr_line
		(start 174.333154 -16.750792)
		(end 174.57674 -16.798036)
		(stroke
			(width 0.06985)
			(type default)
		)
		(layer "In5.Cu")
	)
	(gr_line
		(start 174.356522 -21.233384)
		(end 174.368714 -21.217636)
		(stroke
			(width 0.06985)
			(type default)
		)
		(layer "In5.Cu")
	)
	(gr_line
		(start 174.368714 -21.217636)
		(end 174.374556 -21.19757)
		(stroke
			(width 0.06985)
			(type default)
		)
		(layer "In5.Cu")
	)
	(gr_line
		(start 174.462694 -13.86586)
		(end 174.514256 -14.108684)
		(stroke
			(width 0.06985)
			(type default)
		)
		(layer "In5.Cu")
	)
	(gr_line
		(start 174.462694 -13.86586)
		(end 174.69104 -13.514324)
		(stroke
			(width 0.06985)
			(type default)
		)
		(layer "In5.Cu")
	)
	(gr_line
		(start 174.562262 -19.893788)
		(end 174.577248 -19.870166)
		(stroke
			(width 0.06985)
			(type default)
		)
		(layer "In5.Cu")
	)
	(gr_line
		(start 174.577248 -19.870166)
		(end 174.599854 -19.854672)
		(stroke
			(width 0.06985)
			(type default)
		)
		(layer "In5.Cu")
	)
	(gr_arc
		(start 174.594266 -23.722076)
		(mid 174.3967 -23.80391)
		(end 174.314866 -24.001476)
		(stroke
			(width 0.06985)
			(type default)
		)
		(layer "In5.Cu")
	)
	(gr_line
		(start 174.603664 -18.382234)
		(end 174.650654 -18.138648)
		(stroke
			(width 0.06985)
			(type default)
		)
		(layer "In5.Cu")
	)
	(gr_line
		(start 174.650654 -18.138648)
		(end 174.998126 -17.90446)
		(stroke
			(width 0.06985)
			(type default)
		)
		(layer "In5.Cu")
	)
	(gr_line
		(start 174.69104 -13.514324)
		(end 174.933864 -13.463016)
		(stroke
			(width 0.06985)
			(type default)
		)
		(layer "In5.Cu")
	)
	(gr_line
		(start 174.813214 -14.25956)
		(end 175.191928 -13.676376)
		(stroke
			(width 0.06985)
			(type default)
		)
		(layer "In5.Cu")
	)
	(gr_line
		(start 174.821596 -18.636234)
		(end 175.396652 -18.24863)
		(stroke
			(width 0.06985)
			(type default)
		)
		(layer "In5.Cu")
	)
	(gr_line
		(start 174.928022 -16.561308)
		(end 174.97552 -16.317722)
		(stroke
			(width 0.06985)
			(type default)
		)
		(layer "In5.Cu")
	)
	(gr_line
		(start 174.97552 -16.317722)
		(end 175.322992 -16.08328)
		(stroke
			(width 0.06985)
			(type default)
		)
		(layer "In5.Cu")
	)
	(gr_line
		(start 174.998126 -17.90446)
		(end 175.241712 -17.951704)
		(stroke
			(width 0.06985)
			(type default)
		)
		(layer "In5.Cu")
	)
	(gr_line
		(start 175.113188 -12.864846)
		(end 175.16475 -13.107416)
		(stroke
			(width 0.06985)
			(type default)
		)
		(layer "In5.Cu")
	)
	(gr_line
		(start 175.113188 -12.864846)
		(end 175.341534 -12.51331)
		(stroke
			(width 0.06985)
			(type default)
		)
		(layer "In5.Cu")
	)
	(gr_line
		(start 175.145192 -16.81607)
		(end 175.72101 -16.427704)
		(stroke
			(width 0.06985)
			(type default)
		)
		(layer "In5.Cu")
	)
	(gr_line
		(start 175.217074 -19.42592)
		(end 175.261778 -19.181826)
		(stroke
			(width 0.06985)
			(type default)
		)
		(layer "In5.Cu")
	)
	(gr_line
		(start 175.261778 -19.181826)
		(end 175.60671 -18.943828)
		(stroke
			(width 0.06985)
			(type default)
		)
		(layer "In5.Cu")
	)
	(gr_line
		(start 175.322992 -16.08328)
		(end 175.566578 -16.130778)
		(stroke
			(width 0.06985)
			(type default)
		)
		(layer "In5.Cu")
	)
	(gr_line
		(start 175.341534 -12.51331)
		(end 175.584104 -12.462002)
		(stroke
			(width 0.06985)
			(type default)
		)
		(layer "In5.Cu")
	)
	(gr_line
		(start 175.435768 -19.679412)
		(end 176.01057 -19.282664)
		(stroke
			(width 0.06985)
			(type default)
		)
		(layer "In5.Cu")
	)
	(gr_line
		(start 175.464216 -13.257022)
		(end 175.842422 -12.675108)
		(stroke
			(width 0.06985)
			(type default)
		)
		(layer "In5.Cu")
	)
	(gr_line
		(start 175.592994 -17.714722)
		(end 175.640492 -17.471136)
		(stroke
			(width 0.06985)
			(type default)
		)
		(layer "In5.Cu")
	)
	(gr_line
		(start 175.60671 -18.943828)
		(end 175.851058 -18.988532)
		(stroke
			(width 0.06985)
			(type default)
		)
		(layer "In5.Cu")
	)
	(gr_line
		(start 175.640492 -17.471136)
		(end 175.987964 -17.236948)
		(stroke
			(width 0.06985)
			(type default)
		)
		(layer "In5.Cu")
	)
	(gr_line
		(start 175.763428 -11.863832)
		(end 175.81499 -12.106402)
		(stroke
			(width 0.06985)
			(type default)
		)
		(layer "In5.Cu")
	)
	(gr_line
		(start 175.763428 -11.863832)
		(end 175.991774 -11.512296)
		(stroke
			(width 0.06985)
			(type default)
		)
		(layer "In5.Cu")
	)
	(gr_line
		(start 175.80991 -17.969992)
		(end 176.385982 -17.581372)
		(stroke
			(width 0.06985)
			(type default)
		)
		(layer "In5.Cu")
	)
	(gr_line
		(start 175.987964 -17.236948)
		(end 176.231296 -17.284192)
		(stroke
			(width 0.06985)
			(type default)
		)
		(layer "In5.Cu")
	)
	(gr_line
		(start 175.991774 -11.512296)
		(end 176.234344 -11.460988)
		(stroke
			(width 0.06985)
			(type default)
		)
		(layer "In5.Cu")
	)
	(gr_line
		(start 176.114964 -12.2555)
		(end 176.492662 -11.67384)
		(stroke
			(width 0.06985)
			(type default)
		)
		(layer "In5.Cu")
	)
	(gr_line
		(start 176.199546 -18.747994)
		(end 176.244504 -18.5039)
		(stroke
			(width 0.06985)
			(type default)
		)
		(layer "In5.Cu")
	)
	(gr_line
		(start 176.244504 -18.5039)
		(end 176.589436 -18.265648)
		(stroke
			(width 0.06985)
			(type default)
		)
		(layer "In5.Cu")
	)
	(gr_arc
		(start 176.36871 -23.103332)
		(mid 176.450556 -23.300873)
		(end 176.64811 -23.382732)
		(stroke
			(width 0.06985)
			(type default)
		)
		(layer "In5.Cu")
	)
	(gr_line
		(start 176.417224 -19.002248)
		(end 176.993042 -18.604992)
		(stroke
			(width 0.06985)
			(type default)
		)
		(layer "In5.Cu")
	)
	(gr_line
		(start 176.583086 -17.04721)
		(end 176.630076 -16.803878)
		(stroke
			(width 0.06985)
			(type default)
		)
		(layer "In5.Cu")
	)
	(gr_line
		(start 176.589436 -18.265648)
		(end 176.83353 -18.310606)
		(stroke
			(width 0.06985)
			(type default)
		)
		(layer "In5.Cu")
	)
	(gr_line
		(start 176.630076 -16.803878)
		(end 176.977548 -16.569436)
		(stroke
			(width 0.06985)
			(type default)
		)
		(layer "In5.Cu")
	)
	(gr_arc
		(start 176.64811 -23.712932)
		(mid 176.450544 -23.794766)
		(end 176.36871 -23.992332)
		(stroke
			(width 0.06985)
			(type default)
		)
		(layer "In5.Cu")
	)
	(gr_line
		(start 176.799748 -17.30248)
		(end 177.376328 -16.913606)
		(stroke
			(width 0.06985)
			(type default)
		)
		(layer "In5.Cu")
	)
	(gr_line
		(start 176.977548 -16.569436)
		(end 177.221134 -16.61668)
		(stroke
			(width 0.06985)
			(type default)
		)
		(layer "In5.Cu")
	)
	(gr_line
		(start 177.125122 -10.700258)
		(end 177.136552 -10.682986)
		(stroke
			(width 0.06985)
			(type default)
		)
		(layer "In5.Cu")
	)
	(gr_line
		(start 177.136552 -10.682986)
		(end 177.141124 -10.661904)
		(stroke
			(width 0.06985)
			(type default)
		)
		(layer "In5.Cu")
	)
	(gr_line
		(start 177.182272 -18.069814)
		(end 177.22723 -17.82572)
		(stroke
			(width 0.06985)
			(type default)
		)
		(layer "In5.Cu")
	)
	(gr_line
		(start 177.22723 -17.82572)
		(end 177.572162 -17.587722)
		(stroke
			(width 0.06985)
			(type default)
		)
		(layer "In5.Cu")
	)
	(gr_line
		(start 177.353468 -14.928342)
		(end 177.377598 -14.912086)
		(stroke
			(width 0.06985)
			(type default)
		)
		(layer "In5.Cu")
	)
	(gr_line
		(start 177.377598 -14.912086)
		(end 177.406046 -14.906498)
		(stroke
			(width 0.06985)
			(type default)
		)
		(layer "In5.Cu")
	)
	(gr_line
		(start 177.401474 -18.323052)
		(end 177.973482 -17.928336)
		(stroke
			(width 0.06985)
			(type default)
		)
		(layer "In5.Cu")
	)
	(gr_line
		(start 177.560732 -20.235418)
		(end 177.565304 -20.214336)
		(stroke
			(width 0.06985)
			(type default)
		)
		(layer "In5.Cu")
	)
	(gr_line
		(start 177.565304 -20.214336)
		(end 177.576226 -20.197826)
		(stroke
			(width 0.06985)
			(type default)
		)
		(layer "In5.Cu")
	)
	(gr_line
		(start 177.572162 -17.587722)
		(end 177.816002 -17.632426)
		(stroke
			(width 0.06985)
			(type default)
		)
		(layer "In5.Cu")
	)
	(gr_line
		(start 177.764948 -19.906996)
		(end 177.78095 -19.882358)
		(stroke
			(width 0.06985)
			(type default)
		)
		(layer "In5.Cu")
	)
	(gr_line
		(start 177.78095 -19.882358)
		(end 177.807112 -19.86534)
		(stroke
			(width 0.06985)
			(type default)
		)
		(layer "In5.Cu")
	)
	(gr_line
		(start 177.899822 -5.502402)
		(end 177.904902 -5.479034)
		(stroke
			(width 0.06985)
			(type default)
		)
		(layer "In5.Cu")
	)
	(gr_line
		(start 177.904902 -5.479034)
		(end 177.905156 -5.479034)
		(stroke
			(width 0.06985)
			(type default)
		)
		(layer "In5.Cu")
	)
	(gr_line
		(start 177.905156 -5.479034)
		(end 177.916586 -5.461762)
		(stroke
			(width 0.06985)
			(type default)
		)
		(layer "In5.Cu")
	)
	(gr_line
		(start 178.148234 -17.406366)
		(end 178.16449 -17.39519)
		(stroke
			(width 0.06985)
			(type default)
		)
		(layer "In5.Cu")
	)
	(gr_line
		(start 178.151536 -18.560288)
		(end 178.173126 -18.545556)
		(stroke
			(width 0.06985)
			(type default)
		)
		(layer "In5.Cu")
	)
	(gr_line
		(start 178.16449 -17.39519)
		(end 178.184048 -17.390364)
		(stroke
			(width 0.06985)
			(type default)
		)
		(layer "In5.Cu")
	)
	(gr_line
		(start 178.168046 -19.630644)
		(end 178.19624 -19.612356)
		(stroke
			(width 0.06985)
			(type default)
		)
		(layer "In5.Cu")
	)
	(gr_line
		(start 178.173126 -18.545556)
		(end 178.19878 -18.54073)
		(stroke
			(width 0.06985)
			(type default)
		)
		(layer "In5.Cu")
	)
	(gr_line
		(start 178.19624 -19.612356)
		(end 178.221132 -19.607022)
		(stroke
			(width 0.06985)
			(type default)
		)
		(layer "In5.Cu")
	)
	(gr_line
		(start 178.215544 -5.607558)
		(end 178.215544 -5.607812)
		(stroke
			(width 0.06985)
			(type default)
		)
		(layer "In5.Cu")
	)
	(gr_arc
		(start 178.407314 -23.11654)
		(mid 178.489163 -23.314075)
		(end 178.686714 -23.39594)
		(stroke
			(width 0.06985)
			(type default)
		)
		(layer "In5.Cu")
	)
	(gr_line
		(start 178.41214 -4.698746)
		(end 178.428142 -4.674108)
		(stroke
			(width 0.06985)
			(type default)
		)
		(layer "In5.Cu")
	)
	(gr_line
		(start 178.428142 -4.674108)
		(end 178.45278 -4.658106)
		(stroke
			(width 0.06985)
			(type default)
		)
		(layer "In5.Cu")
	)
	(gr_line
		(start 178.433476 -15.802102)
		(end 178.455066 -15.78737)
		(stroke
			(width 0.06985)
			(type default)
		)
		(layer "In5.Cu")
	)
	(gr_line
		(start 178.455066 -15.78737)
		(end 178.48072 -15.782544)
		(stroke
			(width 0.06985)
			(type default)
		)
		(layer "In5.Cu")
	)
	(gr_arc
		(start 178.686714 -23.72614)
		(mid 178.489148 -23.807974)
		(end 178.407314 -24.00554)
		(stroke
			(width 0.06985)
			(type default)
		)
		(layer "In5.Cu")
	)
	(gr_line
		(start 178.778408 -4.446524)
		(end 178.796188 -4.435094)
		(stroke
			(width 0.06985)
			(type default)
		)
		(layer "In5.Cu")
	)
	(gr_line
		(start 178.796188 -4.435094)
		(end 178.816508 -4.430776)
		(stroke
			(width 0.06985)
			(type default)
		)
		(layer "In5.Cu")
	)
	(gr_line
		(start 179.41163 -22.022562)
		(end 179.416202 -22.001226)
		(stroke
			(width 0.06985)
			(type default)
		)
		(layer "In5.Cu")
	)
	(gr_line
		(start 179.416202 -22.001226)
		(end 179.42814 -21.982684)
		(stroke
			(width 0.06985)
			(type default)
		)
		(layer "In5.Cu")
	)
	(gr_arc
		(start 179.83327 -4.335272)
		(mid 179.951127 -4.286482)
		(end 179.999894 -4.168648)
		(stroke
			(width 0.06985)
			(type default)
		)
		(layer "In5.Cu")
	)
	(gr_line
		(start 179.882292 -21.283422)
		(end 179.897786 -21.259546)
		(stroke
			(width 0.06985)
			(type default)
		)
		(layer "In5.Cu")
	)
	(gr_line
		(start 179.897786 -21.259546)
		(end 179.921916 -21.24329)
		(stroke
			(width 0.06985)
			(type default)
		)
		(layer "In5.Cu")
	)
	(gr_line
		(start 179.96662 -14.746478)
		(end 179.992782 -14.741398)
		(stroke
			(width 0.06985)
			(type default)
		)
		(layer "In5.Cu")
	)
	(gr_line
		(start 179.992782 -14.741398)
		(end 180.015134 -14.726412)
		(stroke
			(width 0.06985)
			(type default)
		)
		(layer "In5.Cu")
	)
	(gr_arc
		(start 179.999894 -4.831842)
		(mid 179.951165 -4.714201)
		(end 179.833524 -4.665472)
		(stroke
			(width 0.06985)
			(type default)
		)
		(layer "In5.Cu")
	)
	(gr_line
		(start 179.999894 -4.831842)
		(end 179.999894 -5.200142)
		(stroke
			(width 0.06985)
			(type default)
		)
		(layer "In5.Cu")
	)
	(gr_line
		(start 179.999894 -3.800094)
		(end 179.999894 -4.168648)
		(stroke
			(width 0.06985)
			(type default)
		)
		(layer "In5.Cu")
	)
	(gr_line
		(start 180.251862 -17.228312)
		(end 180.268372 -17.224248)
		(stroke
			(width 0.06985)
			(type default)
		)
		(layer "In5.Cu")
	)
	(gr_line
		(start 180.268372 -17.224248)
		(end 180.281834 -17.215358)
		(stroke
			(width 0.06985)
			(type default)
		)
		(layer "In5.Cu")
	)
	(gr_line
		(start 180.303678 -15.764002)
		(end 180.329332 -15.759176)
		(stroke
			(width 0.06985)
			(type default)
		)
		(layer "In5.Cu")
	)
	(gr_line
		(start 180.329332 -15.759176)
		(end 180.350922 -15.744444)
		(stroke
			(width 0.06985)
			(type default)
		)
		(layer "In5.Cu")
	)
	(gr_arc
		(start 180.436012 -23.596346)
		(mid 180.517863 -23.793878)
		(end 180.715412 -23.875746)
		(stroke
			(width 0.06985)
			(type default)
		)
		(layer "In5.Cu")
	)
	(gr_line
		(start 180.555392 -18.418556)
		(end 180.581046 -18.41373)
		(stroke
			(width 0.06985)
			(type default)
		)
		(layer "In5.Cu")
	)
	(gr_line
		(start 180.581046 -18.41373)
		(end 180.602636 -18.398998)
		(stroke
			(width 0.06985)
			(type default)
		)
		(layer "In5.Cu")
	)
	(gr_line
		(start 180.647086 -14.299438)
		(end 180.669946 -14.283944)
		(stroke
			(width 0.06985)
			(type default)
		)
		(layer "In5.Cu")
	)
	(gr_line
		(start 180.669946 -14.283944)
		(end 180.684932 -14.26083)
		(stroke
			(width 0.06985)
			(type default)
		)
		(layer "In5.Cu")
	)
	(gr_arc
		(start 180.715412 -24.205946)
		(mid 180.517855 -24.287779)
		(end 180.436012 -24.485346)
		(stroke
			(width 0.06985)
			(type default)
		)
		(layer "In5.Cu")
	)
	(gr_line
		(start 180.915564 -13.905738)
		(end 180.926994 -13.887958)
		(stroke
			(width 0.06985)
			(type default)
		)
		(layer "In5.Cu")
	)
	(gr_line
		(start 180.926994 -13.887958)
		(end 180.931312 -13.867638)
		(stroke
			(width 0.06985)
			(type default)
		)
		(layer "In5.Cu")
	)
	(gr_line
		(start 181.547516 -17.360646)
		(end 181.594506 -17.11706)
		(stroke
			(width 0.06985)
			(type default)
		)
		(layer "In5.Cu")
	)
	(gr_line
		(start 181.548024 -19.237706)
		(end 181.572916 -19.232372)
		(stroke
			(width 0.06985)
			(type default)
		)
		(layer "In5.Cu")
	)
	(gr_line
		(start 181.567074 -14.924024)
		(end 181.587648 -14.910054)
		(stroke
			(width 0.06985)
			(type default)
		)
		(layer "In5.Cu")
	)
	(gr_line
		(start 181.572916 -19.232372)
		(end 181.593998 -19.218148)
		(stroke
			(width 0.06985)
			(type default)
		)
		(layer "In5.Cu")
	)
	(gr_line
		(start 181.587648 -14.910054)
		(end 181.601618 -14.88948)
		(stroke
			(width 0.06985)
			(type default)
		)
		(layer "In5.Cu")
	)
	(gr_line
		(start 181.594506 -17.11706)
		(end 181.941978 -16.882872)
		(stroke
			(width 0.06985)
			(type default)
		)
		(layer "In5.Cu")
	)
	(gr_arc
		(start 181.633368 -3.135122)
		(mid 181.751209 -3.08633)
		(end 181.799992 -2.968498)
		(stroke
			(width 0.06985)
			(type default)
		)
		(layer "In5.Cu")
	)
	(gr_line
		(start 181.764686 -17.615408)
		(end 182.340504 -17.227042)
		(stroke
			(width 0.06985)
			(type default)
		)
		(layer "In5.Cu")
	)
	(gr_arc
		(start 181.799992 -3.631692)
		(mid 181.751263 -3.514051)
		(end 181.633622 -3.465322)
		(stroke
			(width 0.06985)
			(type default)
		)
		(layer "In5.Cu")
	)
	(gr_line
		(start 181.799992 -3.631692)
		(end 181.799992 -3.999992)
		(stroke
			(width 0.06985)
			(type default)
		)
		(layer "In5.Cu")
	)
	(gr_line
		(start 181.799992 -2.600198)
		(end 181.799992 -2.968498)
		(stroke
			(width 0.06985)
			(type default)
		)
		(layer "In5.Cu")
	)
	(gr_line
		(start 181.941978 -16.882872)
		(end 182.185564 -16.930116)
		(stroke
			(width 0.06985)
			(type default)
		)
		(layer "In5.Cu")
	)
	(gr_line
		(start 182.536846 -16.693134)
		(end 182.58409 -16.449548)
		(stroke
			(width 0.06985)
			(type default)
		)
		(layer "In5.Cu")
	)
	(gr_line
		(start 182.570628 -13.45311)
		(end 182.575454 -13.446506)
		(stroke
			(width 0.06985)
			(type default)
		)
		(layer "In5.Cu")
	)
	(gr_line
		(start 182.58409 -16.449548)
		(end 182.931562 -16.21536)
		(stroke
			(width 0.06985)
			(type default)
		)
		(layer "In5.Cu")
	)
	(gr_line
		(start 182.597552 -13.413232)
		(end 182.60187 -13.407136)
		(stroke
			(width 0.06985)
			(type default)
		)
		(layer "In5.Cu")
	)
	(gr_line
		(start 182.60187 -13.407136)
		(end 182.604156 -13.39977)
		(stroke
			(width 0.06985)
			(type default)
		)
		(layer "In5.Cu")
	)
	(gr_line
		(start 182.753762 -16.948404)
		(end 183.330596 -16.559276)
		(stroke
			(width 0.06985)
			(type default)
		)
		(layer "In5.Cu")
	)
	(gr_line
		(start 182.86222 -12.568428)
		(end 182.865014 -12.559792)
		(stroke
			(width 0.06985)
			(type default)
		)
		(layer "In5.Cu")
	)
	(gr_line
		(start 182.931562 -16.21536)
		(end 183.175148 -16.262858)
		(stroke
			(width 0.06985)
			(type default)
		)
		(layer "In5.Cu")
	)
	(gr_line
		(start 183.039004 -21.310092)
		(end 183.049672 -21.293836)
		(stroke
			(width 0.06985)
			(type default)
		)
		(layer "In5.Cu")
	)
	(gr_line
		(start 183.049672 -21.293836)
		(end 183.064912 -21.282406)
		(stroke
			(width 0.06985)
			(type default)
		)
		(layer "In5.Cu")
	)
	(gr_line
		(start 183.089042 -17.808448)
		(end 183.13654 -17.564608)
		(stroke
			(width 0.06985)
			(type default)
		)
		(layer "In5.Cu")
	)
	(gr_line
		(start 183.13654 -17.564608)
		(end 183.484012 -17.33042)
		(stroke
			(width 0.06985)
			(type default)
		)
		(layer "In5.Cu")
	)
	(gr_line
		(start 183.258968 -18.989294)
		(end 183.306466 -18.745708)
		(stroke
			(width 0.06985)
			(type default)
		)
		(layer "In5.Cu")
	)
	(gr_line
		(start 183.306466 -18.745708)
		(end 183.653684 -18.511266)
		(stroke
			(width 0.06985)
			(type default)
		)
		(layer "In5.Cu")
	)
	(gr_line
		(start 183.306466 -18.062956)
		(end 183.88203 -17.674844)
		(stroke
			(width 0.06985)
			(type default)
		)
		(layer "In5.Cu")
	)
	(gr_arc
		(start 183.433212 -4.335018)
		(mid 183.551023 -4.28621)
		(end 183.599836 -4.168394)
		(stroke
			(width 0.06985)
			(type default)
		)
		(layer "In5.Cu")
	)
	(gr_line
		(start 183.472582 -19.247104)
		(end 184.055766 -18.853658)
		(stroke
			(width 0.06985)
			(type default)
		)
		(layer "In5.Cu")
	)
	(gr_line
		(start 183.484012 -17.33042)
		(end 183.727598 -17.377664)
		(stroke
			(width 0.06985)
			(type default)
		)
		(layer "In5.Cu")
	)
	(gr_line
		(start 183.52643 -16.025876)
		(end 183.573928 -15.782036)
		(stroke
			(width 0.06985)
			(type default)
		)
		(layer "In5.Cu")
	)
	(gr_line
		(start 183.573928 -15.782036)
		(end 183.9214 -15.547848)
		(stroke
			(width 0.06985)
			(type default)
		)
		(layer "In5.Cu")
	)
	(gr_arc
		(start 183.599836 -4.831842)
		(mid 183.551033 -4.714021)
		(end 183.433212 -4.665218)
		(stroke
			(width 0.06985)
			(type default)
		)
		(layer "In5.Cu")
	)
	(gr_line
		(start 183.599836 -4.831842)
		(end 183.599836 -5.200142)
		(stroke
			(width 0.06985)
			(type default)
		)
		(layer "In5.Cu")
	)
	(gr_line
		(start 183.599836 -3.800094)
		(end 183.599836 -4.168394)
		(stroke
			(width 0.06985)
			(type default)
		)
		(layer "In5.Cu")
	)
	(gr_line
		(start 183.653684 -18.511266)
		(end 183.897524 -18.558764)
		(stroke
			(width 0.06985)
			(type default)
		)
		(layer "In5.Cu")
	)
	(gr_line
		(start 183.743346 -16.280892)
		(end 184.319926 -15.892018)
		(stroke
			(width 0.06985)
			(type default)
		)
		(layer "In5.Cu")
	)
	(gr_line
		(start 183.9214 -15.547848)
		(end 184.164986 -15.595092)
		(stroke
			(width 0.06985)
			(type default)
		)
		(layer "In5.Cu")
	)
	(gr_line
		(start 184.002934 -14.800072)
		(end 184.025794 -14.785086)
		(stroke
			(width 0.06985)
			(type default)
		)
		(layer "In5.Cu")
	)
	(gr_line
		(start 184.025794 -14.785086)
		(end 184.040526 -14.762988)
		(stroke
			(width 0.06985)
			(type default)
		)
		(layer "In5.Cu")
	)
	(gr_line
		(start 184.079134 -17.140682)
		(end 184.126378 -16.897096)
		(stroke
			(width 0.06985)
			(type default)
		)
		(layer "In5.Cu")
	)
	(gr_line
		(start 184.126378 -16.897096)
		(end 184.47385 -16.662908)
		(stroke
			(width 0.06985)
			(type default)
		)
		(layer "In5.Cu")
	)
	(gr_line
		(start 184.248552 -18.321782)
		(end 184.29605 -18.078196)
		(stroke
			(width 0.06985)
			(type default)
		)
		(layer "In5.Cu")
	)
	(gr_line
		(start 184.29605 -18.078196)
		(end 184.643268 -17.843754)
		(stroke
			(width 0.06985)
			(type default)
		)
		(layer "In5.Cu")
	)
	(gr_line
		(start 184.297066 -17.394682)
		(end 184.871106 -17.007586)
		(stroke
			(width 0.06985)
			(type default)
		)
		(layer "In5.Cu")
	)
	(gr_line
		(start 184.462674 -18.579084)
		(end 185.04408 -18.186908)
		(stroke
			(width 0.06985)
			(type default)
		)
		(layer "In5.Cu")
	)
	(gr_line
		(start 184.47385 -16.662908)
		(end 184.717182 -16.710152)
		(stroke
			(width 0.06985)
			(type default)
		)
		(layer "In5.Cu")
	)
	(gr_line
		(start 184.560464 -13.989812)
		(end 184.575196 -13.968222)
		(stroke
			(width 0.06985)
			(type default)
		)
		(layer "In5.Cu")
	)
	(gr_line
		(start 184.575196 -13.968222)
		(end 184.580276 -13.942314)
		(stroke
			(width 0.06985)
			(type default)
		)
		(layer "In5.Cu")
	)
	(gr_line
		(start 184.643268 -17.843754)
		(end 184.887108 -17.891252)
		(stroke
			(width 0.06985)
			(type default)
		)
		(layer "In5.Cu")
	)
	(gr_line
		(start 184.733184 -15.61338)
		(end 184.753758 -15.59941)
		(stroke
			(width 0.06985)
			(type default)
		)
		(layer "In5.Cu")
	)
	(gr_line
		(start 184.753758 -15.59941)
		(end 184.767728 -15.578836)
		(stroke
			(width 0.06985)
			(type default)
		)
		(layer "In5.Cu")
	)
	(gr_line
		(start 185.068972 -16.47317)
		(end 185.116216 -16.229584)
		(stroke
			(width 0.06985)
			(type default)
		)
		(layer "In5.Cu")
	)
	(gr_line
		(start 185.077354 -19.757644)
		(end 185.11139 -19.512026)
		(stroke
			(width 0.06985)
			(type default)
		)
		(layer "In5.Cu")
	)
	(gr_line
		(start 185.11139 -19.512026)
		(end 185.445654 -19.259296)
		(stroke
			(width 0.06985)
			(type default)
		)
		(layer "In5.Cu")
	)
	(gr_line
		(start 185.116216 -16.229584)
		(end 185.463688 -15.995142)
		(stroke
			(width 0.06985)
			(type default)
		)
		(layer "In5.Cu")
	)
	(gr_arc
		(start 185.23331 -3.135122)
		(mid 185.351131 -3.086319)
		(end 185.399934 -2.968498)
		(stroke
			(width 0.06985)
			(type default)
		)
		(layer "In5.Cu")
	)
	(gr_line
		(start 185.238136 -17.65427)
		(end 185.28538 -17.41043)
		(stroke
			(width 0.06985)
			(type default)
		)
		(layer "In5.Cu")
	)
	(gr_line
		(start 185.28538 -17.41043)
		(end 185.632852 -17.175988)
		(stroke
			(width 0.06985)
			(type default)
		)
		(layer "In5.Cu")
	)
	(gr_line
		(start 185.286396 -16.727678)
		(end 185.862214 -16.339312)
		(stroke
			(width 0.06985)
			(type default)
		)
		(layer "In5.Cu")
	)
	(gr_line
		(start 185.307986 -20.000468)
		(end 185.863738 -19.580606)
		(stroke
			(width 0.06985)
			(type default)
		)
		(layer "In5.Cu")
	)
	(gr_arc
		(start 185.399934 -3.631692)
		(mid 185.3512 -3.514069)
		(end 185.233564 -3.465322)
		(stroke
			(width 0.06985)
			(type default)
		)
		(layer "In5.Cu")
	)
	(gr_line
		(start 185.399934 -3.631692)
		(end 185.399934 -3.999992)
		(stroke
			(width 0.06985)
			(type default)
		)
		(layer "In5.Cu")
	)
	(gr_line
		(start 185.399934 -2.600198)
		(end 185.399934 -2.968498)
		(stroke
			(width 0.06985)
			(type default)
		)
		(layer "In5.Cu")
	)
	(gr_line
		(start 185.445654 -19.259296)
		(end 185.69178 -19.293332)
		(stroke
			(width 0.06985)
			(type default)
		)
		(layer "In5.Cu")
	)
	(gr_line
		(start 185.453528 -17.910556)
		(end 186.034426 -17.518634)
		(stroke
			(width 0.06985)
			(type default)
		)
		(layer "In5.Cu")
	)
	(gr_line
		(start 185.463688 -15.995142)
		(end 185.707274 -16.042386)
		(stroke
			(width 0.06985)
			(type default)
		)
		(layer "In5.Cu")
	)
	(gr_line
		(start 185.632852 -17.175988)
		(end 185.876692 -17.223486)
		(stroke
			(width 0.06985)
			(type default)
		)
		(layer "In5.Cu")
	)
	(gr_line
		(start 186.0296 -19.038062)
		(end 186.063636 -18.79219)
		(stroke
			(width 0.06985)
			(type default)
		)
		(layer "In5.Cu")
	)
	(gr_line
		(start 186.063636 -18.79219)
		(end 186.3979 -18.53946)
		(stroke
			(width 0.06985)
			(type default)
		)
		(layer "In5.Cu")
	)
	(gr_line
		(start 186.182508 -13.480796)
		(end 186.19724 -13.459206)
		(stroke
			(width 0.06985)
			(type default)
		)
		(layer "In5.Cu")
	)
	(gr_line
		(start 186.19724 -13.459206)
		(end 186.202066 -13.433552)
		(stroke
			(width 0.06985)
			(type default)
		)
		(layer "In5.Cu")
	)
	(gr_line
		(start 186.258708 -19.281902)
		(end 186.815476 -18.861024)
		(stroke
			(width 0.06985)
			(type default)
		)
		(layer "In5.Cu")
	)
	(gr_line
		(start 186.3979 -18.53946)
		(end 186.643772 -18.573496)
		(stroke
			(width 0.06985)
			(type default)
		)
		(layer "In5.Cu")
	)
	(gr_line
		(start 186.981846 -18.317972)
		(end 187.015882 -18.072354)
		(stroke
			(width 0.06985)
			(type default)
		)
		(layer "In5.Cu")
	)
	(gr_line
		(start 187.015882 -18.072354)
		(end 187.350146 -17.819624)
		(stroke
			(width 0.06985)
			(type default)
		)
		(layer "In5.Cu")
	)
	(gr_arc
		(start 187.033154 -4.335018)
		(mid 187.150975 -4.286215)
		(end 187.199778 -4.168394)
		(stroke
			(width 0.06985)
			(type default)
		)
		(layer "In5.Cu")
	)
	(gr_line
		(start 187.035694 -15.547594)
		(end 187.057538 -15.533116)
		(stroke
			(width 0.06985)
			(type default)
		)
		(layer "In5.Cu")
	)
	(gr_line
		(start 187.057538 -15.533116)
		(end 187.072524 -15.510002)
		(stroke
			(width 0.06985)
			(type default)
		)
		(layer "In5.Cu")
	)
	(gr_arc
		(start 187.199778 -4.831842)
		(mid 187.150975 -4.714021)
		(end 187.033154 -4.665218)
		(stroke
			(width 0.06985)
			(type default)
		)
		(layer "In5.Cu")
	)
	(gr_line
		(start 187.199778 -4.831842)
		(end 187.199778 -5.200142)
		(stroke
			(width 0.06985)
			(type default)
		)
		(layer "In5.Cu")
	)
	(gr_line
		(start 187.199778 -3.800094)
		(end 187.199778 -4.168394)
		(stroke
			(width 0.06985)
			(type default)
		)
		(layer "In5.Cu")
	)
	(gr_line
		(start 187.21197 -18.56105)
		(end 187.767468 -18.141188)
		(stroke
			(width 0.06985)
			(type default)
		)
		(layer "In5.Cu")
	)
	(gr_line
		(start 187.350146 -17.819624)
		(end 187.596018 -17.85366)
		(stroke
			(width 0.06985)
			(type default)
		)
		(layer "In5.Cu")
	)
	(gr_line
		(start 188.058298 -16.15313)
		(end 188.082428 -16.136874)
		(stroke
			(width 0.06985)
			(type default)
		)
		(layer "In5.Cu")
	)
	(gr_line
		(start 188.082428 -16.136874)
		(end 188.097922 -16.112998)
		(stroke
			(width 0.06985)
			(type default)
		)
		(layer "In5.Cu")
	)
	(gr_line
		(start 188.084206 -13.95095)
		(end 188.095636 -13.93317)
		(stroke
			(width 0.06985)
			(type default)
		)
		(layer "In5.Cu")
	)
	(gr_line
		(start 188.095636 -13.93317)
		(end 188.099954 -13.91285)
		(stroke
			(width 0.06985)
			(type default)
		)
		(layer "In5.Cu")
	)
	(gr_arc
		(start 188.833252 -3.135122)
		(mid 188.951103 -3.086336)
		(end 188.999876 -2.968498)
		(stroke
			(width 0.06985)
			(type default)
		)
		(layer "In5.Cu")
	)
	(gr_arc
		(start 188.999876 -3.631692)
		(mid 188.951147 -3.514051)
		(end 188.833506 -3.465322)
		(stroke
			(width 0.06985)
			(type default)
		)
		(layer "In5.Cu")
	)
	(gr_line
		(start 188.999876 -3.631692)
		(end 188.999876 -3.999992)
		(stroke
			(width 0.06985)
			(type default)
		)
		(layer "In5.Cu")
	)
	(gr_line
		(start 188.999876 -2.600198)
		(end 188.999876 -2.968498)
		(stroke
			(width 0.06985)
			(type default)
		)
		(layer "In5.Cu")
	)
	(gr_line
		(start 189.690248 -13.662406)
		(end 189.701678 -13.644626)
		(stroke
			(width 0.06985)
			(type default)
		)
		(layer "In5.Cu")
	)
	(gr_line
		(start 189.701678 -13.644626)
		(end 189.705996 -13.624306)
		(stroke
			(width 0.06985)
			(type default)
		)
		(layer "In5.Cu")
	)
	(gr_line
		(start 189.929262 -16.506698)
		(end 189.944502 -16.495268)
		(stroke
			(width 0.06985)
			(type default)
		)
		(layer "In5.Cu")
	)
	(gr_line
		(start 189.944502 -16.495268)
		(end 189.95517 -16.479012)
		(stroke
			(width 0.06985)
			(type default)
		)
		(layer "In5.Cu")
	)
	(gr_arc
		(start 190.63335 -4.335018)
		(mid 190.751201 -4.286232)
		(end 190.799974 -4.168394)
		(stroke
			(width 0.06985)
			(type default)
		)
		(layer "In5.Cu")
	)
	(gr_arc
		(start 190.799974 -4.831842)
		(mid 190.751171 -4.714021)
		(end 190.63335 -4.665218)
		(stroke
			(width 0.06985)
			(type default)
		)
		(layer "In5.Cu")
	)
	(gr_line
		(start 190.799974 -4.831842)
		(end 190.799974 -5.200142)
		(stroke
			(width 0.06985)
			(type default)
		)
		(layer "In5.Cu")
	)
	(gr_line
		(start 190.799974 -3.800094)
		(end 190.799974 -4.168394)
		(stroke
			(width 0.06985)
			(type default)
		)
		(layer "In5.Cu")
	)
	(gr_line
		(start 191.715136 -13.768578)
		(end 191.726566 -13.750798)
		(stroke
			(width 0.06985)
			(type default)
		)
		(layer "In5.Cu")
	)
	(gr_line
		(start 191.726566 -13.750798)
		(end 191.730884 -13.730478)
		(stroke
			(width 0.06985)
			(type default)
		)
		(layer "In5.Cu")
	)
	(gr_arc
		(start 192.433194 -3.135122)
		(mid 192.551018 -3.086321)
		(end 192.599818 -2.968498)
		(stroke
			(width 0.06985)
			(type default)
		)
		(layer "In5.Cu")
	)
	(gr_arc
		(start 192.599818 -3.631692)
		(mid 192.551089 -3.514039)
		(end 192.433448 -3.465322)
		(stroke
			(width 0.06985)
			(type default)
		)
		(layer "In5.Cu")
	)
	(gr_line
		(start 192.599818 -3.631692)
		(end 192.599818 -3.999992)
		(stroke
			(width 0.06985)
			(type default)
		)
		(layer "In5.Cu")
	)
	(gr_line
		(start 192.599818 -2.600198)
		(end 192.599818 -2.968498)
		(stroke
			(width 0.06985)
			(type default)
		)
		(layer "In5.Cu")
	)
	(gr_line
		(start 0 -142.999968)
		(end 0 -1.999996)
		(stroke
			(width 1.524)
			(type default)
		)
		(layer "In6.Cu")
	)
	(gr_arc
		(start 0 -142.999968)
		(mid 0.585785 -144.414179)
		(end 1.999996 -144.999964)
		(stroke
			(width 1.524)
			(type default)
		)
		(layer "In6.Cu")
	)
	(gr_arc
		(start 1.999996 0)
		(mid 0.585785 -0.585785)
		(end 0 -1.999996)
		(stroke
			(width 1.524)
			(type default)
		)
		(layer "In6.Cu")
	)
	(gr_line
		(start 1.999996 0)
		(end 208.000092 0)
		(stroke
			(width 1.524)
			(type default)
		)
		(layer "In6.Cu")
	)
	(gr_line
		(start 83.002374 -144.999964)
		(end 1.999996 -144.999964)
		(stroke
			(width 1.524)
			(type default)
		)
		(layer "In6.Cu")
	)
	(gr_arc
		(start 83.002374 -144.999964)
		(mid 84.41672 -144.414257)
		(end 85.002624 -142.999968)
		(stroke
			(width 1.524)
			(type default)
		)
		(layer "In6.Cu")
	)
	(gr_line
		(start 85.002624 -132.26288)
		(end 85.002624 -142.999968)
		(stroke
			(width 1.524)
			(type default)
		)
		(layer "In6.Cu")
	)
	(gr_arc
		(start 85.438742 -12.399772)
		(mid 85.999955 -12.961366)
		(end 86.561422 -12.400026)
		(stroke
			(width 0.2)
			(type default)
		)
		(layer "In6.Cu")
	)
	(gr_line
		(start 85.438742 -10.999978)
		(end 85.438742 -12.399772)
		(stroke
			(width 0.2)
			(type default)
		)
		(layer "In6.Cu")
	)
	(gr_arc
		(start 85.438742 -5.199888)
		(mid 85.999955 -5.761482)
		(end 86.561422 -5.200142)
		(stroke
			(width 0.2)
			(type default)
		)
		(layer "In6.Cu")
	)
	(gr_line
		(start 85.438742 -3.800094)
		(end 85.438742 -5.199888)
		(stroke
			(width 0.2)
			(type default)
		)
		(layer "In6.Cu")
	)
	(gr_line
		(start 86.561422 -12.400026)
		(end 86.561422 -10.999978)
		(stroke
			(width 0.2)
			(type default)
		)
		(layer "In6.Cu")
	)
	(gr_arc
		(start 86.561422 -10.999978)
		(mid 86.000082 -10.438638)
		(end 85.438742 -10.999978)
		(stroke
			(width 0.2)
			(type default)
		)
		(layer "In6.Cu")
	)
	(gr_line
		(start 86.561422 -5.200142)
		(end 86.561422 -3.800094)
		(stroke
			(width 0.2)
			(type default)
		)
		(layer "In6.Cu")
	)
	(gr_arc
		(start 86.561422 -3.800094)
		(mid 86.000082 -3.238754)
		(end 85.438742 -3.800094)
		(stroke
			(width 0.2)
			(type default)
		)
		(layer "In6.Cu")
	)
	(gr_arc
		(start 87.23884 -11.199876)
		(mid 87.800053 -11.76147)
		(end 88.36152 -11.20013)
		(stroke
			(width 0.2)
			(type default)
		)
		(layer "In6.Cu")
	)
	(gr_line
		(start 87.23884 -9.800082)
		(end 87.23884 -11.199876)
		(stroke
			(width 0.2)
			(type default)
		)
		(layer "In6.Cu")
	)
	(gr_arc
		(start 87.23884 -3.999738)
		(mid 87.800053 -4.561332)
		(end 88.36152 -3.999992)
		(stroke
			(width 0.2)
			(type default)
		)
		(layer "In6.Cu")
	)
	(gr_line
		(start 87.23884 -2.600198)
		(end 87.23884 -3.999738)
		(stroke
			(width 0.2)
			(type default)
		)
		(layer "In6.Cu")
	)
	(gr_line
		(start 88.36152 -11.20013)
		(end 88.36152 -9.800082)
		(stroke
			(width 0.2)
			(type default)
		)
		(layer "In6.Cu")
	)
	(gr_arc
		(start 88.36152 -9.800082)
		(mid 87.80018 -9.238742)
		(end 87.23884 -9.800082)
		(stroke
			(width 0.2)
			(type default)
		)
		(layer "In6.Cu")
	)
	(gr_line
		(start 88.36152 -3.999992)
		(end 88.36152 -2.600198)
		(stroke
			(width 0.2)
			(type default)
		)
		(layer "In6.Cu")
	)
	(gr_arc
		(start 88.36152 -2.600198)
		(mid 87.80018 -2.038858)
		(end 87.23884 -2.600198)
		(stroke
			(width 0.2)
			(type default)
		)
		(layer "In6.Cu")
	)
	(gr_arc
		(start 89.038684 -12.399772)
		(mid 89.599897 -12.961366)
		(end 90.161364 -12.400026)
		(stroke
			(width 0.2)
			(type default)
		)
		(layer "In6.Cu")
	)
	(gr_line
		(start 89.038684 -10.999978)
		(end 89.038684 -12.399772)
		(stroke
			(width 0.2)
			(type default)
		)
		(layer "In6.Cu")
	)
	(gr_arc
		(start 89.038684 -5.199888)
		(mid 89.599897 -5.761482)
		(end 90.161364 -5.200142)
		(stroke
			(width 0.2)
			(type default)
		)
		(layer "In6.Cu")
	)
	(gr_line
		(start 89.038684 -3.800094)
		(end 89.038684 -5.199888)
		(stroke
			(width 0.2)
			(type default)
		)
		(layer "In6.Cu")
	)
	(gr_arc
		(start 89.212674 -127.325628)
		(mid 86.197998 -129.018598)
		(end 85.002624 -132.26288)
		(stroke
			(width 1.524)
			(type default)
		)
		(layer "In6.Cu")
	)
	(gr_line
		(start 90.161364 -12.400026)
		(end 90.161364 -10.999978)
		(stroke
			(width 0.2)
			(type default)
		)
		(layer "In6.Cu")
	)
	(gr_arc
		(start 90.161364 -10.999978)
		(mid 89.600024 -10.438638)
		(end 89.038684 -10.999978)
		(stroke
			(width 0.2)
			(type default)
		)
		(layer "In6.Cu")
	)
	(gr_line
		(start 90.161364 -5.200142)
		(end 90.161364 -3.800094)
		(stroke
			(width 0.2)
			(type default)
		)
		(layer "In6.Cu")
	)
	(gr_arc
		(start 90.161364 -3.800094)
		(mid 89.600024 -3.238754)
		(end 89.038684 -3.800094)
		(stroke
			(width 0.2)
			(type default)
		)
		(layer "In6.Cu")
	)
	(gr_arc
		(start 90.838782 -11.199876)
		(mid 91.399995 -11.76147)
		(end 91.961462 -11.20013)
		(stroke
			(width 0.2)
			(type default)
		)
		(layer "In6.Cu")
	)
	(gr_line
		(start 90.838782 -9.800082)
		(end 90.838782 -11.199876)
		(stroke
			(width 0.2)
			(type default)
		)
		(layer "In6.Cu")
	)
	(gr_arc
		(start 90.838782 -3.999738)
		(mid 91.399995 -4.561332)
		(end 91.961462 -3.999992)
		(stroke
			(width 0.2)
			(type default)
		)
		(layer "In6.Cu")
	)
	(gr_line
		(start 90.838782 -2.600198)
		(end 90.838782 -3.999738)
		(stroke
			(width 0.2)
			(type default)
		)
		(layer "In6.Cu")
	)
	(gr_line
		(start 91.961462 -11.20013)
		(end 91.961462 -9.800082)
		(stroke
			(width 0.2)
			(type default)
		)
		(layer "In6.Cu")
	)
	(gr_arc
		(start 91.961462 -9.800082)
		(mid 91.400122 -9.238742)
		(end 90.838782 -9.800082)
		(stroke
			(width 0.2)
			(type default)
		)
		(layer "In6.Cu")
	)
	(gr_line
		(start 91.961462 -3.999992)
		(end 91.961462 -2.600198)
		(stroke
			(width 0.2)
			(type default)
		)
		(layer "In6.Cu")
	)
	(gr_arc
		(start 91.961462 -2.600198)
		(mid 91.400122 -2.038858)
		(end 90.838782 -2.600198)
		(stroke
			(width 0.2)
			(type default)
		)
		(layer "In6.Cu")
	)
	(gr_arc
		(start 92.638626 -12.399772)
		(mid 93.199839 -12.961366)
		(end 93.761306 -12.400026)
		(stroke
			(width 0.2)
			(type default)
		)
		(layer "In6.Cu")
	)
	(gr_line
		(start 92.638626 -10.999978)
		(end 92.638626 -12.399772)
		(stroke
			(width 0.2)
			(type default)
		)
		(layer "In6.Cu")
	)
	(gr_arc
		(start 92.638626 -5.199888)
		(mid 93.199839 -5.761482)
		(end 93.761306 -5.200142)
		(stroke
			(width 0.2)
			(type default)
		)
		(layer "In6.Cu")
	)
	(gr_line
		(start 92.638626 -3.800094)
		(end 92.638626 -5.199888)
		(stroke
			(width 0.2)
			(type default)
		)
		(layer "In6.Cu")
	)
	(gr_line
		(start 93.761306 -12.400026)
		(end 93.761306 -10.999978)
		(stroke
			(width 0.2)
			(type default)
		)
		(layer "In6.Cu")
	)
	(gr_arc
		(start 93.761306 -10.999978)
		(mid 93.199966 -10.438638)
		(end 92.638626 -10.999978)
		(stroke
			(width 0.2)
			(type default)
		)
		(layer "In6.Cu")
	)
	(gr_line
		(start 93.761306 -5.200142)
		(end 93.761306 -3.800094)
		(stroke
			(width 0.2)
			(type default)
		)
		(layer "In6.Cu")
	)
	(gr_arc
		(start 93.761306 -3.800094)
		(mid 93.199966 -3.238754)
		(end 92.638626 -3.800094)
		(stroke
			(width 0.2)
			(type default)
		)
		(layer "In6.Cu")
	)
	(gr_arc
		(start 94.438724 -11.199876)
		(mid 94.999937 -11.76147)
		(end 95.561404 -11.20013)
		(stroke
			(width 0.2)
			(type default)
		)
		(layer "In6.Cu")
	)
	(gr_line
		(start 94.438724 -9.800082)
		(end 94.438724 -11.199876)
		(stroke
			(width 0.2)
			(type default)
		)
		(layer "In6.Cu")
	)
	(gr_arc
		(start 94.438724 -3.999738)
		(mid 94.999937 -4.561332)
		(end 95.561404 -3.999992)
		(stroke
			(width 0.2)
			(type default)
		)
		(layer "In6.Cu")
	)
	(gr_line
		(start 94.438724 -2.600198)
		(end 94.438724 -3.999738)
		(stroke
			(width 0.2)
			(type default)
		)
		(layer "In6.Cu")
	)
	(gr_line
		(start 95.561404 -11.20013)
		(end 95.561404 -9.800082)
		(stroke
			(width 0.2)
			(type default)
		)
		(layer "In6.Cu")
	)
	(gr_arc
		(start 95.561404 -9.800082)
		(mid 95.000064 -9.238742)
		(end 94.438724 -9.800082)
		(stroke
			(width 0.2)
			(type default)
		)
		(layer "In6.Cu")
	)
	(gr_line
		(start 95.561404 -3.999992)
		(end 95.561404 -2.600198)
		(stroke
			(width 0.2)
			(type default)
		)
		(layer "In6.Cu")
	)
	(gr_arc
		(start 95.561404 -2.600198)
		(mid 95.000064 -2.038858)
		(end 94.438724 -2.600198)
		(stroke
			(width 0.2)
			(type default)
		)
		(layer "In6.Cu")
	)
	(gr_arc
		(start 96.040194 -55.242968)
		(mid 96.055073 -55.278889)
		(end 96.090994 -55.293768)
		(stroke
			(width 0.2)
			(type default)
		)
		(layer "In6.Cu")
	)
	(gr_line
		(start 96.040194 -55.039768)
		(end 96.040194 -55.242968)
		(stroke
			(width 0.2)
			(type default)
		)
		(layer "In6.Cu")
	)
	(gr_arc
		(start 96.040194 -54.658768)
		(mid 96.055073 -54.694689)
		(end 96.090994 -54.709568)
		(stroke
			(width 0.2)
			(type default)
		)
		(layer "In6.Cu")
	)
	(gr_line
		(start 96.040194 -54.455568)
		(end 96.040194 -54.658768)
		(stroke
			(width 0.2)
			(type default)
		)
		(layer "In6.Cu")
	)
	(gr_arc
		(start 96.040194 -53.845968)
		(mid 96.055073 -53.881889)
		(end 96.090994 -53.896768)
		(stroke
			(width 0.2)
			(type default)
		)
		(layer "In6.Cu")
	)
	(gr_line
		(start 96.040194 -53.642768)
		(end 96.040194 -53.845968)
		(stroke
			(width 0.2)
			(type default)
		)
		(layer "In6.Cu")
	)
	(gr_arc
		(start 96.040194 -53.261768)
		(mid 96.055073 -53.297689)
		(end 96.090994 -53.312568)
		(stroke
			(width 0.2)
			(type default)
		)
		(layer "In6.Cu")
	)
	(gr_line
		(start 96.040194 -53.058568)
		(end 96.040194 -53.261768)
		(stroke
			(width 0.2)
			(type default)
		)
		(layer "In6.Cu")
	)
	(gr_arc
		(start 96.040194 -52.448968)
		(mid 96.055073 -52.484889)
		(end 96.090994 -52.499768)
		(stroke
			(width 0.2)
			(type default)
		)
		(layer "In6.Cu")
	)
	(gr_line
		(start 96.040194 -52.245768)
		(end 96.040194 -52.448968)
		(stroke
			(width 0.2)
			(type default)
		)
		(layer "In6.Cu")
	)
	(gr_arc
		(start 96.040194 -51.864768)
		(mid 96.055073 -51.900689)
		(end 96.090994 -51.915568)
		(stroke
			(width 0.2)
			(type default)
		)
		(layer "In6.Cu")
	)
	(gr_line
		(start 96.040194 -51.661568)
		(end 96.040194 -51.864768)
		(stroke
			(width 0.2)
			(type default)
		)
		(layer "In6.Cu")
	)
	(gr_arc
		(start 96.040194 -51.051968)
		(mid 96.055073 -51.087889)
		(end 96.090994 -51.102768)
		(stroke
			(width 0.2)
			(type default)
		)
		(layer "In6.Cu")
	)
	(gr_line
		(start 96.040194 -50.848768)
		(end 96.040194 -51.051968)
		(stroke
			(width 0.2)
			(type default)
		)
		(layer "In6.Cu")
	)
	(gr_arc
		(start 96.040194 -50.467768)
		(mid 96.055073 -50.503689)
		(end 96.090994 -50.518568)
		(stroke
			(width 0.2)
			(type default)
		)
		(layer "In6.Cu")
	)
	(gr_line
		(start 96.040194 -50.264568)
		(end 96.040194 -50.467768)
		(stroke
			(width 0.2)
			(type default)
		)
		(layer "In6.Cu")
	)
	(gr_line
		(start 96.090994 -55.293768)
		(end 96.903794 -55.293768)
		(stroke
			(width 0.2)
			(type default)
		)
		(layer "In6.Cu")
	)
	(gr_arc
		(start 96.090994 -54.988968)
		(mid 96.055073 -55.003847)
		(end 96.040194 -55.039768)
		(stroke
			(width 0.2)
			(type default)
		)
		(layer "In6.Cu")
	)
	(gr_line
		(start 96.090994 -54.709568)
		(end 96.903794 -54.709568)
		(stroke
			(width 0.2)
			(type default)
		)
		(layer "In6.Cu")
	)
	(gr_arc
		(start 96.090994 -54.404768)
		(mid 96.055073 -54.419647)
		(end 96.040194 -54.455568)
		(stroke
			(width 0.2)
			(type default)
		)
		(layer "In6.Cu")
	)
	(gr_line
		(start 96.090994 -53.896768)
		(end 96.903794 -53.896768)
		(stroke
			(width 0.2)
			(type default)
		)
		(layer "In6.Cu")
	)
	(gr_arc
		(start 96.090994 -53.591968)
		(mid 96.055073 -53.606847)
		(end 96.040194 -53.642768)
		(stroke
			(width 0.2)
			(type default)
		)
		(layer "In6.Cu")
	)
	(gr_line
		(start 96.090994 -53.312568)
		(end 96.903794 -53.312568)
		(stroke
			(width 0.2)
			(type default)
		)
		(layer "In6.Cu")
	)
	(gr_arc
		(start 96.090994 -53.007768)
		(mid 96.055073 -53.022647)
		(end 96.040194 -53.058568)
		(stroke
			(width 0.2)
			(type default)
		)
		(layer "In6.Cu")
	)
	(gr_line
		(start 96.090994 -52.499768)
		(end 96.903794 -52.499768)
		(stroke
			(width 0.2)
			(type default)
		)
		(layer "In6.Cu")
	)
	(gr_arc
		(start 96.090994 -52.194968)
		(mid 96.055073 -52.209847)
		(end 96.040194 -52.245768)
		(stroke
			(width 0.2)
			(type default)
		)
		(layer "In6.Cu")
	)
	(gr_line
		(start 96.090994 -51.915568)
		(end 96.903794 -51.915568)
		(stroke
			(width 0.2)
			(type default)
		)
		(layer "In6.Cu")
	)
	(gr_arc
		(start 96.090994 -51.610768)
		(mid 96.055073 -51.625647)
		(end 96.040194 -51.661568)
		(stroke
			(width 0.2)
			(type default)
		)
		(layer "In6.Cu")
	)
	(gr_line
		(start 96.090994 -51.102768)
		(end 96.903794 -51.102768)
		(stroke
			(width 0.2)
			(type default)
		)
		(layer "In6.Cu")
	)
	(gr_arc
		(start 96.090994 -50.797968)
		(mid 96.055073 -50.812847)
		(end 96.040194 -50.848768)
		(stroke
			(width 0.2)
			(type default)
		)
		(layer "In6.Cu")
	)
	(gr_line
		(start 96.090994 -50.518568)
		(end 96.903794 -50.518568)
		(stroke
			(width 0.2)
			(type default)
		)
		(layer "In6.Cu")
	)
	(gr_arc
		(start 96.090994 -50.213768)
		(mid 96.055073 -50.228647)
		(end 96.040194 -50.264568)
		(stroke
			(width 0.2)
			(type default)
		)
		(layer "In6.Cu")
	)
	(gr_arc
		(start 96.238822 -12.399772)
		(mid 96.800035 -12.961366)
		(end 97.361502 -12.400026)
		(stroke
			(width 0.2)
			(type default)
		)
		(layer "In6.Cu")
	)
	(gr_line
		(start 96.238822 -10.999978)
		(end 96.238822 -12.399772)
		(stroke
			(width 0.2)
			(type default)
		)
		(layer "In6.Cu")
	)
	(gr_arc
		(start 96.238822 -5.199888)
		(mid 96.800035 -5.761482)
		(end 97.361502 -5.200142)
		(stroke
			(width 0.2)
			(type default)
		)
		(layer "In6.Cu")
	)
	(gr_line
		(start 96.238822 -3.800094)
		(end 96.238822 -5.199888)
		(stroke
			(width 0.2)
			(type default)
		)
		(layer "In6.Cu")
	)
	(gr_arc
		(start 96.4946 -44.6278)
		(mid 96.509479 -44.663721)
		(end 96.5454 -44.6786)
		(stroke
			(width 0.2)
			(type default)
		)
		(layer "In6.Cu")
	)
	(gr_line
		(start 96.4946 -43.815)
		(end 96.4946 -44.6278)
		(stroke
			(width 0.2)
			(type default)
		)
		(layer "In6.Cu")
	)
	(gr_line
		(start 96.5454 -44.6786)
		(end 96.7486 -44.6786)
		(stroke
			(width 0.2)
			(type default)
		)
		(layer "In6.Cu")
	)
	(gr_arc
		(start 96.5454 -43.7642)
		(mid 96.509479 -43.779079)
		(end 96.4946 -43.815)
		(stroke
			(width 0.2)
			(type default)
		)
		(layer "In6.Cu")
	)
	(gr_arc
		(start 96.7486 -44.6786)
		(mid 96.784521 -44.663721)
		(end 96.7994 -44.6278)
		(stroke
			(width 0.2)
			(type default)
		)
		(layer "In6.Cu")
	)
	(gr_line
		(start 96.7486 -43.7642)
		(end 96.5454 -43.7642)
		(stroke
			(width 0.2)
			(type default)
		)
		(layer "In6.Cu")
	)
	(gr_line
		(start 96.7994 -44.6278)
		(end 96.7994 -43.815)
		(stroke
			(width 0.2)
			(type default)
		)
		(layer "In6.Cu")
	)
	(gr_arc
		(start 96.7994 -43.815)
		(mid 96.784521 -43.779079)
		(end 96.7486 -43.7642)
		(stroke
			(width 0.2)
			(type default)
		)
		(layer "In6.Cu")
	)
	(gr_arc
		(start 96.903794 -55.293768)
		(mid 96.939715 -55.278889)
		(end 96.954594 -55.242968)
		(stroke
			(width 0.2)
			(type default)
		)
		(layer "In6.Cu")
	)
	(gr_line
		(start 96.903794 -54.988968)
		(end 96.090994 -54.988968)
		(stroke
			(width 0.2)
			(type default)
		)
		(layer "In6.Cu")
	)
	(gr_arc
		(start 96.903794 -54.709568)
		(mid 96.939715 -54.694689)
		(end 96.954594 -54.658768)
		(stroke
			(width 0.2)
			(type default)
		)
		(layer "In6.Cu")
	)
	(gr_line
		(start 96.903794 -54.404768)
		(end 96.090994 -54.404768)
		(stroke
			(width 0.2)
			(type default)
		)
		(layer "In6.Cu")
	)
	(gr_arc
		(start 96.903794 -53.896768)
		(mid 96.939715 -53.881889)
		(end 96.954594 -53.845968)
		(stroke
			(width 0.2)
			(type default)
		)
		(layer "In6.Cu")
	)
	(gr_line
		(start 96.903794 -53.591968)
		(end 96.090994 -53.591968)
		(stroke
			(width 0.2)
			(type default)
		)
		(layer "In6.Cu")
	)
	(gr_arc
		(start 96.903794 -53.312568)
		(mid 96.939715 -53.297689)
		(end 96.954594 -53.261768)
		(stroke
			(width 0.2)
			(type default)
		)
		(layer "In6.Cu")
	)
	(gr_line
		(start 96.903794 -53.007768)
		(end 96.090994 -53.007768)
		(stroke
			(width 0.2)
			(type default)
		)
		(layer "In6.Cu")
	)
	(gr_arc
		(start 96.903794 -52.499768)
		(mid 96.939715 -52.484889)
		(end 96.954594 -52.448968)
		(stroke
			(width 0.2)
			(type default)
		)
		(layer "In6.Cu")
	)
	(gr_line
		(start 96.903794 -52.194968)
		(end 96.090994 -52.194968)
		(stroke
			(width 0.2)
			(type default)
		)
		(layer "In6.Cu")
	)
	(gr_arc
		(start 96.903794 -51.915568)
		(mid 96.939715 -51.900689)
		(end 96.954594 -51.864768)
		(stroke
			(width 0.2)
			(type default)
		)
		(layer "In6.Cu")
	)
	(gr_line
		(start 96.903794 -51.610768)
		(end 96.090994 -51.610768)
		(stroke
			(width 0.2)
			(type default)
		)
		(layer "In6.Cu")
	)
	(gr_arc
		(start 96.903794 -51.102768)
		(mid 96.939715 -51.087889)
		(end 96.954594 -51.051968)
		(stroke
			(width 0.2)
			(type default)
		)
		(layer "In6.Cu")
	)
	(gr_line
		(start 96.903794 -50.797968)
		(end 96.090994 -50.797968)
		(stroke
			(width 0.2)
			(type default)
		)
		(layer "In6.Cu")
	)
	(gr_arc
		(start 96.903794 -50.518568)
		(mid 96.939715 -50.503689)
		(end 96.954594 -50.467768)
		(stroke
			(width 0.2)
			(type default)
		)
		(layer "In6.Cu")
	)
	(gr_line
		(start 96.903794 -50.213768)
		(end 96.090994 -50.213768)
		(stroke
			(width 0.2)
			(type default)
		)
		(layer "In6.Cu")
	)
	(gr_line
		(start 96.954594 -55.242968)
		(end 96.954594 -55.039768)
		(stroke
			(width 0.2)
			(type default)
		)
		(layer "In6.Cu")
	)
	(gr_arc
		(start 96.954594 -55.039768)
		(mid 96.939715 -55.003847)
		(end 96.903794 -54.988968)
		(stroke
			(width 0.2)
			(type default)
		)
		(layer "In6.Cu")
	)
	(gr_line
		(start 96.954594 -54.658768)
		(end 96.954594 -54.455568)
		(stroke
			(width 0.2)
			(type default)
		)
		(layer "In6.Cu")
	)
	(gr_arc
		(start 96.954594 -54.455568)
		(mid 96.939715 -54.419647)
		(end 96.903794 -54.404768)
		(stroke
			(width 0.2)
			(type default)
		)
		(layer "In6.Cu")
	)
	(gr_line
		(start 96.954594 -53.845968)
		(end 96.954594 -53.642768)
		(stroke
			(width 0.2)
			(type default)
		)
		(layer "In6.Cu")
	)
	(gr_arc
		(start 96.954594 -53.642768)
		(mid 96.939715 -53.606847)
		(end 96.903794 -53.591968)
		(stroke
			(width 0.2)
			(type default)
		)
		(layer "In6.Cu")
	)
	(gr_line
		(start 96.954594 -53.261768)
		(end 96.954594 -53.058568)
		(stroke
			(width 0.2)
			(type default)
		)
		(layer "In6.Cu")
	)
	(gr_arc
		(start 96.954594 -53.058568)
		(mid 96.939715 -53.022647)
		(end 96.903794 -53.007768)
		(stroke
			(width 0.2)
			(type default)
		)
		(layer "In6.Cu")
	)
	(gr_line
		(start 96.954594 -52.448968)
		(end 96.954594 -52.245768)
		(stroke
			(width 0.2)
			(type default)
		)
		(layer "In6.Cu")
	)
	(gr_arc
		(start 96.954594 -52.245768)
		(mid 96.939715 -52.209847)
		(end 96.903794 -52.194968)
		(stroke
			(width 0.2)
			(type default)
		)
		(layer "In6.Cu")
	)
	(gr_line
		(start 96.954594 -51.864768)
		(end 96.954594 -51.661568)
		(stroke
			(width 0.2)
			(type default)
		)
		(layer "In6.Cu")
	)
	(gr_arc
		(start 96.954594 -51.661568)
		(mid 96.939715 -51.625647)
		(end 96.903794 -51.610768)
		(stroke
			(width 0.2)
			(type default)
		)
		(layer "In6.Cu")
	)
	(gr_line
		(start 96.954594 -51.051968)
		(end 96.954594 -50.848768)
		(stroke
			(width 0.2)
			(type default)
		)
		(layer "In6.Cu")
	)
	(gr_arc
		(start 96.954594 -50.848768)
		(mid 96.939715 -50.812847)
		(end 96.903794 -50.797968)
		(stroke
			(width 0.2)
			(type default)
		)
		(layer "In6.Cu")
	)
	(gr_line
		(start 96.954594 -50.467768)
		(end 96.954594 -50.264568)
		(stroke
			(width 0.2)
			(type default)
		)
		(layer "In6.Cu")
	)
	(gr_arc
		(start 96.954594 -50.264568)
		(mid 96.939715 -50.228647)
		(end 96.903794 -50.213768)
		(stroke
			(width 0.2)
			(type default)
		)
		(layer "In6.Cu")
	)
	(gr_arc
		(start 97.0534 -44.6278)
		(mid 97.068279 -44.663721)
		(end 97.1042 -44.6786)
		(stroke
			(width 0.2)
			(type default)
		)
		(layer "In6.Cu")
	)
	(gr_line
		(start 97.0534 -43.815)
		(end 97.0534 -44.6278)
		(stroke
			(width 0.2)
			(type default)
		)
		(layer "In6.Cu")
	)
	(gr_line
		(start 97.1042 -44.6786)
		(end 97.3074 -44.6786)
		(stroke
			(width 0.2)
			(type default)
		)
		(layer "In6.Cu")
	)
	(gr_arc
		(start 97.1042 -43.7642)
		(mid 97.068279 -43.779079)
		(end 97.0534 -43.815)
		(stroke
			(width 0.2)
			(type default)
		)
		(layer "In6.Cu")
	)
	(gr_arc
		(start 97.3074 -44.6786)
		(mid 97.343321 -44.663721)
		(end 97.3582 -44.6278)
		(stroke
			(width 0.2)
			(type default)
		)
		(layer "In6.Cu")
	)
	(gr_line
		(start 97.3074 -43.7642)
		(end 97.1042 -43.7642)
		(stroke
			(width 0.2)
			(type default)
		)
		(layer "In6.Cu")
	)
	(gr_line
		(start 97.3582 -44.6278)
		(end 97.3582 -43.815)
		(stroke
			(width 0.2)
			(type default)
		)
		(layer "In6.Cu")
	)
	(gr_arc
		(start 97.3582 -43.815)
		(mid 97.343321 -43.779079)
		(end 97.3074 -43.7642)
		(stroke
			(width 0.2)
			(type default)
		)
		(layer "In6.Cu")
	)
	(gr_line
		(start 97.361502 -12.400026)
		(end 97.361502 -10.999978)
		(stroke
			(width 0.2)
			(type default)
		)
		(layer "In6.Cu")
	)
	(gr_arc
		(start 97.361502 -10.999978)
		(mid 96.800162 -10.438638)
		(end 96.238822 -10.999978)
		(stroke
			(width 0.2)
			(type default)
		)
		(layer "In6.Cu")
	)
	(gr_line
		(start 97.361502 -5.200142)
		(end 97.361502 -3.800094)
		(stroke
			(width 0.2)
			(type default)
		)
		(layer "In6.Cu")
	)
	(gr_arc
		(start 97.361502 -3.800094)
		(mid 96.800162 -3.238754)
		(end 96.238822 -3.800094)
		(stroke
			(width 0.2)
			(type default)
		)
		(layer "In6.Cu")
	)
	(gr_line
		(start 97.499932 -126.000002)
		(end 89.212674 -127.325628)
		(stroke
			(width 1.524)
			(type default)
		)
		(layer "In6.Cu")
	)
	(gr_arc
		(start 98.0186 -44.6278)
		(mid 98.033479 -44.663721)
		(end 98.0694 -44.6786)
		(stroke
			(width 0.2)
			(type default)
		)
		(layer "In6.Cu")
	)
	(gr_line
		(start 98.0186 -43.815)
		(end 98.0186 -44.6278)
		(stroke
			(width 0.2)
			(type default)
		)
		(layer "In6.Cu")
	)
	(gr_arc
		(start 98.038666 -11.199876)
		(mid 98.599879 -11.76147)
		(end 99.161346 -11.20013)
		(stroke
			(width 0.2)
			(type default)
		)
		(layer "In6.Cu")
	)
	(gr_line
		(start 98.038666 -9.800082)
		(end 98.038666 -11.199876)
		(stroke
			(width 0.2)
			(type default)
		)
		(layer "In6.Cu")
	)
	(gr_arc
		(start 98.038666 -3.999738)
		(mid 98.599879 -4.561332)
		(end 99.161346 -3.999992)
		(stroke
			(width 0.2)
			(type default)
		)
		(layer "In6.Cu")
	)
	(gr_line
		(start 98.038666 -2.600198)
		(end 98.038666 -3.999738)
		(stroke
			(width 0.2)
			(type default)
		)
		(layer "In6.Cu")
	)
	(gr_line
		(start 98.0694 -44.6786)
		(end 98.2726 -44.6786)
		(stroke
			(width 0.2)
			(type default)
		)
		(layer "In6.Cu")
	)
	(gr_arc
		(start 98.0694 -43.7642)
		(mid 98.033479 -43.779079)
		(end 98.0186 -43.815)
		(stroke
			(width 0.2)
			(type default)
		)
		(layer "In6.Cu")
	)
	(gr_arc
		(start 98.2726 -44.6786)
		(mid 98.308521 -44.663721)
		(end 98.3234 -44.6278)
		(stroke
			(width 0.2)
			(type default)
		)
		(layer "In6.Cu")
	)
	(gr_line
		(start 98.2726 -43.7642)
		(end 98.0694 -43.7642)
		(stroke
			(width 0.2)
			(type default)
		)
		(layer "In6.Cu")
	)
	(gr_line
		(start 98.3234 -44.6278)
		(end 98.3234 -43.815)
		(stroke
			(width 0.2)
			(type default)
		)
		(layer "In6.Cu")
	)
	(gr_arc
		(start 98.3234 -43.815)
		(mid 98.308521 -43.779079)
		(end 98.2726 -43.7642)
		(stroke
			(width 0.2)
			(type default)
		)
		(layer "In6.Cu")
	)
	(gr_arc
		(start 98.5774 -44.6278)
		(mid 98.592279 -44.663721)
		(end 98.6282 -44.6786)
		(stroke
			(width 0.2)
			(type default)
		)
		(layer "In6.Cu")
	)
	(gr_line
		(start 98.5774 -43.815)
		(end 98.5774 -44.6278)
		(stroke
			(width 0.2)
			(type default)
		)
		(layer "In6.Cu")
	)
	(gr_line
		(start 98.6282 -44.6786)
		(end 98.8314 -44.6786)
		(stroke
			(width 0.2)
			(type default)
		)
		(layer "In6.Cu")
	)
	(gr_arc
		(start 98.6282 -43.7642)
		(mid 98.592279 -43.779079)
		(end 98.5774 -43.815)
		(stroke
			(width 0.2)
			(type default)
		)
		(layer "In6.Cu")
	)
	(gr_arc
		(start 98.641916 -54.99989)
		(mid 98.999929 -55.358284)
		(end 99.358196 -55.000144)
		(stroke
			(width 0.2)
			(type default)
		)
		(layer "In6.Cu")
	)
	(gr_line
		(start 98.641916 -54.000146)
		(end 98.641916 -54.99989)
		(stroke
			(width 0.2)
			(type default)
		)
		(layer "In6.Cu")
	)
	(gr_arc
		(start 98.8314 -44.6786)
		(mid 98.867321 -44.663721)
		(end 98.8822 -44.6278)
		(stroke
			(width 0.2)
			(type default)
		)
		(layer "In6.Cu")
	)
	(gr_line
		(start 98.8314 -43.7642)
		(end 98.6282 -43.7642)
		(stroke
			(width 0.2)
			(type default)
		)
		(layer "In6.Cu")
	)
	(gr_line
		(start 98.8822 -44.6278)
		(end 98.8822 -43.815)
		(stroke
			(width 0.2)
			(type default)
		)
		(layer "In6.Cu")
	)
	(gr_arc
		(start 98.8822 -43.815)
		(mid 98.867321 -43.779079)
		(end 98.8314 -43.7642)
		(stroke
			(width 0.2)
			(type default)
		)
		(layer "In6.Cu")
	)
	(gr_line
		(start 99.161346 -11.20013)
		(end 99.161346 -9.800082)
		(stroke
			(width 0.2)
			(type default)
		)
		(layer "In6.Cu")
	)
	(gr_arc
		(start 99.161346 -9.800082)
		(mid 98.600006 -9.238742)
		(end 98.038666 -9.800082)
		(stroke
			(width 0.2)
			(type default)
		)
		(layer "In6.Cu")
	)
	(gr_line
		(start 99.161346 -3.999992)
		(end 99.161346 -2.600198)
		(stroke
			(width 0.2)
			(type default)
		)
		(layer "In6.Cu")
	)
	(gr_arc
		(start 99.161346 -2.600198)
		(mid 98.600006 -2.038858)
		(end 98.038666 -2.600198)
		(stroke
			(width 0.2)
			(type default)
		)
		(layer "In6.Cu")
	)
	(gr_line
		(start 99.358196 -55.000144)
		(end 99.358196 -54.000146)
		(stroke
			(width 0.2)
			(type default)
		)
		(layer "In6.Cu")
	)
	(gr_arc
		(start 99.358196 -54.000146)
		(mid 99.000056 -53.642006)
		(end 98.641916 -54.000146)
		(stroke
			(width 0.2)
			(type default)
		)
		(layer "In6.Cu")
	)
	(gr_arc
		(start 99.5426 -44.6278)
		(mid 99.557479 -44.663721)
		(end 99.5934 -44.6786)
		(stroke
			(width 0.2)
			(type default)
		)
		(layer "In6.Cu")
	)
	(gr_line
		(start 99.5426 -43.815)
		(end 99.5426 -44.6278)
		(stroke
			(width 0.2)
			(type default)
		)
		(layer "In6.Cu")
	)
	(gr_line
		(start 99.5934 -44.6786)
		(end 99.7966 -44.6786)
		(stroke
			(width 0.2)
			(type default)
		)
		(layer "In6.Cu")
	)
	(gr_arc
		(start 99.5934 -43.7642)
		(mid 99.557479 -43.779079)
		(end 99.5426 -43.815)
		(stroke
			(width 0.2)
			(type default)
		)
		(layer "In6.Cu")
	)
	(gr_arc
		(start 99.641914 -51.999896)
		(mid 99.999927 -52.35829)
		(end 100.358194 -52.00015)
		(stroke
			(width 0.2)
			(type default)
		)
		(layer "In6.Cu")
	)
	(gr_line
		(start 99.641914 -51.000152)
		(end 99.641914 -51.999896)
		(stroke
			(width 0.2)
			(type default)
		)
		(layer "In6.Cu")
	)
	(gr_arc
		(start 99.7966 -44.6786)
		(mid 99.832521 -44.663721)
		(end 99.8474 -44.6278)
		(stroke
			(width 0.2)
			(type default)
		)
		(layer "In6.Cu")
	)
	(gr_line
		(start 99.7966 -43.7642)
		(end 99.5934 -43.7642)
		(stroke
			(width 0.2)
			(type default)
		)
		(layer "In6.Cu")
	)
	(gr_arc
		(start 99.838764 -12.399772)
		(mid 100.399977 -12.961366)
		(end 100.961444 -12.400026)
		(stroke
			(width 0.2)
			(type default)
		)
		(layer "In6.Cu")
	)
	(gr_line
		(start 99.838764 -10.999978)
		(end 99.838764 -12.399772)
		(stroke
			(width 0.2)
			(type default)
		)
		(layer "In6.Cu")
	)
	(gr_arc
		(start 99.838764 -5.199888)
		(mid 100.399977 -5.761482)
		(end 100.961444 -5.200142)
		(stroke
			(width 0.2)
			(type default)
		)
		(layer "In6.Cu")
	)
	(gr_line
		(start 99.838764 -3.800094)
		(end 99.838764 -5.199888)
		(stroke
			(width 0.2)
			(type default)
		)
		(layer "In6.Cu")
	)
	(gr_line
		(start 99.8474 -44.6278)
		(end 99.8474 -43.815)
		(stroke
			(width 0.2)
			(type default)
		)
		(layer "In6.Cu")
	)
	(gr_arc
		(start 99.8474 -43.815)
		(mid 99.832521 -43.779079)
		(end 99.7966 -43.7642)
		(stroke
			(width 0.2)
			(type default)
		)
		(layer "In6.Cu")
	)
	(gr_arc
		(start 100.1014 -44.6278)
		(mid 100.116279 -44.663721)
		(end 100.1522 -44.6786)
		(stroke
			(width 0.2)
			(type default)
		)
		(layer "In6.Cu")
	)
	(gr_line
		(start 100.1014 -43.815)
		(end 100.1014 -44.6278)
		(stroke
			(width 0.2)
			(type default)
		)
		(layer "In6.Cu")
	)
	(gr_line
		(start 100.1522 -44.6786)
		(end 100.3554 -44.6786)
		(stroke
			(width 0.2)
			(type default)
		)
		(layer "In6.Cu")
	)
	(gr_arc
		(start 100.1522 -43.7642)
		(mid 100.116279 -43.779079)
		(end 100.1014 -43.815)
		(stroke
			(width 0.2)
			(type default)
		)
		(layer "In6.Cu")
	)
	(gr_arc
		(start 100.3554 -44.6786)
		(mid 100.391321 -44.663721)
		(end 100.4062 -44.6278)
		(stroke
			(width 0.2)
			(type default)
		)
		(layer "In6.Cu")
	)
	(gr_line
		(start 100.3554 -43.7642)
		(end 100.1522 -43.7642)
		(stroke
			(width 0.2)
			(type default)
		)
		(layer "In6.Cu")
	)
	(gr_line
		(start 100.358194 -52.00015)
		(end 100.358194 -51.000152)
		(stroke
			(width 0.2)
			(type default)
		)
		(layer "In6.Cu")
	)
	(gr_arc
		(start 100.358194 -51.000152)
		(mid 100.000054 -50.642012)
		(end 99.641914 -51.000152)
		(stroke
			(width 0.2)
			(type default)
		)
		(layer "In6.Cu")
	)
	(gr_line
		(start 100.4062 -44.6278)
		(end 100.4062 -43.815)
		(stroke
			(width 0.2)
			(type default)
		)
		(layer "In6.Cu")
	)
	(gr_arc
		(start 100.4062 -43.815)
		(mid 100.391321 -43.779079)
		(end 100.3554 -43.7642)
		(stroke
			(width 0.2)
			(type default)
		)
		(layer "In6.Cu")
	)
	(gr_arc
		(start 100.641912 -55.999888)
		(mid 100.999925 -56.358282)
		(end 101.358192 -56.000142)
		(stroke
			(width 0.2)
			(type default)
		)
		(layer "In6.Cu")
	)
	(gr_line
		(start 100.641912 -55.000144)
		(end 100.641912 -55.999888)
		(stroke
			(width 0.2)
			(type default)
		)
		(layer "In6.Cu")
	)
	(gr_arc
		(start 100.641912 -52.999894)
		(mid 100.999925 -53.358288)
		(end 101.358192 -53.000148)
		(stroke
			(width 0.2)
			(type default)
		)
		(layer "In6.Cu")
	)
	(gr_line
		(start 100.641912 -52.00015)
		(end 100.641912 -52.999894)
		(stroke
			(width 0.2)
			(type default)
		)
		(layer "In6.Cu")
	)
	(gr_line
		(start 100.961444 -12.400026)
		(end 100.961444 -10.999978)
		(stroke
			(width 0.2)
			(type default)
		)
		(layer "In6.Cu")
	)
	(gr_arc
		(start 100.961444 -10.999978)
		(mid 100.400104 -10.438638)
		(end 99.838764 -10.999978)
		(stroke
			(width 0.2)
			(type default)
		)
		(layer "In6.Cu")
	)
	(gr_line
		(start 100.961444 -5.200142)
		(end 100.961444 -3.800094)
		(stroke
			(width 0.2)
			(type default)
		)
		(layer "In6.Cu")
	)
	(gr_arc
		(start 100.961444 -3.800094)
		(mid 100.400104 -3.238754)
		(end 99.838764 -3.800094)
		(stroke
			(width 0.2)
			(type default)
		)
		(layer "In6.Cu")
	)
	(gr_arc
		(start 101.0666 -44.6278)
		(mid 101.081479 -44.663721)
		(end 101.1174 -44.6786)
		(stroke
			(width 0.2)
			(type default)
		)
		(layer "In6.Cu")
	)
	(gr_line
		(start 101.0666 -43.815)
		(end 101.0666 -44.6278)
		(stroke
			(width 0.2)
			(type default)
		)
		(layer "In6.Cu")
	)
	(gr_line
		(start 101.1174 -44.6786)
		(end 101.3206 -44.6786)
		(stroke
			(width 0.2)
			(type default)
		)
		(layer "In6.Cu")
	)
	(gr_arc
		(start 101.1174 -43.7642)
		(mid 101.081479 -43.779079)
		(end 101.0666 -43.815)
		(stroke
			(width 0.2)
			(type default)
		)
		(layer "In6.Cu")
	)
	(gr_arc
		(start 101.3206 -44.6786)
		(mid 101.356521 -44.663721)
		(end 101.3714 -44.6278)
		(stroke
			(width 0.2)
			(type default)
		)
		(layer "In6.Cu")
	)
	(gr_line
		(start 101.3206 -43.7642)
		(end 101.1174 -43.7642)
		(stroke
			(width 0.2)
			(type default)
		)
		(layer "In6.Cu")
	)
	(gr_line
		(start 101.358192 -56.000142)
		(end 101.358192 -55.000144)
		(stroke
			(width 0.2)
			(type default)
		)
		(layer "In6.Cu")
	)
	(gr_arc
		(start 101.358192 -55.000144)
		(mid 101.000052 -54.642004)
		(end 100.641912 -55.000144)
		(stroke
			(width 0.2)
			(type default)
		)
		(layer "In6.Cu")
	)
	(gr_line
		(start 101.358192 -53.000148)
		(end 101.358192 -52.00015)
		(stroke
			(width 0.2)
			(type default)
		)
		(layer "In6.Cu")
	)
	(gr_arc
		(start 101.358192 -52.00015)
		(mid 101.000052 -51.64201)
		(end 100.641912 -52.00015)
		(stroke
			(width 0.2)
			(type default)
		)
		(layer "In6.Cu")
	)
	(gr_line
		(start 101.3714 -44.6278)
		(end 101.3714 -43.815)
		(stroke
			(width 0.2)
			(type default)
		)
		(layer "In6.Cu")
	)
	(gr_arc
		(start 101.3714 -43.815)
		(mid 101.356521 -43.779079)
		(end 101.3206 -43.7642)
		(stroke
			(width 0.2)
			(type default)
		)
		(layer "In6.Cu")
	)
	(gr_arc
		(start 101.6254 -44.6278)
		(mid 101.640279 -44.663721)
		(end 101.6762 -44.6786)
		(stroke
			(width 0.2)
			(type default)
		)
		(layer "In6.Cu")
	)
	(gr_line
		(start 101.6254 -43.815)
		(end 101.6254 -44.6278)
		(stroke
			(width 0.2)
			(type default)
		)
		(layer "In6.Cu")
	)
	(gr_arc
		(start 101.638862 -11.199876)
		(mid 102.200075 -11.76147)
		(end 102.761542 -11.20013)
		(stroke
			(width 0.2)
			(type default)
		)
		(layer "In6.Cu")
	)
	(gr_line
		(start 101.638862 -9.800082)
		(end 101.638862 -11.199876)
		(stroke
			(width 0.2)
			(type default)
		)
		(layer "In6.Cu")
	)
	(gr_arc
		(start 101.638862 -3.999738)
		(mid 102.200075 -4.561332)
		(end 102.761542 -3.999992)
		(stroke
			(width 0.2)
			(type default)
		)
		(layer "In6.Cu")
	)
	(gr_line
		(start 101.638862 -2.600198)
		(end 101.638862 -3.999738)
		(stroke
			(width 0.2)
			(type default)
		)
		(layer "In6.Cu")
	)
	(gr_arc
		(start 101.64191 -55.999888)
		(mid 101.999923 -56.358282)
		(end 102.35819 -56.000142)
		(stroke
			(width 0.2)
			(type default)
		)
		(layer "In6.Cu")
	)
	(gr_line
		(start 101.64191 -55.000144)
		(end 101.64191 -55.999888)
		(stroke
			(width 0.2)
			(type default)
		)
		(layer "In6.Cu")
	)
	(gr_arc
		(start 101.64191 -51.999896)
		(mid 101.999923 -52.35829)
		(end 102.35819 -52.00015)
		(stroke
			(width 0.2)
			(type default)
		)
		(layer "In6.Cu")
	)
	(gr_line
		(start 101.64191 -51.000152)
		(end 101.64191 -51.999896)
		(stroke
			(width 0.2)
			(type default)
		)
		(layer "In6.Cu")
	)
	(gr_line
		(start 101.6762 -44.6786)
		(end 101.8794 -44.6786)
		(stroke
			(width 0.2)
			(type default)
		)
		(layer "In6.Cu")
	)
	(gr_arc
		(start 101.6762 -43.7642)
		(mid 101.640279 -43.779079)
		(end 101.6254 -43.815)
		(stroke
			(width 0.2)
			(type default)
		)
		(layer "In6.Cu")
	)
	(gr_arc
		(start 101.8794 -44.6786)
		(mid 101.915321 -44.663721)
		(end 101.9302 -44.6278)
		(stroke
			(width 0.2)
			(type default)
		)
		(layer "In6.Cu")
	)
	(gr_line
		(start 101.8794 -43.7642)
		(end 101.6762 -43.7642)
		(stroke
			(width 0.2)
			(type default)
		)
		(layer "In6.Cu")
	)
	(gr_line
		(start 101.9302 -44.6278)
		(end 101.9302 -43.815)
		(stroke
			(width 0.2)
			(type default)
		)
		(layer "In6.Cu")
	)
	(gr_arc
		(start 101.9302 -43.815)
		(mid 101.915321 -43.779079)
		(end 101.8794 -43.7642)
		(stroke
			(width 0.2)
			(type default)
		)
		(layer "In6.Cu")
	)
	(gr_arc
		(start 102.266496 -115.990878)
		(mid 102.491032 -116.733574)
		(end 103.233728 -116.509038)
		(stroke
			(width 0.2)
			(type default)
		)
		(layer "In6.Cu")
	)
	(gr_line
		(start 102.266496 -115.990624)
		(end 102.266496 -115.990878)
		(stroke
			(width 0.2)
			(type default)
		)
		(layer "In6.Cu")
	)
	(gr_arc
		(start 102.266496 -112.191038)
		(mid 102.491032 -112.933734)
		(end 103.233728 -112.709198)
		(stroke
			(width 0.2)
			(type default)
		)
		(layer "In6.Cu")
	)
	(gr_line
		(start 102.266496 -112.190784)
		(end 102.266496 -112.191038)
		(stroke
			(width 0.2)
			(type default)
		)
		(layer "In6.Cu")
	)
	(gr_line
		(start 102.311454 -108.415074)
		(end 102.311962 -108.415328)
		(stroke
			(width 0.2)
			(type default)
		)
		(layer "In6.Cu")
	)
	(gr_line
		(start 102.311454 -108.41482)
		(end 102.311454 -108.415074)
		(stroke
			(width 0.2)
			(type default)
		)
		(layer "In6.Cu")
	)
	(gr_line
		(start 102.311454 -104.61498)
		(end 102.311962 -104.615234)
		(stroke
			(width 0.2)
			(type default)
		)
		(layer "In6.Cu")
	)
	(gr_line
		(start 102.311454 -104.614726)
		(end 102.311454 -104.61498)
		(stroke
			(width 0.2)
			(type default)
		)
		(layer "In6.Cu")
	)
	(gr_arc
		(start 102.311962 -108.415328)
		(mid 102.515416 -109.088174)
		(end 103.188262 -108.88472)
		(stroke
			(width 0.2)
			(type default)
		)
		(layer "In6.Cu")
	)
	(gr_arc
		(start 102.311962 -104.615234)
		(mid 102.515416 -105.28808)
		(end 103.188262 -105.084626)
		(stroke
			(width 0.2)
			(type default)
		)
		(layer "In6.Cu")
	)
	(gr_line
		(start 102.35819 -56.000142)
		(end 102.35819 -55.000144)
		(stroke
			(width 0.2)
			(type default)
		)
		(layer "In6.Cu")
	)
	(gr_arc
		(start 102.35819 -55.000144)
		(mid 102.00005 -54.642004)
		(end 101.64191 -55.000144)
		(stroke
			(width 0.2)
			(type default)
		)
		(layer "In6.Cu")
	)
	(gr_line
		(start 102.35819 -52.00015)
		(end 102.35819 -51.000152)
		(stroke
			(width 0.2)
			(type default)
		)
		(layer "In6.Cu")
	)
	(gr_arc
		(start 102.35819 -51.000152)
		(mid 102.00005 -50.642012)
		(end 101.64191 -51.000152)
		(stroke
			(width 0.2)
			(type default)
		)
		(layer "In6.Cu")
	)
	(gr_arc
		(start 102.5906 -44.6278)
		(mid 102.605479 -44.663721)
		(end 102.6414 -44.6786)
		(stroke
			(width 0.2)
			(type default)
		)
		(layer "In6.Cu")
	)
	(gr_line
		(start 102.5906 -43.815)
		(end 102.5906 -44.6278)
		(stroke
			(width 0.2)
			(type default)
		)
		(layer "In6.Cu")
	)
	(gr_line
		(start 102.6414 -44.6786)
		(end 102.8446 -44.6786)
		(stroke
			(width 0.2)
			(type default)
		)
		(layer "In6.Cu")
	)
	(gr_arc
		(start 102.6414 -43.7642)
		(mid 102.605479 -43.779079)
		(end 102.5906 -43.815)
		(stroke
			(width 0.2)
			(type default)
		)
		(layer "In6.Cu")
	)
	(gr_arc
		(start 102.641908 -55.999888)
		(mid 102.999921 -56.358282)
		(end 103.358188 -56.000142)
		(stroke
			(width 0.2)
			(type default)
		)
		(layer "In6.Cu")
	)
	(gr_line
		(start 102.641908 -55.000144)
		(end 102.641908 -55.999888)
		(stroke
			(width 0.2)
			(type default)
		)
		(layer "In6.Cu")
	)
	(gr_arc
		(start 102.641908 -52.999894)
		(mid 102.999921 -53.358288)
		(end 103.358188 -53.000148)
		(stroke
			(width 0.2)
			(type default)
		)
		(layer "In6.Cu")
	)
	(gr_line
		(start 102.641908 -52.00015)
		(end 102.641908 -52.999894)
		(stroke
			(width 0.2)
			(type default)
		)
		(layer "In6.Cu")
	)
	(gr_line
		(start 102.761542 -11.20013)
		(end 102.761542 -9.800082)
		(stroke
			(width 0.2)
			(type default)
		)
		(layer "In6.Cu")
	)
	(gr_arc
		(start 102.761542 -9.800082)
		(mid 102.200202 -9.238742)
		(end 101.638862 -9.800082)
		(stroke
			(width 0.2)
			(type default)
		)
		(layer "In6.Cu")
	)
	(gr_line
		(start 102.761542 -3.999992)
		(end 102.761542 -2.600198)
		(stroke
			(width 0.2)
			(type default)
		)
		(layer "In6.Cu")
	)
	(gr_arc
		(start 102.761542 -2.600198)
		(mid 102.200202 -2.038858)
		(end 101.638862 -2.600198)
		(stroke
			(width 0.2)
			(type default)
		)
		(layer "In6.Cu")
	)
	(gr_arc
		(start 102.8446 -44.6786)
		(mid 102.880521 -44.663721)
		(end 102.8954 -44.6278)
		(stroke
			(width 0.2)
			(type default)
		)
		(layer "In6.Cu")
	)
	(gr_line
		(start 102.8446 -43.7642)
		(end 102.6414 -43.7642)
		(stroke
			(width 0.2)
			(type default)
		)
		(layer "In6.Cu")
	)
	(gr_line
		(start 102.8954 -44.6278)
		(end 102.8954 -43.815)
		(stroke
			(width 0.2)
			(type default)
		)
		(layer "In6.Cu")
	)
	(gr_arc
		(start 102.8954 -43.815)
		(mid 102.880521 -43.779079)
		(end 102.8446 -43.7642)
		(stroke
			(width 0.2)
			(type default)
		)
		(layer "In6.Cu")
	)
	(gr_line
		(start 103.016304 -114.59083)
		(end 102.266496 -115.990624)
		(stroke
			(width 0.2)
			(type default)
		)
		(layer "In6.Cu")
	)
	(gr_line
		(start 103.016304 -110.79099)
		(end 102.266496 -112.190784)
		(stroke
			(width 0.2)
			(type default)
		)
		(layer "In6.Cu")
	)
	(gr_line
		(start 103.061008 -107.015026)
		(end 102.311454 -108.41482)
		(stroke
			(width 0.2)
			(type default)
		)
		(layer "In6.Cu")
	)
	(gr_line
		(start 103.061008 -103.215186)
		(end 102.311454 -104.614726)
		(stroke
			(width 0.2)
			(type default)
		)
		(layer "In6.Cu")
	)
	(gr_line
		(start 103.06177 -107.01528)
		(end 103.061008 -107.015026)
		(stroke
			(width 0.2)
			(type default)
		)
		(layer "In6.Cu")
	)
	(gr_line
		(start 103.06177 -103.21544)
		(end 103.061008 -103.215186)
		(stroke
			(width 0.2)
			(type default)
		)
		(layer "In6.Cu")
	)
	(gr_arc
		(start 103.1494 -44.6278)
		(mid 103.164279 -44.663721)
		(end 103.2002 -44.6786)
		(stroke
			(width 0.2)
			(type default)
		)
		(layer "In6.Cu")
	)
	(gr_line
		(start 103.1494 -43.815)
		(end 103.1494 -44.6278)
		(stroke
			(width 0.2)
			(type default)
		)
		(layer "In6.Cu")
	)
	(gr_line
		(start 103.188262 -108.88472)
		(end 103.189024 -108.884974)
		(stroke
			(width 0.2)
			(type default)
		)
		(layer "In6.Cu")
	)
	(gr_line
		(start 103.188262 -105.084626)
		(end 103.189024 -105.08488)
		(stroke
			(width 0.2)
			(type default)
		)
		(layer "In6.Cu")
	)
	(gr_line
		(start 103.189024 -108.884974)
		(end 103.938832 -107.484926)
		(stroke
			(width 0.2)
			(type default)
		)
		(layer "In6.Cu")
	)
	(gr_line
		(start 103.189024 -105.08488)
		(end 103.938832 -103.685086)
		(stroke
			(width 0.2)
			(type default)
		)
		(layer "In6.Cu")
	)
	(gr_line
		(start 103.2002 -44.6786)
		(end 103.4034 -44.6786)
		(stroke
			(width 0.2)
			(type default)
		)
		(layer "In6.Cu")
	)
	(gr_arc
		(start 103.2002 -43.7642)
		(mid 103.164279 -43.779079)
		(end 103.1494 -43.815)
		(stroke
			(width 0.2)
			(type default)
		)
		(layer "In6.Cu")
	)
	(gr_line
		(start 103.233728 -116.509038)
		(end 103.983536 -115.10899)
		(stroke
			(width 0.2)
			(type default)
		)
		(layer "In6.Cu")
	)
	(gr_line
		(start 103.233728 -112.709198)
		(end 103.983536 -111.30915)
		(stroke
			(width 0.2)
			(type default)
		)
		(layer "In6.Cu")
	)
	(gr_line
		(start 103.358188 -56.000142)
		(end 103.358188 -55.000144)
		(stroke
			(width 0.2)
			(type default)
		)
		(layer "In6.Cu")
	)
	(gr_arc
		(start 103.358188 -55.000144)
		(mid 103.000048 -54.642004)
		(end 102.641908 -55.000144)
		(stroke
			(width 0.2)
			(type default)
		)
		(layer "In6.Cu")
	)
	(gr_line
		(start 103.358188 -53.000148)
		(end 103.358188 -52.00015)
		(stroke
			(width 0.2)
			(type default)
		)
		(layer "In6.Cu")
	)
	(gr_arc
		(start 103.358188 -52.00015)
		(mid 103.000048 -51.64201)
		(end 102.641908 -52.00015)
		(stroke
			(width 0.2)
			(type default)
		)
		(layer "In6.Cu")
	)
	(gr_arc
		(start 103.4034 -44.6786)
		(mid 103.439321 -44.663721)
		(end 103.4542 -44.6278)
		(stroke
			(width 0.2)
			(type default)
		)
		(layer "In6.Cu")
	)
	(gr_line
		(start 103.4034 -43.7642)
		(end 103.2002 -43.7642)
		(stroke
			(width 0.2)
			(type default)
		)
		(layer "In6.Cu")
	)
	(gr_arc
		(start 103.438706 -12.399772)
		(mid 103.999919 -12.961366)
		(end 104.561386 -12.400026)
		(stroke
			(width 0.2)
			(type default)
		)
		(layer "In6.Cu")
	)
	(gr_line
		(start 103.438706 -10.999978)
		(end 103.438706 -12.399772)
		(stroke
			(width 0.2)
			(type default)
		)
		(layer "In6.Cu")
	)
	(gr_arc
		(start 103.438706 -5.199888)
		(mid 103.999919 -5.761482)
		(end 104.561386 -5.200142)
		(stroke
			(width 0.2)
			(type default)
		)
		(layer "In6.Cu")
	)
	(gr_line
		(start 103.438706 -3.800094)
		(end 103.438706 -5.199888)
		(stroke
			(width 0.2)
			(type default)
		)
		(layer "In6.Cu")
	)
	(gr_line
		(start 103.4542 -44.6278)
		(end 103.4542 -43.815)
		(stroke
			(width 0.2)
			(type default)
		)
		(layer "In6.Cu")
	)
	(gr_arc
		(start 103.4542 -43.815)
		(mid 103.439321 -43.779079)
		(end 103.4034 -43.7642)
		(stroke
			(width 0.2)
			(type default)
		)
		(layer "In6.Cu")
	)
	(gr_arc
		(start 103.641906 -55.999888)
		(mid 103.999919 -56.358282)
		(end 104.358186 -56.000142)
		(stroke
			(width 0.2)
			(type default)
		)
		(layer "In6.Cu")
	)
	(gr_line
		(start 103.641906 -55.000144)
		(end 103.641906 -55.999888)
		(stroke
			(width 0.2)
			(type default)
		)
		(layer "In6.Cu")
	)
	(gr_arc
		(start 103.641906 -51.999896)
		(mid 103.999919 -52.35829)
		(end 104.358186 -52.00015)
		(stroke
			(width 0.2)
			(type default)
		)
		(layer "In6.Cu")
	)
	(gr_line
		(start 103.641906 -51.000152)
		(end 103.641906 -51.999896)
		(stroke
			(width 0.2)
			(type default)
		)
		(layer "In6.Cu")
	)
	(gr_arc
		(start 103.93807 -107.484672)
		(mid 103.734616 -106.811826)
		(end 103.06177 -107.01528)
		(stroke
			(width 0.2)
			(type default)
		)
		(layer "In6.Cu")
	)
	(gr_arc
		(start 103.93807 -103.684832)
		(mid 103.734616 -103.011986)
		(end 103.06177 -103.21544)
		(stroke
			(width 0.2)
			(type default)
		)
		(layer "In6.Cu")
	)
	(gr_line
		(start 103.938832 -107.484926)
		(end 103.93807 -107.484672)
		(stroke
			(width 0.2)
			(type default)
		)
		(layer "In6.Cu")
	)
	(gr_line
		(start 103.938832 -103.685086)
		(end 103.93807 -103.684832)
		(stroke
			(width 0.2)
			(type default)
		)
		(layer "In6.Cu")
	)
	(gr_arc
		(start 103.983536 -115.10899)
		(mid 103.759 -114.366294)
		(end 103.016304 -114.59083)
		(stroke
			(width 0.2)
			(type default)
		)
		(layer "In6.Cu")
	)
	(gr_arc
		(start 103.983536 -111.30915)
		(mid 103.759 -110.566454)
		(end 103.016304 -110.79099)
		(stroke
			(width 0.2)
			(type default)
		)
		(layer "In6.Cu")
	)
	(gr_arc
		(start 104.1146 -44.6278)
		(mid 104.129479 -44.663721)
		(end 104.1654 -44.6786)
		(stroke
			(width 0.2)
			(type default)
		)
		(layer "In6.Cu")
	)
	(gr_line
		(start 104.1146 -43.815)
		(end 104.1146 -44.6278)
		(stroke
			(width 0.2)
			(type default)
		)
		(layer "In6.Cu")
	)
	(gr_line
		(start 104.1654 -44.6786)
		(end 104.3686 -44.6786)
		(stroke
			(width 0.2)
			(type default)
		)
		(layer "In6.Cu")
	)
	(gr_arc
		(start 104.1654 -43.7642)
		(mid 104.129479 -43.779079)
		(end 104.1146 -43.815)
		(stroke
			(width 0.2)
			(type default)
		)
		(layer "In6.Cu")
	)
	(gr_line
		(start 104.358186 -56.000142)
		(end 104.358186 -55.000144)
		(stroke
			(width 0.2)
			(type default)
		)
		(layer "In6.Cu")
	)
	(gr_arc
		(start 104.358186 -55.000144)
		(mid 104.000046 -54.642004)
		(end 103.641906 -55.000144)
		(stroke
			(width 0.2)
			(type default)
		)
		(layer "In6.Cu")
	)
	(gr_line
		(start 104.358186 -52.00015)
		(end 104.358186 -51.000152)
		(stroke
			(width 0.2)
			(type default)
		)
		(layer "In6.Cu")
	)
	(gr_arc
		(start 104.358186 -51.000152)
		(mid 104.000046 -50.642012)
		(end 103.641906 -51.000152)
		(stroke
			(width 0.2)
			(type default)
		)
		(layer "In6.Cu")
	)
	(gr_arc
		(start 104.3686 -44.6786)
		(mid 104.404521 -44.663721)
		(end 104.4194 -44.6278)
		(stroke
			(width 0.2)
			(type default)
		)
		(layer "In6.Cu")
	)
	(gr_line
		(start 104.3686 -43.7642)
		(end 104.1654 -43.7642)
		(stroke
			(width 0.2)
			(type default)
		)
		(layer "In6.Cu")
	)
	(gr_line
		(start 104.4194 -44.6278)
		(end 104.4194 -43.815)
		(stroke
			(width 0.2)
			(type default)
		)
		(layer "In6.Cu")
	)
	(gr_arc
		(start 104.4194 -43.815)
		(mid 104.404521 -43.779079)
		(end 104.3686 -43.7642)
		(stroke
			(width 0.2)
			(type default)
		)
		(layer "In6.Cu")
	)
	(gr_arc
		(start 104.516428 -115.990624)
		(mid 104.740809 -116.733627)
		(end 105.48366 -116.509038)
		(stroke
			(width 0.2)
			(type default)
		)
		(layer "In6.Cu")
	)
	(gr_arc
		(start 104.516428 -112.190784)
		(mid 104.740809 -112.933787)
		(end 105.48366 -112.709198)
		(stroke
			(width 0.2)
			(type default)
		)
		(layer "In6.Cu")
	)
	(gr_line
		(start 104.561386 -108.415074)
		(end 104.561894 -108.415328)
		(stroke
			(width 0.2)
			(type default)
		)
		(layer "In6.Cu")
	)
	(gr_line
		(start 104.561386 -108.41482)
		(end 104.561386 -108.415074)
		(stroke
			(width 0.2)
			(type default)
		)
		(layer "In6.Cu")
	)
	(gr_line
		(start 104.561386 -104.61498)
		(end 104.561894 -104.615234)
		(stroke
			(width 0.2)
			(type default)
		)
		(layer "In6.Cu")
	)
	(gr_line
		(start 104.561386 -104.614472)
		(end 104.561386 -104.61498)
		(stroke
			(width 0.2)
			(type default)
		)
		(layer "In6.Cu")
	)
	(gr_line
		(start 104.561386 -12.400026)
		(end 104.561386 -10.999978)
		(stroke
			(width 0.2)
			(type default)
		)
		(layer "In6.Cu")
	)
	(gr_arc
		(start 104.561386 -10.999978)
		(mid 104.000046 -10.438638)
		(end 103.438706 -10.999978)
		(stroke
			(width 0.2)
			(type default)
		)
		(layer "In6.Cu")
	)
	(gr_line
		(start 104.561386 -5.200142)
		(end 104.561386 -3.800094)
		(stroke
			(width 0.2)
			(type default)
		)
		(layer "In6.Cu")
	)
	(gr_arc
		(start 104.561386 -3.800094)
		(mid 104.000046 -3.238754)
		(end 103.438706 -3.800094)
		(stroke
			(width 0.2)
			(type default)
		)
		(layer "In6.Cu")
	)
	(gr_arc
		(start 104.561894 -108.415328)
		(mid 104.765348 -109.088174)
		(end 105.438194 -108.88472)
		(stroke
			(width 0.2)
			(type default)
		)
		(layer "In6.Cu")
	)
	(gr_arc
		(start 104.561894 -104.615234)
		(mid 104.765348 -105.28808)
		(end 105.438194 -105.084626)
		(stroke
			(width 0.2)
			(type default)
		)
		(layer "In6.Cu")
	)
	(gr_arc
		(start 104.641904 -55.999888)
		(mid 104.999917 -56.358282)
		(end 105.358184 -56.000142)
		(stroke
			(width 0.2)
			(type default)
		)
		(layer "In6.Cu")
	)
	(gr_line
		(start 104.641904 -55.000144)
		(end 104.641904 -55.999888)
		(stroke
			(width 0.2)
			(type default)
		)
		(layer "In6.Cu")
	)
	(gr_arc
		(start 104.641904 -52.999894)
		(mid 104.999917 -53.358288)
		(end 105.358184 -53.000148)
		(stroke
			(width 0.2)
			(type default)
		)
		(layer "In6.Cu")
	)
	(gr_line
		(start 104.641904 -52.00015)
		(end 104.641904 -52.999894)
		(stroke
			(width 0.2)
			(type default)
		)
		(layer "In6.Cu")
	)
	(gr_arc
		(start 104.6734 -44.6278)
		(mid 104.688279 -44.663721)
		(end 104.7242 -44.6786)
		(stroke
			(width 0.2)
			(type default)
		)
		(layer "In6.Cu")
	)
	(gr_line
		(start 104.6734 -43.815)
		(end 104.6734 -44.6278)
		(stroke
			(width 0.2)
			(type default)
		)
		(layer "In6.Cu")
	)
	(gr_line
		(start 104.7242 -44.6786)
		(end 104.9274 -44.6786)
		(stroke
			(width 0.2)
			(type default)
		)
		(layer "In6.Cu")
	)
	(gr_arc
		(start 104.7242 -43.7642)
		(mid 104.688279 -43.779079)
		(end 104.6734 -43.815)
		(stroke
			(width 0.2)
			(type default)
		)
		(layer "In6.Cu")
	)
	(gr_arc
		(start 104.9274 -44.6786)
		(mid 104.963321 -44.663721)
		(end 104.9782 -44.6278)
		(stroke
			(width 0.2)
			(type default)
		)
		(layer "In6.Cu")
	)
	(gr_line
		(start 104.9274 -43.7642)
		(end 104.7242 -43.7642)
		(stroke
			(width 0.2)
			(type default)
		)
		(layer "In6.Cu")
	)
	(gr_line
		(start 104.9782 -44.6278)
		(end 104.9782 -43.815)
		(stroke
			(width 0.2)
			(type default)
		)
		(layer "In6.Cu")
	)
	(gr_arc
		(start 104.9782 -43.815)
		(mid 104.963321 -43.779079)
		(end 104.9274 -43.7642)
		(stroke
			(width 0.2)
			(type default)
		)
		(layer "In6.Cu")
	)
	(gr_arc
		(start 105.238804 -11.199876)
		(mid 105.800017 -11.76147)
		(end 106.361484 -11.20013)
		(stroke
			(width 0.2)
			(type default)
		)
		(layer "In6.Cu")
	)
	(gr_line
		(start 105.238804 -9.800082)
		(end 105.238804 -11.199876)
		(stroke
			(width 0.2)
			(type default)
		)
		(layer "In6.Cu")
	)
	(gr_arc
		(start 105.238804 -3.999738)
		(mid 105.800017 -4.561332)
		(end 106.361484 -3.999992)
		(stroke
			(width 0.2)
			(type default)
		)
		(layer "In6.Cu")
	)
	(gr_line
		(start 105.238804 -2.600198)
		(end 105.238804 -3.999738)
		(stroke
			(width 0.2)
			(type default)
		)
		(layer "In6.Cu")
	)
	(gr_line
		(start 105.26649 -114.59083)
		(end 104.516428 -115.990624)
		(stroke
			(width 0.2)
			(type default)
		)
		(layer "In6.Cu")
	)
	(gr_line
		(start 105.26649 -110.79099)
		(end 104.516428 -112.190784)
		(stroke
			(width 0.2)
			(type default)
		)
		(layer "In6.Cu")
	)
	(gr_line
		(start 105.311194 -107.014772)
		(end 104.561386 -108.41482)
		(stroke
			(width 0.2)
			(type default)
		)
		(layer "In6.Cu")
	)
	(gr_line
		(start 105.311194 -103.214932)
		(end 104.561386 -104.614472)
		(stroke
			(width 0.2)
			(type default)
		)
		(layer "In6.Cu")
	)
	(gr_line
		(start 105.311956 -107.01528)
		(end 105.311194 -107.014772)
		(stroke
			(width 0.2)
			(type default)
		)
		(layer "In6.Cu")
	)
	(gr_line
		(start 105.311956 -103.21544)
		(end 105.311194 -103.214932)
		(stroke
			(width 0.2)
			(type default)
		)
		(layer "In6.Cu")
	)
	(gr_line
		(start 105.358184 -56.000142)
		(end 105.358184 -55.000144)
		(stroke
			(width 0.2)
			(type default)
		)
		(layer "In6.Cu")
	)
	(gr_arc
		(start 105.358184 -55.000144)
		(mid 105.000044 -54.642004)
		(end 104.641904 -55.000144)
		(stroke
			(width 0.2)
			(type default)
		)
		(layer "In6.Cu")
	)
	(gr_line
		(start 105.358184 -53.000148)
		(end 105.358184 -52.00015)
		(stroke
			(width 0.2)
			(type default)
		)
		(layer "In6.Cu")
	)
	(gr_arc
		(start 105.358184 -52.00015)
		(mid 105.000044 -51.64201)
		(end 104.641904 -52.00015)
		(stroke
			(width 0.2)
			(type default)
		)
		(layer "In6.Cu")
	)
	(gr_line
		(start 105.438194 -108.88472)
		(end 105.438956 -108.885228)
		(stroke
			(width 0.2)
			(type default)
		)
		(layer "In6.Cu")
	)
	(gr_line
		(start 105.438194 -105.084626)
		(end 105.438956 -105.085134)
		(stroke
			(width 0.2)
			(type default)
		)
		(layer "In6.Cu")
	)
	(gr_line
		(start 105.438956 -108.885228)
		(end 106.189018 -107.48518)
		(stroke
			(width 0.2)
			(type default)
		)
		(layer "In6.Cu")
	)
	(gr_line
		(start 105.438956 -105.085134)
		(end 106.189018 -103.68534)
		(stroke
			(width 0.2)
			(type default)
		)
		(layer "In6.Cu")
	)
	(gr_line
		(start 105.48366 -116.509038)
		(end 106.233722 -115.10899)
		(stroke
			(width 0.2)
			(type default)
		)
		(layer "In6.Cu")
	)
	(gr_line
		(start 105.48366 -112.709198)
		(end 106.233722 -111.30915)
		(stroke
			(width 0.2)
			(type default)
		)
		(layer "In6.Cu")
	)
	(gr_arc
		(start 105.6386 -44.6278)
		(mid 105.653479 -44.663721)
		(end 105.6894 -44.6786)
		(stroke
			(width 0.2)
			(type default)
		)
		(layer "In6.Cu")
	)
	(gr_line
		(start 105.6386 -43.815)
		(end 105.6386 -44.6278)
		(stroke
			(width 0.2)
			(type default)
		)
		(layer "In6.Cu")
	)
	(gr_arc
		(start 105.641902 -55.999888)
		(mid 105.999915 -56.358282)
		(end 106.358182 -56.000142)
		(stroke
			(width 0.2)
			(type default)
		)
		(layer "In6.Cu")
	)
	(gr_line
		(start 105.641902 -55.000144)
		(end 105.641902 -55.999888)
		(stroke
			(width 0.2)
			(type default)
		)
		(layer "In6.Cu")
	)
	(gr_arc
		(start 105.641902 -51.999896)
		(mid 105.999915 -52.35829)
		(end 106.358182 -52.00015)
		(stroke
			(width 0.2)
			(type default)
		)
		(layer "In6.Cu")
	)
	(gr_line
		(start 105.641902 -51.000152)
		(end 105.641902 -51.999896)
		(stroke
			(width 0.2)
			(type default)
		)
		(layer "In6.Cu")
	)
	(gr_line
		(start 105.6894 -44.6786)
		(end 105.8926 -44.6786)
		(stroke
			(width 0.2)
			(type default)
		)
		(layer "In6.Cu")
	)
	(gr_arc
		(start 105.6894 -43.7642)
		(mid 105.653479 -43.779079)
		(end 105.6386 -43.815)
		(stroke
			(width 0.2)
			(type default)
		)
		(layer "In6.Cu")
	)
	(gr_arc
		(start 105.8926 -44.6786)
		(mid 105.928521 -44.663721)
		(end 105.9434 -44.6278)
		(stroke
			(width 0.2)
			(type default)
		)
		(layer "In6.Cu")
	)
	(gr_line
		(start 105.8926 -43.7642)
		(end 105.6894 -43.7642)
		(stroke
			(width 0.2)
			(type default)
		)
		(layer "In6.Cu")
	)
	(gr_line
		(start 105.9434 -44.6278)
		(end 105.9434 -43.815)
		(stroke
			(width 0.2)
			(type default)
		)
		(layer "In6.Cu")
	)
	(gr_arc
		(start 105.9434 -43.815)
		(mid 105.928521 -43.779079)
		(end 105.8926 -43.7642)
		(stroke
			(width 0.2)
			(type default)
		)
		(layer "In6.Cu")
	)
	(gr_arc
		(start 106.188256 -107.484672)
		(mid 105.984802 -106.811826)
		(end 105.311956 -107.01528)
		(stroke
			(width 0.2)
			(type default)
		)
		(layer "In6.Cu")
	)
	(gr_arc
		(start 106.188256 -103.684832)
		(mid 105.984802 -103.011986)
		(end 105.311956 -103.21544)
		(stroke
			(width 0.2)
			(type default)
		)
		(layer "In6.Cu")
	)
	(gr_line
		(start 106.189018 -107.48518)
		(end 106.188256 -107.484672)
		(stroke
			(width 0.2)
			(type default)
		)
		(layer "In6.Cu")
	)
	(gr_line
		(start 106.189018 -103.68534)
		(end 106.188256 -103.684832)
		(stroke
			(width 0.2)
			(type default)
		)
		(layer "In6.Cu")
	)
	(gr_arc
		(start 106.1974 -44.6278)
		(mid 106.212279 -44.663721)
		(end 106.2482 -44.6786)
		(stroke
			(width 0.2)
			(type default)
		)
		(layer "In6.Cu")
	)
	(gr_line
		(start 106.1974 -43.815)
		(end 106.1974 -44.6278)
		(stroke
			(width 0.2)
			(type default)
		)
		(layer "In6.Cu")
	)
	(gr_arc
		(start 106.233722 -115.10899)
		(mid 106.009186 -114.366294)
		(end 105.26649 -114.59083)
		(stroke
			(width 0.2)
			(type default)
		)
		(layer "In6.Cu")
	)
	(gr_arc
		(start 106.233722 -111.30915)
		(mid 106.009186 -110.566454)
		(end 105.26649 -110.79099)
		(stroke
			(width 0.2)
			(type default)
		)
		(layer "In6.Cu")
	)
	(gr_line
		(start 106.2482 -44.6786)
		(end 106.4514 -44.6786)
		(stroke
			(width 0.2)
			(type default)
		)
		(layer "In6.Cu")
	)
	(gr_arc
		(start 106.2482 -43.7642)
		(mid 106.212279 -43.779079)
		(end 106.1974 -43.815)
		(stroke
			(width 0.2)
			(type default)
		)
		(layer "In6.Cu")
	)
	(gr_line
		(start 106.358182 -56.000142)
		(end 106.358182 -55.000144)
		(stroke
			(width 0.2)
			(type default)
		)
		(layer "In6.Cu")
	)
	(gr_arc
		(start 106.358182 -55.000144)
		(mid 106.000042 -54.642004)
		(end 105.641902 -55.000144)
		(stroke
			(width 0.2)
			(type default)
		)
		(layer "In6.Cu")
	)
	(gr_line
		(start 106.358182 -52.00015)
		(end 106.358182 -51.000152)
		(stroke
			(width 0.2)
			(type default)
		)
		(layer "In6.Cu")
	)
	(gr_arc
		(start 106.358182 -51.000152)
		(mid 106.000042 -50.642012)
		(end 105.641902 -51.000152)
		(stroke
			(width 0.2)
			(type default)
		)
		(layer "In6.Cu")
	)
	(gr_line
		(start 106.361484 -11.20013)
		(end 106.361484 -9.800082)
		(stroke
			(width 0.2)
			(type default)
		)
		(layer "In6.Cu")
	)
	(gr_arc
		(start 106.361484 -9.800082)
		(mid 105.800144 -9.238742)
		(end 105.238804 -9.800082)
		(stroke
			(width 0.2)
			(type default)
		)
		(layer "In6.Cu")
	)
	(gr_line
		(start 106.361484 -3.999992)
		(end 106.361484 -2.600198)
		(stroke
			(width 0.2)
			(type default)
		)
		(layer "In6.Cu")
	)
	(gr_arc
		(start 106.361484 -2.600198)
		(mid 105.800144 -2.038858)
		(end 105.238804 -2.600198)
		(stroke
			(width 0.2)
			(type default)
		)
		(layer "In6.Cu")
	)
	(gr_arc
		(start 106.4514 -44.6786)
		(mid 106.487321 -44.663721)
		(end 106.5022 -44.6278)
		(stroke
			(width 0.2)
			(type default)
		)
		(layer "In6.Cu")
	)
	(gr_line
		(start 106.4514 -43.7642)
		(end 106.2482 -43.7642)
		(stroke
			(width 0.2)
			(type default)
		)
		(layer "In6.Cu")
	)
	(gr_line
		(start 106.5022 -44.6278)
		(end 106.5022 -43.815)
		(stroke
			(width 0.2)
			(type default)
		)
		(layer "In6.Cu")
	)
	(gr_arc
		(start 106.5022 -43.815)
		(mid 106.487321 -43.779079)
		(end 106.4514 -43.7642)
		(stroke
			(width 0.2)
			(type default)
		)
		(layer "In6.Cu")
	)
	(gr_arc
		(start 106.6419 -55.999888)
		(mid 106.999913 -56.358282)
		(end 107.35818 -56.000142)
		(stroke
			(width 0.2)
			(type default)
		)
		(layer "In6.Cu")
	)
	(gr_line
		(start 106.6419 -55.000144)
		(end 106.6419 -55.999888)
		(stroke
			(width 0.2)
			(type default)
		)
		(layer "In6.Cu")
	)
	(gr_arc
		(start 106.6419 -52.999894)
		(mid 106.999913 -53.358288)
		(end 107.35818 -53.000148)
		(stroke
			(width 0.2)
			(type default)
		)
		(layer "In6.Cu")
	)
	(gr_line
		(start 106.6419 -52.00015)
		(end 106.6419 -52.999894)
		(stroke
			(width 0.2)
			(type default)
		)
		(layer "In6.Cu")
	)
	(gr_arc
		(start 107.038648 -12.399772)
		(mid 107.599861 -12.961366)
		(end 108.161328 -12.400026)
		(stroke
			(width 0.2)
			(type default)
		)
		(layer "In6.Cu")
	)
	(gr_line
		(start 107.038648 -10.999978)
		(end 107.038648 -12.399772)
		(stroke
			(width 0.2)
			(type default)
		)
		(layer "In6.Cu")
	)
	(gr_arc
		(start 107.038648 -5.199888)
		(mid 107.599861 -5.761482)
		(end 108.161328 -5.200142)
		(stroke
			(width 0.2)
			(type default)
		)
		(layer "In6.Cu")
	)
	(gr_line
		(start 107.038648 -3.800094)
		(end 107.038648 -5.199888)
		(stroke
			(width 0.2)
			(type default)
		)
		(layer "In6.Cu")
	)
	(gr_arc
		(start 107.1626 -44.6278)
		(mid 107.177479 -44.663721)
		(end 107.2134 -44.6786)
		(stroke
			(width 0.2)
			(type default)
		)
		(layer "In6.Cu")
	)
	(gr_line
		(start 107.1626 -43.815)
		(end 107.1626 -44.6278)
		(stroke
			(width 0.2)
			(type default)
		)
		(layer "In6.Cu")
	)
	(gr_line
		(start 107.2134 -44.6786)
		(end 107.4166 -44.6786)
		(stroke
			(width 0.2)
			(type default)
		)
		(layer "In6.Cu")
	)
	(gr_arc
		(start 107.2134 -43.7642)
		(mid 107.177479 -43.779079)
		(end 107.1626 -43.815)
		(stroke
			(width 0.2)
			(type default)
		)
		(layer "In6.Cu")
	)
	(gr_line
		(start 107.35818 -56.000142)
		(end 107.35818 -55.000144)
		(stroke
			(width 0.2)
			(type default)
		)
		(layer "In6.Cu")
	)
	(gr_arc
		(start 107.35818 -55.000144)
		(mid 107.00004 -54.642004)
		(end 106.6419 -55.000144)
		(stroke
			(width 0.2)
			(type default)
		)
		(layer "In6.Cu")
	)
	(gr_line
		(start 107.35818 -53.000148)
		(end 107.35818 -52.00015)
		(stroke
			(width 0.2)
			(type default)
		)
		(layer "In6.Cu")
	)
	(gr_arc
		(start 107.35818 -52.00015)
		(mid 107.00004 -51.64201)
		(end 106.6419 -52.00015)
		(stroke
			(width 0.2)
			(type default)
		)
		(layer "In6.Cu")
	)
	(gr_arc
		(start 107.4166 -44.6786)
		(mid 107.452521 -44.663721)
		(end 107.4674 -44.6278)
		(stroke
			(width 0.2)
			(type default)
		)
		(layer "In6.Cu")
	)
	(gr_line
		(start 107.4166 -43.7642)
		(end 107.2134 -43.7642)
		(stroke
			(width 0.2)
			(type default)
		)
		(layer "In6.Cu")
	)
	(gr_line
		(start 107.4674 -44.6278)
		(end 107.4674 -43.815)
		(stroke
			(width 0.2)
			(type default)
		)
		(layer "In6.Cu")
	)
	(gr_arc
		(start 107.4674 -43.815)
		(mid 107.452521 -43.779079)
		(end 107.4166 -43.7642)
		(stroke
			(width 0.2)
			(type default)
		)
		(layer "In6.Cu")
	)
	(gr_arc
		(start 107.641898 -55.999888)
		(mid 107.999911 -56.358282)
		(end 108.358178 -56.000142)
		(stroke
			(width 0.2)
			(type default)
		)
		(layer "In6.Cu")
	)
	(gr_line
		(start 107.641898 -55.000144)
		(end 107.641898 -55.999888)
		(stroke
			(width 0.2)
			(type default)
		)
		(layer "In6.Cu")
	)
	(gr_arc
		(start 107.641898 -51.999896)
		(mid 107.999911 -52.35829)
		(end 108.358178 -52.00015)
		(stroke
			(width 0.2)
			(type default)
		)
		(layer "In6.Cu")
	)
	(gr_line
		(start 107.641898 -51.000152)
		(end 107.641898 -51.999896)
		(stroke
			(width 0.2)
			(type default)
		)
		(layer "In6.Cu")
	)
	(gr_arc
		(start 107.7214 -44.6278)
		(mid 107.736279 -44.663721)
		(end 107.7722 -44.6786)
		(stroke
			(width 0.2)
			(type default)
		)
		(layer "In6.Cu")
	)
	(gr_line
		(start 107.7214 -43.815)
		(end 107.7214 -44.6278)
		(stroke
			(width 0.2)
			(type default)
		)
		(layer "In6.Cu")
	)
	(gr_line
		(start 107.7722 -44.6786)
		(end 107.9754 -44.6786)
		(stroke
			(width 0.2)
			(type default)
		)
		(layer "In6.Cu")
	)
	(gr_arc
		(start 107.7722 -43.7642)
		(mid 107.736279 -43.779079)
		(end 107.7214 -43.815)
		(stroke
			(width 0.2)
			(type default)
		)
		(layer "In6.Cu")
	)
	(gr_arc
		(start 107.9754 -44.6786)
		(mid 108.011321 -44.663721)
		(end 108.0262 -44.6278)
		(stroke
			(width 0.2)
			(type default)
		)
		(layer "In6.Cu")
	)
	(gr_line
		(start 107.9754 -43.7642)
		(end 107.7722 -43.7642)
		(stroke
			(width 0.2)
			(type default)
		)
		(layer "In6.Cu")
	)
	(gr_line
		(start 108.0262 -44.6278)
		(end 108.0262 -43.815)
		(stroke
			(width 0.2)
			(type default)
		)
		(layer "In6.Cu")
	)
	(gr_arc
		(start 108.0262 -43.815)
		(mid 108.011321 -43.779079)
		(end 107.9754 -43.7642)
		(stroke
			(width 0.2)
			(type default)
		)
		(layer "In6.Cu")
	)
	(gr_line
		(start 108.161328 -12.400026)
		(end 108.161328 -10.999978)
		(stroke
			(width 0.2)
			(type default)
		)
		(layer "In6.Cu")
	)
	(gr_arc
		(start 108.161328 -10.999978)
		(mid 107.599988 -10.438638)
		(end 107.038648 -10.999978)
		(stroke
			(width 0.2)
			(type default)
		)
		(layer "In6.Cu")
	)
	(gr_line
		(start 108.161328 -5.200142)
		(end 108.161328 -3.800094)
		(stroke
			(width 0.2)
			(type default)
		)
		(layer "In6.Cu")
	)
	(gr_arc
		(start 108.161328 -3.800094)
		(mid 107.599988 -3.238754)
		(end 107.038648 -3.800094)
		(stroke
			(width 0.2)
			(type default)
		)
		(layer "In6.Cu")
	)
	(gr_line
		(start 108.358178 -56.000142)
		(end 108.358178 -55.000144)
		(stroke
			(width 0.2)
			(type default)
		)
		(layer "In6.Cu")
	)
	(gr_arc
		(start 108.358178 -55.000144)
		(mid 108.000038 -54.642004)
		(end 107.641898 -55.000144)
		(stroke
			(width 0.2)
			(type default)
		)
		(layer "In6.Cu")
	)
	(gr_line
		(start 108.358178 -52.00015)
		(end 108.358178 -51.000152)
		(stroke
			(width 0.2)
			(type default)
		)
		(layer "In6.Cu")
	)
	(gr_arc
		(start 108.358178 -51.000152)
		(mid 108.000038 -50.642012)
		(end 107.641898 -51.000152)
		(stroke
			(width 0.2)
			(type default)
		)
		(layer "In6.Cu")
	)
	(gr_arc
		(start 108.641896 -55.999888)
		(mid 108.999909 -56.358282)
		(end 109.358176 -56.000142)
		(stroke
			(width 0.2)
			(type default)
		)
		(layer "In6.Cu")
	)
	(gr_line
		(start 108.641896 -55.000144)
		(end 108.641896 -55.999888)
		(stroke
			(width 0.2)
			(type default)
		)
		(layer "In6.Cu")
	)
	(gr_arc
		(start 108.641896 -52.999894)
		(mid 108.999909 -53.358288)
		(end 109.358176 -53.000148)
		(stroke
			(width 0.2)
			(type default)
		)
		(layer "In6.Cu")
	)
	(gr_line
		(start 108.641896 -52.00015)
		(end 108.641896 -52.999894)
		(stroke
			(width 0.2)
			(type default)
		)
		(layer "In6.Cu")
	)
	(gr_arc
		(start 108.6866 -44.6278)
		(mid 108.701479 -44.663721)
		(end 108.7374 -44.6786)
		(stroke
			(width 0.2)
			(type default)
		)
		(layer "In6.Cu")
	)
	(gr_line
		(start 108.6866 -43.815)
		(end 108.6866 -44.6278)
		(stroke
			(width 0.2)
			(type default)
		)
		(layer "In6.Cu")
	)
	(gr_line
		(start 108.7374 -44.6786)
		(end 108.9406 -44.6786)
		(stroke
			(width 0.2)
			(type default)
		)
		(layer "In6.Cu")
	)
	(gr_arc
		(start 108.7374 -43.7642)
		(mid 108.701479 -43.779079)
		(end 108.6866 -43.815)
		(stroke
			(width 0.2)
			(type default)
		)
		(layer "In6.Cu")
	)
	(gr_arc
		(start 108.838746 -11.199876)
		(mid 109.399959 -11.76147)
		(end 109.961426 -11.20013)
		(stroke
			(width 0.2)
			(type default)
		)
		(layer "In6.Cu")
	)
	(gr_line
		(start 108.838746 -9.800082)
		(end 108.838746 -11.199876)
		(stroke
			(width 0.2)
			(type default)
		)
		(layer "In6.Cu")
	)
	(gr_arc
		(start 108.838746 -3.999738)
		(mid 109.399959 -4.561332)
		(end 109.961426 -3.999992)
		(stroke
			(width 0.2)
			(type default)
		)
		(layer "In6.Cu")
	)
	(gr_line
		(start 108.838746 -2.600198)
		(end 108.838746 -3.999738)
		(stroke
			(width 0.2)
			(type default)
		)
		(layer "In6.Cu")
	)
	(gr_arc
		(start 108.9406 -44.6786)
		(mid 108.976521 -44.663721)
		(end 108.9914 -44.6278)
		(stroke
			(width 0.2)
			(type default)
		)
		(layer "In6.Cu")
	)
	(gr_line
		(start 108.9406 -43.7642)
		(end 108.7374 -43.7642)
		(stroke
			(width 0.2)
			(type default)
		)
		(layer "In6.Cu")
	)
	(gr_line
		(start 108.9914 -44.6278)
		(end 108.9914 -43.815)
		(stroke
			(width 0.2)
			(type default)
		)
		(layer "In6.Cu")
	)
	(gr_arc
		(start 108.9914 -43.815)
		(mid 108.976521 -43.779079)
		(end 108.9406 -43.7642)
		(stroke
			(width 0.2)
			(type default)
		)
		(layer "In6.Cu")
	)
	(gr_arc
		(start 109.2454 -44.6278)
		(mid 109.260279 -44.663721)
		(end 109.2962 -44.6786)
		(stroke
			(width 0.2)
			(type default)
		)
		(layer "In6.Cu")
	)
	(gr_line
		(start 109.2454 -43.815)
		(end 109.2454 -44.6278)
		(stroke
			(width 0.2)
			(type default)
		)
		(layer "In6.Cu")
	)
	(gr_line
		(start 109.2962 -44.6786)
		(end 109.4994 -44.6786)
		(stroke
			(width 0.2)
			(type default)
		)
		(layer "In6.Cu")
	)
	(gr_arc
		(start 109.2962 -43.7642)
		(mid 109.260279 -43.779079)
		(end 109.2454 -43.815)
		(stroke
			(width 0.2)
			(type default)
		)
		(layer "In6.Cu")
	)
	(gr_line
		(start 109.358176 -56.000142)
		(end 109.358176 -55.000144)
		(stroke
			(width 0.2)
			(type default)
		)
		(layer "In6.Cu")
	)
	(gr_arc
		(start 109.358176 -55.000144)
		(mid 109.000036 -54.642004)
		(end 108.641896 -55.000144)
		(stroke
			(width 0.2)
			(type default)
		)
		(layer "In6.Cu")
	)
	(gr_line
		(start 109.358176 -53.000148)
		(end 109.358176 -52.00015)
		(stroke
			(width 0.2)
			(type default)
		)
		(layer "In6.Cu")
	)
	(gr_arc
		(start 109.358176 -52.00015)
		(mid 109.000036 -51.64201)
		(end 108.641896 -52.00015)
		(stroke
			(width 0.2)
			(type default)
		)
		(layer "In6.Cu")
	)
	(gr_arc
		(start 109.4994 -44.6786)
		(mid 109.535321 -44.663721)
		(end 109.5502 -44.6278)
		(stroke
			(width 0.2)
			(type default)
		)
		(layer "In6.Cu")
	)
	(gr_line
		(start 109.4994 -43.7642)
		(end 109.2962 -43.7642)
		(stroke
			(width 0.2)
			(type default)
		)
		(layer "In6.Cu")
	)
	(gr_line
		(start 109.5502 -44.6278)
		(end 109.5502 -43.815)
		(stroke
			(width 0.2)
			(type default)
		)
		(layer "In6.Cu")
	)
	(gr_arc
		(start 109.5502 -43.815)
		(mid 109.535321 -43.779079)
		(end 109.4994 -43.7642)
		(stroke
			(width 0.2)
			(type default)
		)
		(layer "In6.Cu")
	)
	(gr_arc
		(start 109.641894 -55.999888)
		(mid 109.999907 -56.358282)
		(end 110.358174 -56.000142)
		(stroke
			(width 0.2)
			(type default)
		)
		(layer "In6.Cu")
	)
	(gr_line
		(start 109.641894 -55.000144)
		(end 109.641894 -55.999888)
		(stroke
			(width 0.2)
			(type default)
		)
		(layer "In6.Cu")
	)
	(gr_arc
		(start 109.641894 -51.999896)
		(mid 109.999907 -52.35829)
		(end 110.358174 -52.00015)
		(stroke
			(width 0.2)
			(type default)
		)
		(layer "In6.Cu")
	)
	(gr_line
		(start 109.641894 -51.000152)
		(end 109.641894 -51.999896)
		(stroke
			(width 0.2)
			(type default)
		)
		(layer "In6.Cu")
	)
	(gr_line
		(start 109.961426 -11.20013)
		(end 109.961426 -9.800082)
		(stroke
			(width 0.2)
			(type default)
		)
		(layer "In6.Cu")
	)
	(gr_arc
		(start 109.961426 -9.800082)
		(mid 109.400086 -9.238742)
		(end 108.838746 -9.800082)
		(stroke
			(width 0.2)
			(type default)
		)
		(layer "In6.Cu")
	)
	(gr_line
		(start 109.961426 -3.999992)
		(end 109.961426 -2.600198)
		(stroke
			(width 0.2)
			(type default)
		)
		(layer "In6.Cu")
	)
	(gr_arc
		(start 109.961426 -2.600198)
		(mid 109.400086 -2.038858)
		(end 108.838746 -2.600198)
		(stroke
			(width 0.2)
			(type default)
		)
		(layer "In6.Cu")
	)
	(gr_arc
		(start 110.2106 -44.6278)
		(mid 110.225479 -44.663721)
		(end 110.2614 -44.6786)
		(stroke
			(width 0.2)
			(type default)
		)
		(layer "In6.Cu")
	)
	(gr_line
		(start 110.2106 -43.815)
		(end 110.2106 -44.6278)
		(stroke
			(width 0.2)
			(type default)
		)
		(layer "In6.Cu")
	)
	(gr_line
		(start 110.2614 -44.6786)
		(end 110.4646 -44.6786)
		(stroke
			(width 0.2)
			(type default)
		)
		(layer "In6.Cu")
	)
	(gr_arc
		(start 110.2614 -43.7642)
		(mid 110.225479 -43.779079)
		(end 110.2106 -43.815)
		(stroke
			(width 0.2)
			(type default)
		)
		(layer "In6.Cu")
	)
	(gr_line
		(start 110.358174 -56.000142)
		(end 110.358174 -55.000144)
		(stroke
			(width 0.2)
			(type default)
		)
		(layer "In6.Cu")
	)
	(gr_arc
		(start 110.358174 -55.000144)
		(mid 110.000034 -54.642004)
		(end 109.641894 -55.000144)
		(stroke
			(width 0.2)
			(type default)
		)
		(layer "In6.Cu")
	)
	(gr_line
		(start 110.358174 -52.00015)
		(end 110.358174 -51.000152)
		(stroke
			(width 0.2)
			(type default)
		)
		(layer "In6.Cu")
	)
	(gr_arc
		(start 110.358174 -51.000152)
		(mid 110.000034 -50.642012)
		(end 109.641894 -51.000152)
		(stroke
			(width 0.2)
			(type default)
		)
		(layer "In6.Cu")
	)
	(gr_arc
		(start 110.4646 -44.6786)
		(mid 110.500521 -44.663721)
		(end 110.5154 -44.6278)
		(stroke
			(width 0.2)
			(type default)
		)
		(layer "In6.Cu")
	)
	(gr_line
		(start 110.4646 -43.7642)
		(end 110.2614 -43.7642)
		(stroke
			(width 0.2)
			(type default)
		)
		(layer "In6.Cu")
	)
	(gr_line
		(start 110.5154 -44.6278)
		(end 110.5154 -43.815)
		(stroke
			(width 0.2)
			(type default)
		)
		(layer "In6.Cu")
	)
	(gr_arc
		(start 110.5154 -43.815)
		(mid 110.500521 -43.779079)
		(end 110.4646 -43.7642)
		(stroke
			(width 0.2)
			(type default)
		)
		(layer "In6.Cu")
	)
	(gr_arc
		(start 110.638844 -12.399772)
		(mid 111.200057 -12.961366)
		(end 111.761524 -12.400026)
		(stroke
			(width 0.2)
			(type default)
		)
		(layer "In6.Cu")
	)
	(gr_line
		(start 110.638844 -10.999978)
		(end 110.638844 -12.399772)
		(stroke
			(width 0.2)
			(type default)
		)
		(layer "In6.Cu")
	)
	(gr_arc
		(start 110.638844 -5.199888)
		(mid 111.200057 -5.761482)
		(end 111.761524 -5.200142)
		(stroke
			(width 0.2)
			(type default)
		)
		(layer "In6.Cu")
	)
	(gr_line
		(start 110.638844 -3.800094)
		(end 110.638844 -5.199888)
		(stroke
			(width 0.2)
			(type default)
		)
		(layer "In6.Cu")
	)
	(gr_arc
		(start 110.641892 -55.999888)
		(mid 110.999905 -56.358282)
		(end 111.358172 -56.000142)
		(stroke
			(width 0.2)
			(type default)
		)
		(layer "In6.Cu")
	)
	(gr_line
		(start 110.641892 -55.000144)
		(end 110.641892 -55.999888)
		(stroke
			(width 0.2)
			(type default)
		)
		(layer "In6.Cu")
	)
	(gr_arc
		(start 110.641892 -52.999894)
		(mid 110.999905 -53.358288)
		(end 111.358172 -53.000148)
		(stroke
			(width 0.2)
			(type default)
		)
		(layer "In6.Cu")
	)
	(gr_line
		(start 110.641892 -52.00015)
		(end 110.641892 -52.999894)
		(stroke
			(width 0.2)
			(type default)
		)
		(layer "In6.Cu")
	)
	(gr_arc
		(start 110.7694 -44.6278)
		(mid 110.784279 -44.663721)
		(end 110.8202 -44.6786)
		(stroke
			(width 0.2)
			(type default)
		)
		(layer "In6.Cu")
	)
	(gr_line
		(start 110.7694 -43.815)
		(end 110.7694 -44.6278)
		(stroke
			(width 0.2)
			(type default)
		)
		(layer "In6.Cu")
	)
	(gr_line
		(start 110.8202 -44.6786)
		(end 111.0234 -44.6786)
		(stroke
			(width 0.2)
			(type default)
		)
		(layer "In6.Cu")
	)
	(gr_arc
		(start 110.8202 -43.7642)
		(mid 110.784279 -43.779079)
		(end 110.7694 -43.815)
		(stroke
			(width 0.2)
			(type default)
		)
		(layer "In6.Cu")
	)
	(gr_arc
		(start 111.0234 -44.6786)
		(mid 111.059321 -44.663721)
		(end 111.0742 -44.6278)
		(stroke
			(width 0.2)
			(type default)
		)
		(layer "In6.Cu")
	)
	(gr_line
		(start 111.0234 -43.7642)
		(end 110.8202 -43.7642)
		(stroke
			(width 0.2)
			(type default)
		)
		(layer "In6.Cu")
	)
	(gr_line
		(start 111.0742 -44.6278)
		(end 111.0742 -43.815)
		(stroke
			(width 0.2)
			(type default)
		)
		(layer "In6.Cu")
	)
	(gr_arc
		(start 111.0742 -43.815)
		(mid 111.059321 -43.779079)
		(end 111.0234 -43.7642)
		(stroke
			(width 0.2)
			(type default)
		)
		(layer "In6.Cu")
	)
	(gr_line
		(start 111.358172 -56.000142)
		(end 111.358172 -55.000144)
		(stroke
			(width 0.2)
			(type default)
		)
		(layer "In6.Cu")
	)
	(gr_arc
		(start 111.358172 -55.000144)
		(mid 111.000032 -54.642004)
		(end 110.641892 -55.000144)
		(stroke
			(width 0.2)
			(type default)
		)
		(layer "In6.Cu")
	)
	(gr_line
		(start 111.358172 -53.000148)
		(end 111.358172 -52.00015)
		(stroke
			(width 0.2)
			(type default)
		)
		(layer "In6.Cu")
	)
	(gr_arc
		(start 111.358172 -52.00015)
		(mid 111.000032 -51.64201)
		(end 110.641892 -52.00015)
		(stroke
			(width 0.2)
			(type default)
		)
		(layer "In6.Cu")
	)
	(gr_arc
		(start 111.64189 -55.999888)
		(mid 111.999903 -56.358282)
		(end 112.35817 -56.000142)
		(stroke
			(width 0.2)
			(type default)
		)
		(layer "In6.Cu")
	)
	(gr_line
		(start 111.64189 -55.000144)
		(end 111.64189 -55.999888)
		(stroke
			(width 0.2)
			(type default)
		)
		(layer "In6.Cu")
	)
	(gr_arc
		(start 111.64189 -51.999896)
		(mid 111.999903 -52.35829)
		(end 112.35817 -52.00015)
		(stroke
			(width 0.2)
			(type default)
		)
		(layer "In6.Cu")
	)
	(gr_line
		(start 111.64189 -51.000152)
		(end 111.64189 -51.999896)
		(stroke
			(width 0.2)
			(type default)
		)
		(layer "In6.Cu")
	)
	(gr_arc
		(start 111.7346 -44.6278)
		(mid 111.749479 -44.663721)
		(end 111.7854 -44.6786)
		(stroke
			(width 0.2)
			(type default)
		)
		(layer "In6.Cu")
	)
	(gr_line
		(start 111.7346 -43.815)
		(end 111.7346 -44.6278)
		(stroke
			(width 0.2)
			(type default)
		)
		(layer "In6.Cu")
	)
	(gr_line
		(start 111.761524 -12.400026)
		(end 111.761524 -10.999978)
		(stroke
			(width 0.2)
			(type default)
		)
		(layer "In6.Cu")
	)
	(gr_arc
		(start 111.761524 -10.999978)
		(mid 111.200184 -10.438638)
		(end 110.638844 -10.999978)
		(stroke
			(width 0.2)
			(type default)
		)
		(layer "In6.Cu")
	)
	(gr_line
		(start 111.761524 -5.200142)
		(end 111.761524 -3.800094)
		(stroke
			(width 0.2)
			(type default)
		)
		(layer "In6.Cu")
	)
	(gr_arc
		(start 111.761524 -3.800094)
		(mid 111.200184 -3.238754)
		(end 110.638844 -3.800094)
		(stroke
			(width 0.2)
			(type default)
		)
		(layer "In6.Cu")
	)
	(gr_line
		(start 111.7854 -44.6786)
		(end 111.9886 -44.6786)
		(stroke
			(width 0.2)
			(type default)
		)
		(layer "In6.Cu")
	)
	(gr_arc
		(start 111.7854 -43.7642)
		(mid 111.749479 -43.779079)
		(end 111.7346 -43.815)
		(stroke
			(width 0.2)
			(type default)
		)
		(layer "In6.Cu")
	)
	(gr_arc
		(start 111.9886 -44.6786)
		(mid 112.024521 -44.663721)
		(end 112.0394 -44.6278)
		(stroke
			(width 0.2)
			(type default)
		)
		(layer "In6.Cu")
	)
	(gr_line
		(start 111.9886 -43.7642)
		(end 111.7854 -43.7642)
		(stroke
			(width 0.2)
			(type default)
		)
		(layer "In6.Cu")
	)
	(gr_line
		(start 112.0394 -44.6278)
		(end 112.0394 -43.815)
		(stroke
			(width 0.2)
			(type default)
		)
		(layer "In6.Cu")
	)
	(gr_arc
		(start 112.0394 -43.815)
		(mid 112.024521 -43.779079)
		(end 111.9886 -43.7642)
		(stroke
			(width 0.2)
			(type default)
		)
		(layer "In6.Cu")
	)
	(gr_arc
		(start 112.2934 -44.6278)
		(mid 112.308279 -44.663721)
		(end 112.3442 -44.6786)
		(stroke
			(width 0.2)
			(type default)
		)
		(layer "In6.Cu")
	)
	(gr_line
		(start 112.2934 -43.815)
		(end 112.2934 -44.6278)
		(stroke
			(width 0.2)
			(type default)
		)
		(layer "In6.Cu")
	)
	(gr_line
		(start 112.3442 -44.6786)
		(end 112.5474 -44.6786)
		(stroke
			(width 0.2)
			(type default)
		)
		(layer "In6.Cu")
	)
	(gr_arc
		(start 112.3442 -43.7642)
		(mid 112.308279 -43.779079)
		(end 112.2934 -43.815)
		(stroke
			(width 0.2)
			(type default)
		)
		(layer "In6.Cu")
	)
	(gr_line
		(start 112.35817 -56.000142)
		(end 112.35817 -55.000144)
		(stroke
			(width 0.2)
			(type default)
		)
		(layer "In6.Cu")
	)
	(gr_arc
		(start 112.35817 -55.000144)
		(mid 112.00003 -54.642004)
		(end 111.64189 -55.000144)
		(stroke
			(width 0.2)
			(type default)
		)
		(layer "In6.Cu")
	)
	(gr_line
		(start 112.35817 -52.00015)
		(end 112.35817 -51.000152)
		(stroke
			(width 0.2)
			(type default)
		)
		(layer "In6.Cu")
	)
	(gr_arc
		(start 112.35817 -51.000152)
		(mid 112.00003 -50.642012)
		(end 111.64189 -51.000152)
		(stroke
			(width 0.2)
			(type default)
		)
		(layer "In6.Cu")
	)
	(gr_arc
		(start 112.438688 -11.199876)
		(mid 112.999901 -11.76147)
		(end 113.561368 -11.20013)
		(stroke
			(width 0.2)
			(type default)
		)
		(layer "In6.Cu")
	)
	(gr_line
		(start 112.438688 -9.800082)
		(end 112.438688 -11.199876)
		(stroke
			(width 0.2)
			(type default)
		)
		(layer "In6.Cu")
	)
	(gr_arc
		(start 112.438688 -3.999738)
		(mid 112.999901 -4.561332)
		(end 113.561368 -3.999992)
		(stroke
			(width 0.2)
			(type default)
		)
		(layer "In6.Cu")
	)
	(gr_line
		(start 112.438688 -2.600198)
		(end 112.438688 -3.999738)
		(stroke
			(width 0.2)
			(type default)
		)
		(layer "In6.Cu")
	)
	(gr_line
		(start 112.499902 -126.000002)
		(end 97.499932 -126.000002)
		(stroke
			(width 1.524)
			(type default)
		)
		(layer "In6.Cu")
	)
	(gr_arc
		(start 112.5474 -44.6786)
		(mid 112.583321 -44.663721)
		(end 112.5982 -44.6278)
		(stroke
			(width 0.2)
			(type default)
		)
		(layer "In6.Cu")
	)
	(gr_line
		(start 112.5474 -43.7642)
		(end 112.3442 -43.7642)
		(stroke
			(width 0.2)
			(type default)
		)
		(layer "In6.Cu")
	)
	(gr_line
		(start 112.5982 -44.6278)
		(end 112.5982 -43.815)
		(stroke
			(width 0.2)
			(type default)
		)
		(layer "In6.Cu")
	)
	(gr_arc
		(start 112.5982 -43.815)
		(mid 112.583321 -43.779079)
		(end 112.5474 -43.7642)
		(stroke
			(width 0.2)
			(type default)
		)
		(layer "In6.Cu")
	)
	(gr_arc
		(start 112.641888 -55.999888)
		(mid 112.999901 -56.358282)
		(end 113.358168 -56.000142)
		(stroke
			(width 0.2)
			(type default)
		)
		(layer "In6.Cu")
	)
	(gr_line
		(start 112.641888 -55.000144)
		(end 112.641888 -55.999888)
		(stroke
			(width 0.2)
			(type default)
		)
		(layer "In6.Cu")
	)
	(gr_arc
		(start 112.641888 -52.999894)
		(mid 112.999901 -53.358288)
		(end 113.358168 -53.000148)
		(stroke
			(width 0.2)
			(type default)
		)
		(layer "In6.Cu")
	)
	(gr_line
		(start 112.641888 -52.00015)
		(end 112.641888 -52.999894)
		(stroke
			(width 0.2)
			(type default)
		)
		(layer "In6.Cu")
	)
	(gr_arc
		(start 113.2586 -44.6278)
		(mid 113.273479 -44.663721)
		(end 113.3094 -44.6786)
		(stroke
			(width 0.2)
			(type default)
		)
		(layer "In6.Cu")
	)
	(gr_line
		(start 113.2586 -43.815)
		(end 113.2586 -44.6278)
		(stroke
			(width 0.2)
			(type default)
		)
		(layer "In6.Cu")
	)
	(gr_line
		(start 113.3094 -44.6786)
		(end 113.5126 -44.6786)
		(stroke
			(width 0.2)
			(type default)
		)
		(layer "In6.Cu")
	)
	(gr_arc
		(start 113.3094 -43.7642)
		(mid 113.273479 -43.779079)
		(end 113.2586 -43.815)
		(stroke
			(width 0.2)
			(type default)
		)
		(layer "In6.Cu")
	)
	(gr_line
		(start 113.358168 -56.000142)
		(end 113.358168 -55.000144)
		(stroke
			(width 0.2)
			(type default)
		)
		(layer "In6.Cu")
	)
	(gr_arc
		(start 113.358168 -55.000144)
		(mid 113.000028 -54.642004)
		(end 112.641888 -55.000144)
		(stroke
			(width 0.2)
			(type default)
		)
		(layer "In6.Cu")
	)
	(gr_line
		(start 113.358168 -53.000148)
		(end 113.358168 -52.00015)
		(stroke
			(width 0.2)
			(type default)
		)
		(layer "In6.Cu")
	)
	(gr_arc
		(start 113.358168 -52.00015)
		(mid 113.000028 -51.64201)
		(end 112.641888 -52.00015)
		(stroke
			(width 0.2)
			(type default)
		)
		(layer "In6.Cu")
	)
	(gr_arc
		(start 113.5126 -44.6786)
		(mid 113.548521 -44.663721)
		(end 113.5634 -44.6278)
		(stroke
			(width 0.2)
			(type default)
		)
		(layer "In6.Cu")
	)
	(gr_line
		(start 113.5126 -43.7642)
		(end 113.3094 -43.7642)
		(stroke
			(width 0.2)
			(type default)
		)
		(layer "In6.Cu")
	)
	(gr_line
		(start 113.561368 -11.20013)
		(end 113.561368 -9.800082)
		(stroke
			(width 0.2)
			(type default)
		)
		(layer "In6.Cu")
	)
	(gr_arc
		(start 113.561368 -9.800082)
		(mid 113.000028 -9.238742)
		(end 112.438688 -9.800082)
		(stroke
			(width 0.2)
			(type default)
		)
		(layer "In6.Cu")
	)
	(gr_line
		(start 113.561368 -3.999992)
		(end 113.561368 -2.600198)
		(stroke
			(width 0.2)
			(type default)
		)
		(layer "In6.Cu")
	)
	(gr_arc
		(start 113.561368 -2.600198)
		(mid 113.000028 -2.038858)
		(end 112.438688 -2.600198)
		(stroke
			(width 0.2)
			(type default)
		)
		(layer "In6.Cu")
	)
	(gr_line
		(start 113.5634 -44.6278)
		(end 113.5634 -43.815)
		(stroke
			(width 0.2)
			(type default)
		)
		(layer "In6.Cu")
	)
	(gr_arc
		(start 113.5634 -43.815)
		(mid 113.548521 -43.779079)
		(end 113.5126 -43.7642)
		(stroke
			(width 0.2)
			(type default)
		)
		(layer "In6.Cu")
	)
	(gr_arc
		(start 113.641886 -55.999888)
		(mid 113.999899 -56.358282)
		(end 114.358166 -56.000142)
		(stroke
			(width 0.2)
			(type default)
		)
		(layer "In6.Cu")
	)
	(gr_line
		(start 113.641886 -55.000144)
		(end 113.641886 -55.999888)
		(stroke
			(width 0.2)
			(type default)
		)
		(layer "In6.Cu")
	)
	(gr_arc
		(start 113.641886 -51.999896)
		(mid 113.999899 -52.35829)
		(end 114.358166 -52.00015)
		(stroke
			(width 0.2)
			(type default)
		)
		(layer "In6.Cu")
	)
	(gr_line
		(start 113.641886 -51.000152)
		(end 113.641886 -51.999896)
		(stroke
			(width 0.2)
			(type default)
		)
		(layer "In6.Cu")
	)
	(gr_arc
		(start 113.8174 -44.6278)
		(mid 113.832279 -44.663721)
		(end 113.8682 -44.6786)
		(stroke
			(width 0.2)
			(type default)
		)
		(layer "In6.Cu")
	)
	(gr_line
		(start 113.8174 -43.815)
		(end 113.8174 -44.6278)
		(stroke
			(width 0.2)
			(type default)
		)
		(layer "In6.Cu")
	)
	(gr_line
		(start 113.8682 -44.6786)
		(end 114.0714 -44.6786)
		(stroke
			(width 0.2)
			(type default)
		)
		(layer "In6.Cu")
	)
	(gr_arc
		(start 113.8682 -43.7642)
		(mid 113.832279 -43.779079)
		(end 113.8174 -43.815)
		(stroke
			(width 0.2)
			(type default)
		)
		(layer "In6.Cu")
	)
	(gr_arc
		(start 114.0714 -44.6786)
		(mid 114.107321 -44.663721)
		(end 114.1222 -44.6278)
		(stroke
			(width 0.2)
			(type default)
		)
		(layer "In6.Cu")
	)
	(gr_line
		(start 114.0714 -43.7642)
		(end 113.8682 -43.7642)
		(stroke
			(width 0.2)
			(type default)
		)
		(layer "In6.Cu")
	)
	(gr_line
		(start 114.1222 -44.6278)
		(end 114.1222 -43.815)
		(stroke
			(width 0.2)
			(type default)
		)
		(layer "In6.Cu")
	)
	(gr_arc
		(start 114.1222 -43.815)
		(mid 114.107321 -43.779079)
		(end 114.0714 -43.7642)
		(stroke
			(width 0.2)
			(type default)
		)
		(layer "In6.Cu")
	)
	(gr_arc
		(start 114.238786 -12.399772)
		(mid 114.799999 -12.961366)
		(end 115.361466 -12.400026)
		(stroke
			(width 0.2)
			(type default)
		)
		(layer "In6.Cu")
	)
	(gr_line
		(start 114.238786 -10.999978)
		(end 114.238786 -12.399772)
		(stroke
			(width 0.2)
			(type default)
		)
		(layer "In6.Cu")
	)
	(gr_arc
		(start 114.238786 -5.199888)
		(mid 114.799999 -5.761482)
		(end 115.361466 -5.200142)
		(stroke
			(width 0.2)
			(type default)
		)
		(layer "In6.Cu")
	)
	(gr_line
		(start 114.238786 -3.800094)
		(end 114.238786 -5.199888)
		(stroke
			(width 0.2)
			(type default)
		)
		(layer "In6.Cu")
	)
	(gr_line
		(start 114.358166 -56.000142)
		(end 114.358166 -55.000144)
		(stroke
			(width 0.2)
			(type default)
		)
		(layer "In6.Cu")
	)
	(gr_arc
		(start 114.358166 -55.000144)
		(mid 114.000026 -54.642004)
		(end 113.641886 -55.000144)
		(stroke
			(width 0.2)
			(type default)
		)
		(layer "In6.Cu")
	)
	(gr_line
		(start 114.358166 -52.00015)
		(end 114.358166 -51.000152)
		(stroke
			(width 0.2)
			(type default)
		)
		(layer "In6.Cu")
	)
	(gr_arc
		(start 114.358166 -51.000152)
		(mid 114.000026 -50.642012)
		(end 113.641886 -51.000152)
		(stroke
			(width 0.2)
			(type default)
		)
		(layer "In6.Cu")
	)
	(gr_arc
		(start 114.7826 -44.6278)
		(mid 114.797479 -44.663721)
		(end 114.8334 -44.6786)
		(stroke
			(width 0.2)
			(type default)
		)
		(layer "In6.Cu")
	)
	(gr_line
		(start 114.7826 -43.815)
		(end 114.7826 -44.6278)
		(stroke
			(width 0.2)
			(type default)
		)
		(layer "In6.Cu")
	)
	(gr_line
		(start 114.8334 -44.6786)
		(end 115.0366 -44.6786)
		(stroke
			(width 0.2)
			(type default)
		)
		(layer "In6.Cu")
	)
	(gr_arc
		(start 114.8334 -43.7642)
		(mid 114.797479 -43.779079)
		(end 114.7826 -43.815)
		(stroke
			(width 0.2)
			(type default)
		)
		(layer "In6.Cu")
	)
	(gr_arc
		(start 115.0366 -44.6786)
		(mid 115.072521 -44.663721)
		(end 115.0874 -44.6278)
		(stroke
			(width 0.2)
			(type default)
		)
		(layer "In6.Cu")
	)
	(gr_line
		(start 115.0366 -43.7642)
		(end 114.8334 -43.7642)
		(stroke
			(width 0.2)
			(type default)
		)
		(layer "In6.Cu")
	)
	(gr_line
		(start 115.0874 -44.6278)
		(end 115.0874 -43.815)
		(stroke
			(width 0.2)
			(type default)
		)
		(layer "In6.Cu")
	)
	(gr_arc
		(start 115.0874 -43.815)
		(mid 115.072521 -43.779079)
		(end 115.0366 -43.7642)
		(stroke
			(width 0.2)
			(type default)
		)
		(layer "In6.Cu")
	)
	(gr_arc
		(start 115.3414 -44.6278)
		(mid 115.356279 -44.663721)
		(end 115.3922 -44.6786)
		(stroke
			(width 0.2)
			(type default)
		)
		(layer "In6.Cu")
	)
	(gr_line
		(start 115.3414 -43.815)
		(end 115.3414 -44.6278)
		(stroke
			(width 0.2)
			(type default)
		)
		(layer "In6.Cu")
	)
	(gr_line
		(start 115.361466 -12.400026)
		(end 115.361466 -10.999978)
		(stroke
			(width 0.2)
			(type default)
		)
		(layer "In6.Cu")
	)
	(gr_arc
		(start 115.361466 -10.999978)
		(mid 114.800126 -10.438638)
		(end 114.238786 -10.999978)
		(stroke
			(width 0.2)
			(type default)
		)
		(layer "In6.Cu")
	)
	(gr_line
		(start 115.361466 -5.200142)
		(end 115.361466 -3.800094)
		(stroke
			(width 0.2)
			(type default)
		)
		(layer "In6.Cu")
	)
	(gr_arc
		(start 115.361466 -3.800094)
		(mid 114.800126 -3.238754)
		(end 114.238786 -3.800094)
		(stroke
			(width 0.2)
			(type default)
		)
		(layer "In6.Cu")
	)
	(gr_line
		(start 115.3922 -44.6786)
		(end 115.5954 -44.6786)
		(stroke
			(width 0.2)
			(type default)
		)
		(layer "In6.Cu")
	)
	(gr_arc
		(start 115.3922 -43.7642)
		(mid 115.356279 -43.779079)
		(end 115.3414 -43.815)
		(stroke
			(width 0.2)
			(type default)
		)
		(layer "In6.Cu")
	)
	(gr_arc
		(start 115.5954 -44.6786)
		(mid 115.631321 -44.663721)
		(end 115.6462 -44.6278)
		(stroke
			(width 0.2)
			(type default)
		)
		(layer "In6.Cu")
	)
	(gr_line
		(start 115.5954 -43.7642)
		(end 115.3922 -43.7642)
		(stroke
			(width 0.2)
			(type default)
		)
		(layer "In6.Cu")
	)
	(gr_arc
		(start 115.641882 -55.999888)
		(mid 115.999895 -56.358282)
		(end 116.358162 -56.000142)
		(stroke
			(width 0.2)
			(type default)
		)
		(layer "In6.Cu")
	)
	(gr_line
		(start 115.641882 -55.000144)
		(end 115.641882 -55.999888)
		(stroke
			(width 0.2)
			(type default)
		)
		(layer "In6.Cu")
	)
	(gr_arc
		(start 115.641882 -52.999894)
		(mid 115.999895 -53.358288)
		(end 116.358162 -53.000148)
		(stroke
			(width 0.2)
			(type default)
		)
		(layer "In6.Cu")
	)
	(gr_line
		(start 115.641882 -52.00015)
		(end 115.641882 -52.999894)
		(stroke
			(width 0.2)
			(type default)
		)
		(layer "In6.Cu")
	)
	(gr_line
		(start 115.6462 -44.6278)
		(end 115.6462 -43.815)
		(stroke
			(width 0.2)
			(type default)
		)
		(layer "In6.Cu")
	)
	(gr_arc
		(start 115.6462 -43.815)
		(mid 115.631321 -43.779079)
		(end 115.5954 -43.7642)
		(stroke
			(width 0.2)
			(type default)
		)
		(layer "In6.Cu")
	)
	(gr_arc
		(start 116.03863 -11.199876)
		(mid 116.599843 -11.76147)
		(end 117.16131 -11.20013)
		(stroke
			(width 0.2)
			(type default)
		)
		(layer "In6.Cu")
	)
	(gr_line
		(start 116.03863 -9.800082)
		(end 116.03863 -11.199876)
		(stroke
			(width 0.2)
			(type default)
		)
		(layer "In6.Cu")
	)
	(gr_arc
		(start 116.03863 -3.999738)
		(mid 116.599843 -4.561332)
		(end 117.16131 -3.999992)
		(stroke
			(width 0.2)
			(type default)
		)
		(layer "In6.Cu")
	)
	(gr_line
		(start 116.03863 -2.600198)
		(end 116.03863 -3.999738)
		(stroke
			(width 0.2)
			(type default)
		)
		(layer "In6.Cu")
	)
	(gr_arc
		(start 116.3066 -44.6278)
		(mid 116.321479 -44.663721)
		(end 116.3574 -44.6786)
		(stroke
			(width 0.2)
			(type default)
		)
		(layer "In6.Cu")
	)
	(gr_line
		(start 116.3066 -43.815)
		(end 116.3066 -44.6278)
		(stroke
			(width 0.2)
			(type default)
		)
		(layer "In6.Cu")
	)
	(gr_line
		(start 116.3574 -44.6786)
		(end 116.5606 -44.6786)
		(stroke
			(width 0.2)
			(type default)
		)
		(layer "In6.Cu")
	)
	(gr_arc
		(start 116.3574 -43.7642)
		(mid 116.321479 -43.779079)
		(end 116.3066 -43.815)
		(stroke
			(width 0.2)
			(type default)
		)
		(layer "In6.Cu")
	)
	(gr_line
		(start 116.358162 -56.000142)
		(end 116.358162 -55.000144)
		(stroke
			(width 0.2)
			(type default)
		)
		(layer "In6.Cu")
	)
	(gr_arc
		(start 116.358162 -55.000144)
		(mid 116.000022 -54.642004)
		(end 115.641882 -55.000144)
		(stroke
			(width 0.2)
			(type default)
		)
		(layer "In6.Cu")
	)
	(gr_line
		(start 116.358162 -53.000148)
		(end 116.358162 -52.00015)
		(stroke
			(width 0.2)
			(type default)
		)
		(layer "In6.Cu")
	)
	(gr_arc
		(start 116.358162 -52.00015)
		(mid 116.000022 -51.64201)
		(end 115.641882 -52.00015)
		(stroke
			(width 0.2)
			(type default)
		)
		(layer "In6.Cu")
	)
	(gr_arc
		(start 116.5606 -44.6786)
		(mid 116.596521 -44.663721)
		(end 116.6114 -44.6278)
		(stroke
			(width 0.2)
			(type default)
		)
		(layer "In6.Cu")
	)
	(gr_line
		(start 116.5606 -43.7642)
		(end 116.3574 -43.7642)
		(stroke
			(width 0.2)
			(type default)
		)
		(layer "In6.Cu")
	)
	(gr_line
		(start 116.6114 -44.6278)
		(end 116.6114 -43.815)
		(stroke
			(width 0.2)
			(type default)
		)
		(layer "In6.Cu")
	)
	(gr_arc
		(start 116.6114 -43.815)
		(mid 116.596521 -43.779079)
		(end 116.5606 -43.7642)
		(stroke
			(width 0.2)
			(type default)
		)
		(layer "In6.Cu")
	)
	(gr_arc
		(start 116.64188 -55.999888)
		(mid 116.999893 -56.358282)
		(end 117.35816 -56.000142)
		(stroke
			(width 0.2)
			(type default)
		)
		(layer "In6.Cu")
	)
	(gr_line
		(start 116.64188 -55.000144)
		(end 116.64188 -55.999888)
		(stroke
			(width 0.2)
			(type default)
		)
		(layer "In6.Cu")
	)
	(gr_arc
		(start 116.64188 -51.999896)
		(mid 116.999893 -52.35829)
		(end 117.35816 -52.00015)
		(stroke
			(width 0.2)
			(type default)
		)
		(layer "In6.Cu")
	)
	(gr_line
		(start 116.64188 -51.000152)
		(end 116.64188 -51.999896)
		(stroke
			(width 0.2)
			(type default)
		)
		(layer "In6.Cu")
	)
	(gr_arc
		(start 116.8654 -44.6278)
		(mid 116.880279 -44.663721)
		(end 116.9162 -44.6786)
		(stroke
			(width 0.2)
			(type default)
		)
		(layer "In6.Cu")
	)
	(gr_line
		(start 116.8654 -43.815)
		(end 116.8654 -44.6278)
		(stroke
			(width 0.2)
			(type default)
		)
		(layer "In6.Cu")
	)
	(gr_line
		(start 116.9162 -44.6786)
		(end 117.1194 -44.6786)
		(stroke
			(width 0.2)
			(type default)
		)
		(layer "In6.Cu")
	)
	(gr_arc
		(start 116.9162 -43.7642)
		(mid 116.880279 -43.779079)
		(end 116.8654 -43.815)
		(stroke
			(width 0.2)
			(type default)
		)
		(layer "In6.Cu")
	)
	(gr_arc
		(start 117.1194 -44.6786)
		(mid 117.155321 -44.663721)
		(end 117.1702 -44.6278)
		(stroke
			(width 0.2)
			(type default)
		)
		(layer "In6.Cu")
	)
	(gr_line
		(start 117.1194 -43.7642)
		(end 116.9162 -43.7642)
		(stroke
			(width 0.2)
			(type default)
		)
		(layer "In6.Cu")
	)
	(gr_line
		(start 117.16131 -11.20013)
		(end 117.16131 -9.800082)
		(stroke
			(width 0.2)
			(type default)
		)
		(layer "In6.Cu")
	)
	(gr_arc
		(start 117.16131 -9.800082)
		(mid 116.59997 -9.238742)
		(end 116.03863 -9.800082)
		(stroke
			(width 0.2)
			(type default)
		)
		(layer "In6.Cu")
	)
	(gr_line
		(start 117.16131 -3.999992)
		(end 117.16131 -2.600198)
		(stroke
			(width 0.2)
			(type default)
		)
		(layer "In6.Cu")
	)
	(gr_arc
		(start 117.16131 -2.600198)
		(mid 116.59997 -2.038858)
		(end 116.03863 -2.600198)
		(stroke
			(width 0.2)
			(type default)
		)
		(layer "In6.Cu")
	)
	(gr_line
		(start 117.1702 -44.6278)
		(end 117.1702 -43.815)
		(stroke
			(width 0.2)
			(type default)
		)
		(layer "In6.Cu")
	)
	(gr_arc
		(start 117.1702 -43.815)
		(mid 117.155321 -43.779079)
		(end 117.1194 -43.7642)
		(stroke
			(width 0.2)
			(type default)
		)
		(layer "In6.Cu")
	)
	(gr_line
		(start 117.35816 -56.000142)
		(end 117.35816 -55.000144)
		(stroke
			(width 0.2)
			(type default)
		)
		(layer "In6.Cu")
	)
	(gr_arc
		(start 117.35816 -55.000144)
		(mid 117.00002 -54.642004)
		(end 116.64188 -55.000144)
		(stroke
			(width 0.2)
			(type default)
		)
		(layer "In6.Cu")
	)
	(gr_line
		(start 117.35816 -52.00015)
		(end 117.35816 -51.000152)
		(stroke
			(width 0.2)
			(type default)
		)
		(layer "In6.Cu")
	)
	(gr_arc
		(start 117.35816 -51.000152)
		(mid 117.00002 -50.642012)
		(end 116.64188 -51.000152)
		(stroke
			(width 0.2)
			(type default)
		)
		(layer "In6.Cu")
	)
	(gr_arc
		(start 117.641878 -55.999888)
		(mid 117.999891 -56.358282)
		(end 118.358158 -56.000142)
		(stroke
			(width 0.2)
			(type default)
		)
		(layer "In6.Cu")
	)
	(gr_line
		(start 117.641878 -55.000144)
		(end 117.641878 -55.999888)
		(stroke
			(width 0.2)
			(type default)
		)
		(layer "In6.Cu")
	)
	(gr_arc
		(start 117.641878 -52.999894)
		(mid 117.999891 -53.358288)
		(end 118.358158 -53.000148)
		(stroke
			(width 0.2)
			(type default)
		)
		(layer "In6.Cu")
	)
	(gr_line
		(start 117.641878 -52.00015)
		(end 117.641878 -52.999894)
		(stroke
			(width 0.2)
			(type default)
		)
		(layer "In6.Cu")
	)
	(gr_arc
		(start 117.8306 -44.6278)
		(mid 117.845479 -44.663721)
		(end 117.8814 -44.6786)
		(stroke
			(width 0.2)
			(type default)
		)
		(layer "In6.Cu")
	)
	(gr_line
		(start 117.8306 -43.815)
		(end 117.8306 -44.6278)
		(stroke
			(width 0.2)
			(type default)
		)
		(layer "In6.Cu")
	)
	(gr_arc
		(start 117.838728 -12.399772)
		(mid 118.399941 -12.961366)
		(end 118.961408 -12.400026)
		(stroke
			(width 0.2)
			(type default)
		)
		(layer "In6.Cu")
	)
	(gr_line
		(start 117.838728 -10.999978)
		(end 117.838728 -12.399772)
		(stroke
			(width 0.2)
			(type default)
		)
		(layer "In6.Cu")
	)
	(gr_arc
		(start 117.838728 -5.199888)
		(mid 118.399941 -5.761482)
		(end 118.961408 -5.200142)
		(stroke
			(width 0.2)
			(type default)
		)
		(layer "In6.Cu")
	)
	(gr_line
		(start 117.838728 -3.800094)
		(end 117.838728 -5.199888)
		(stroke
			(width 0.2)
			(type default)
		)
		(layer "In6.Cu")
	)
	(gr_line
		(start 117.8814 -44.6786)
		(end 118.0846 -44.6786)
		(stroke
			(width 0.2)
			(type default)
		)
		(layer "In6.Cu")
	)
	(gr_arc
		(start 117.8814 -43.7642)
		(mid 117.845479 -43.779079)
		(end 117.8306 -43.815)
		(stroke
			(width 0.2)
			(type default)
		)
		(layer "In6.Cu")
	)
	(gr_arc
		(start 118.0846 -44.6786)
		(mid 118.120521 -44.663721)
		(end 118.1354 -44.6278)
		(stroke
			(width 0.2)
			(type default)
		)
		(layer "In6.Cu")
	)
	(gr_line
		(start 118.0846 -43.7642)
		(end 117.8814 -43.7642)
		(stroke
			(width 0.2)
			(type default)
		)
		(layer "In6.Cu")
	)
	(gr_line
		(start 118.1354 -44.6278)
		(end 118.1354 -43.815)
		(stroke
			(width 0.2)
			(type default)
		)
		(layer "In6.Cu")
	)
	(gr_arc
		(start 118.1354 -43.815)
		(mid 118.120521 -43.779079)
		(end 118.0846 -43.7642)
		(stroke
			(width 0.2)
			(type default)
		)
		(layer "In6.Cu")
	)
	(gr_line
		(start 118.358158 -56.000142)
		(end 118.358158 -55.000144)
		(stroke
			(width 0.2)
			(type default)
		)
		(layer "In6.Cu")
	)
	(gr_arc
		(start 118.358158 -55.000144)
		(mid 118.000018 -54.642004)
		(end 117.641878 -55.000144)
		(stroke
			(width 0.2)
			(type default)
		)
		(layer "In6.Cu")
	)
	(gr_line
		(start 118.358158 -53.000148)
		(end 118.358158 -52.00015)
		(stroke
			(width 0.2)
			(type default)
		)
		(layer "In6.Cu")
	)
	(gr_arc
		(start 118.358158 -52.00015)
		(mid 118.000018 -51.64201)
		(end 117.641878 -52.00015)
		(stroke
			(width 0.2)
			(type default)
		)
		(layer "In6.Cu")
	)
	(gr_arc
		(start 118.3894 -44.6278)
		(mid 118.404279 -44.663721)
		(end 118.4402 -44.6786)
		(stroke
			(width 0.2)
			(type default)
		)
		(layer "In6.Cu")
	)
	(gr_line
		(start 118.3894 -43.815)
		(end 118.3894 -44.6278)
		(stroke
			(width 0.2)
			(type default)
		)
		(layer "In6.Cu")
	)
	(gr_line
		(start 118.4402 -44.6786)
		(end 118.6434 -44.6786)
		(stroke
			(width 0.2)
			(type default)
		)
		(layer "In6.Cu")
	)
	(gr_arc
		(start 118.4402 -43.7642)
		(mid 118.404279 -43.779079)
		(end 118.3894 -43.815)
		(stroke
			(width 0.2)
			(type default)
		)
		(layer "In6.Cu")
	)
	(gr_arc
		(start 118.641876 -55.999888)
		(mid 118.999889 -56.358282)
		(end 119.358156 -56.000142)
		(stroke
			(width 0.2)
			(type default)
		)
		(layer "In6.Cu")
	)
	(gr_line
		(start 118.641876 -55.000144)
		(end 118.641876 -55.999888)
		(stroke
			(width 0.2)
			(type default)
		)
		(layer "In6.Cu")
	)
	(gr_arc
		(start 118.641876 -51.999896)
		(mid 118.999889 -52.35829)
		(end 119.358156 -52.00015)
		(stroke
			(width 0.2)
			(type default)
		)
		(layer "In6.Cu")
	)
	(gr_line
		(start 118.641876 -51.000152)
		(end 118.641876 -51.999896)
		(stroke
			(width 0.2)
			(type default)
		)
		(layer "In6.Cu")
	)
	(gr_arc
		(start 118.6434 -44.6786)
		(mid 118.679321 -44.663721)
		(end 118.6942 -44.6278)
		(stroke
			(width 0.2)
			(type default)
		)
		(layer "In6.Cu")
	)
	(gr_line
		(start 118.6434 -43.7642)
		(end 118.4402 -43.7642)
		(stroke
			(width 0.2)
			(type default)
		)
		(layer "In6.Cu")
	)
	(gr_line
		(start 118.6942 -44.6278)
		(end 118.6942 -43.815)
		(stroke
			(width 0.2)
			(type default)
		)
		(layer "In6.Cu")
	)
	(gr_arc
		(start 118.6942 -43.815)
		(mid 118.679321 -43.779079)
		(end 118.6434 -43.7642)
		(stroke
			(width 0.2)
			(type default)
		)
		(layer "In6.Cu")
	)
	(gr_line
		(start 118.961408 -12.400026)
		(end 118.961408 -10.999978)
		(stroke
			(width 0.2)
			(type default)
		)
		(layer "In6.Cu")
	)
	(gr_arc
		(start 118.961408 -10.999978)
		(mid 118.400068 -10.438638)
		(end 117.838728 -10.999978)
		(stroke
			(width 0.2)
			(type default)
		)
		(layer "In6.Cu")
	)
	(gr_line
		(start 118.961408 -5.200142)
		(end 118.961408 -3.800094)
		(stroke
			(width 0.2)
			(type default)
		)
		(layer "In6.Cu")
	)
	(gr_arc
		(start 118.961408 -3.800094)
		(mid 118.400068 -3.238754)
		(end 117.838728 -3.800094)
		(stroke
			(width 0.2)
			(type default)
		)
		(layer "In6.Cu")
	)
	(gr_arc
		(start 119.3546 -44.6278)
		(mid 119.369479 -44.663721)
		(end 119.4054 -44.6786)
		(stroke
			(width 0.2)
			(type default)
		)
		(layer "In6.Cu")
	)
	(gr_line
		(start 119.3546 -43.815)
		(end 119.3546 -44.6278)
		(stroke
			(width 0.2)
			(type default)
		)
		(layer "In6.Cu")
	)
	(gr_line
		(start 119.358156 -56.000142)
		(end 119.358156 -55.000144)
		(stroke
			(width 0.2)
			(type default)
		)
		(layer "In6.Cu")
	)
	(gr_arc
		(start 119.358156 -55.000144)
		(mid 119.000016 -54.642004)
		(end 118.641876 -55.000144)
		(stroke
			(width 0.2)
			(type default)
		)
		(layer "In6.Cu")
	)
	(gr_line
		(start 119.358156 -52.00015)
		(end 119.358156 -51.000152)
		(stroke
			(width 0.2)
			(type default)
		)
		(layer "In6.Cu")
	)
	(gr_arc
		(start 119.358156 -51.000152)
		(mid 119.000016 -50.642012)
		(end 118.641876 -51.000152)
		(stroke
			(width 0.2)
			(type default)
		)
		(layer "In6.Cu")
	)
	(gr_line
		(start 119.4054 -44.6786)
		(end 119.6086 -44.6786)
		(stroke
			(width 0.2)
			(type default)
		)
		(layer "In6.Cu")
	)
	(gr_arc
		(start 119.4054 -43.7642)
		(mid 119.369479 -43.779079)
		(end 119.3546 -43.815)
		(stroke
			(width 0.2)
			(type default)
		)
		(layer "In6.Cu")
	)
	(gr_arc
		(start 119.6086 -44.6786)
		(mid 119.644521 -44.663721)
		(end 119.6594 -44.6278)
		(stroke
			(width 0.2)
			(type default)
		)
		(layer "In6.Cu")
	)
	(gr_line
		(start 119.6086 -43.7642)
		(end 119.4054 -43.7642)
		(stroke
			(width 0.2)
			(type default)
		)
		(layer "In6.Cu")
	)
	(gr_arc
		(start 119.638826 -11.199876)
		(mid 120.200039 -11.76147)
		(end 120.761506 -11.20013)
		(stroke
			(width 0.2)
			(type default)
		)
		(layer "In6.Cu")
	)
	(gr_line
		(start 119.638826 -9.800082)
		(end 119.638826 -11.199876)
		(stroke
			(width 0.2)
			(type default)
		)
		(layer "In6.Cu")
	)
	(gr_arc
		(start 119.638826 -3.999738)
		(mid 120.200039 -4.561332)
		(end 120.761506 -3.999992)
		(stroke
			(width 0.2)
			(type default)
		)
		(layer "In6.Cu")
	)
	(gr_line
		(start 119.638826 -2.600198)
		(end 119.638826 -3.999738)
		(stroke
			(width 0.2)
			(type default)
		)
		(layer "In6.Cu")
	)
	(gr_arc
		(start 119.641874 -55.999888)
		(mid 119.999887 -56.358282)
		(end 120.358154 -56.000142)
		(stroke
			(width 0.2)
			(type default)
		)
		(layer "In6.Cu")
	)
	(gr_line
		(start 119.641874 -55.000144)
		(end 119.641874 -55.999888)
		(stroke
			(width 0.2)
			(type default)
		)
		(layer "In6.Cu")
	)
	(gr_arc
		(start 119.641874 -52.999894)
		(mid 119.999887 -53.358288)
		(end 120.358154 -53.000148)
		(stroke
			(width 0.2)
			(type default)
		)
		(layer "In6.Cu")
	)
	(gr_line
		(start 119.641874 -52.00015)
		(end 119.641874 -52.999894)
		(stroke
			(width 0.2)
			(type default)
		)
		(layer "In6.Cu")
	)
	(gr_line
		(start 119.6594 -44.6278)
		(end 119.6594 -43.815)
		(stroke
			(width 0.2)
			(type default)
		)
		(layer "In6.Cu")
	)
	(gr_arc
		(start 119.6594 -43.815)
		(mid 119.644521 -43.779079)
		(end 119.6086 -43.7642)
		(stroke
			(width 0.2)
			(type default)
		)
		(layer "In6.Cu")
	)
	(gr_arc
		(start 119.9134 -44.6278)
		(mid 119.928279 -44.663721)
		(end 119.9642 -44.6786)
		(stroke
			(width 0.2)
			(type default)
		)
		(layer "In6.Cu")
	)
	(gr_line
		(start 119.9134 -43.815)
		(end 119.9134 -44.6278)
		(stroke
			(width 0.2)
			(type default)
		)
		(layer "In6.Cu")
	)
	(gr_line
		(start 119.9642 -44.6786)
		(end 120.1674 -44.6786)
		(stroke
			(width 0.2)
			(type default)
		)
		(layer "In6.Cu")
	)
	(gr_arc
		(start 119.9642 -43.7642)
		(mid 119.928279 -43.779079)
		(end 119.9134 -43.815)
		(stroke
			(width 0.2)
			(type default)
		)
		(layer "In6.Cu")
	)
	(gr_arc
		(start 120.1674 -44.6786)
		(mid 120.203321 -44.663721)
		(end 120.2182 -44.6278)
		(stroke
			(width 0.2)
			(type default)
		)
		(layer "In6.Cu")
	)
	(gr_line
		(start 120.1674 -43.7642)
		(end 119.9642 -43.7642)
		(stroke
			(width 0.2)
			(type default)
		)
		(layer "In6.Cu")
	)
	(gr_line
		(start 120.2182 -44.6278)
		(end 120.2182 -43.815)
		(stroke
			(width 0.2)
			(type default)
		)
		(layer "In6.Cu")
	)
	(gr_arc
		(start 120.2182 -43.815)
		(mid 120.203321 -43.779079)
		(end 120.1674 -43.7642)
		(stroke
			(width 0.2)
			(type default)
		)
		(layer "In6.Cu")
	)
	(gr_line
		(start 120.358154 -56.000142)
		(end 120.358154 -55.000144)
		(stroke
			(width 0.2)
			(type default)
		)
		(layer "In6.Cu")
	)
	(gr_arc
		(start 120.358154 -55.000144)
		(mid 120.000014 -54.642004)
		(end 119.641874 -55.000144)
		(stroke
			(width 0.2)
			(type default)
		)
		(layer "In6.Cu")
	)
	(gr_line
		(start 120.358154 -53.000148)
		(end 120.358154 -52.00015)
		(stroke
			(width 0.2)
			(type default)
		)
		(layer "In6.Cu")
	)
	(gr_arc
		(start 120.358154 -52.00015)
		(mid 120.000014 -51.64201)
		(end 119.641874 -52.00015)
		(stroke
			(width 0.2)
			(type default)
		)
		(layer "In6.Cu")
	)
	(gr_arc
		(start 120.641872 -55.999888)
		(mid 120.999885 -56.358282)
		(end 121.358152 -56.000142)
		(stroke
			(width 0.2)
			(type default)
		)
		(layer "In6.Cu")
	)
	(gr_line
		(start 120.641872 -55.000144)
		(end 120.641872 -55.999888)
		(stroke
			(width 0.2)
			(type default)
		)
		(layer "In6.Cu")
	)
	(gr_arc
		(start 120.641872 -51.999896)
		(mid 120.999885 -52.35829)
		(end 121.358152 -52.00015)
		(stroke
			(width 0.2)
			(type default)
		)
		(layer "In6.Cu")
	)
	(gr_line
		(start 120.641872 -51.000152)
		(end 120.641872 -51.999896)
		(stroke
			(width 0.2)
			(type default)
		)
		(layer "In6.Cu")
	)
	(gr_line
		(start 120.761506 -11.20013)
		(end 120.761506 -9.800082)
		(stroke
			(width 0.2)
			(type default)
		)
		(layer "In6.Cu")
	)
	(gr_arc
		(start 120.761506 -9.800082)
		(mid 120.200166 -9.238742)
		(end 119.638826 -9.800082)
		(stroke
			(width 0.2)
			(type default)
		)
		(layer "In6.Cu")
	)
	(gr_line
		(start 120.761506 -3.999992)
		(end 120.761506 -2.600198)
		(stroke
			(width 0.2)
			(type default)
		)
		(layer "In6.Cu")
	)
	(gr_arc
		(start 120.761506 -2.600198)
		(mid 120.200166 -2.038858)
		(end 119.638826 -2.600198)
		(stroke
			(width 0.2)
			(type default)
		)
		(layer "In6.Cu")
	)
	(gr_line
		(start 120.79224 -127.32639)
		(end 112.499902 -126.000002)
		(stroke
			(width 1.524)
			(type default)
		)
		(layer "In6.Cu")
	)
	(gr_arc
		(start 121.285 -39.878)
		(mid 121.299879 -39.913921)
		(end 121.3358 -39.9288)
		(stroke
			(width 0.2)
			(type default)
		)
		(layer "In6.Cu")
	)
	(gr_line
		(start 121.285 -39.0652)
		(end 121.285 -39.878)
		(stroke
			(width 0.2)
			(type default)
		)
		(layer "In6.Cu")
	)
	(gr_line
		(start 121.3358 -39.9288)
		(end 121.539 -39.9288)
		(stroke
			(width 0.2)
			(type default)
		)
		(layer "In6.Cu")
	)
	(gr_arc
		(start 121.3358 -39.0144)
		(mid 121.299879 -39.029279)
		(end 121.285 -39.0652)
		(stroke
			(width 0.2)
			(type default)
		)
		(layer "In6.Cu")
	)
	(gr_line
		(start 121.358152 -56.000142)
		(end 121.358152 -55.000144)
		(stroke
			(width 0.2)
			(type default)
		)
		(layer "In6.Cu")
	)
	(gr_arc
		(start 121.358152 -55.000144)
		(mid 121.000012 -54.642004)
		(end 120.641872 -55.000144)
		(stroke
			(width 0.2)
			(type default)
		)
		(layer "In6.Cu")
	)
	(gr_line
		(start 121.358152 -52.00015)
		(end 121.358152 -51.000152)
		(stroke
			(width 0.2)
			(type default)
		)
		(layer "In6.Cu")
	)
	(gr_arc
		(start 121.358152 -51.000152)
		(mid 121.000012 -50.642012)
		(end 120.641872 -51.000152)
		(stroke
			(width 0.2)
			(type default)
		)
		(layer "In6.Cu")
	)
	(gr_arc
		(start 121.43867 -12.399772)
		(mid 121.999883 -12.961366)
		(end 122.56135 -12.400026)
		(stroke
			(width 0.2)
			(type default)
		)
		(layer "In6.Cu")
	)
	(gr_line
		(start 121.43867 -10.999978)
		(end 121.43867 -12.399772)
		(stroke
			(width 0.2)
			(type default)
		)
		(layer "In6.Cu")
	)
	(gr_arc
		(start 121.43867 -5.199888)
		(mid 121.999883 -5.761482)
		(end 122.56135 -5.200142)
		(stroke
			(width 0.2)
			(type default)
		)
		(layer "In6.Cu")
	)
	(gr_line
		(start 121.43867 -3.800094)
		(end 121.43867 -5.199888)
		(stroke
			(width 0.2)
			(type default)
		)
		(layer "In6.Cu")
	)
	(gr_arc
		(start 121.539 -39.9288)
		(mid 121.574921 -39.913921)
		(end 121.5898 -39.878)
		(stroke
			(width 0.2)
			(type default)
		)
		(layer "In6.Cu")
	)
	(gr_line
		(start 121.539 -39.0144)
		(end 121.3358 -39.0144)
		(stroke
			(width 0.2)
			(type default)
		)
		(layer "In6.Cu")
	)
	(gr_line
		(start 121.5898 -39.878)
		(end 121.5898 -39.0652)
		(stroke
			(width 0.2)
			(type default)
		)
		(layer "In6.Cu")
	)
	(gr_arc
		(start 121.5898 -39.0652)
		(mid 121.574921 -39.029279)
		(end 121.539 -39.0144)
		(stroke
			(width 0.2)
			(type default)
		)
		(layer "In6.Cu")
	)
	(gr_arc
		(start 121.64187 -55.999888)
		(mid 121.999883 -56.358282)
		(end 122.35815 -56.000142)
		(stroke
			(width 0.2)
			(type default)
		)
		(layer "In6.Cu")
	)
	(gr_line
		(start 121.64187 -55.000144)
		(end 121.64187 -55.999888)
		(stroke
			(width 0.2)
			(type default)
		)
		(layer "In6.Cu")
	)
	(gr_arc
		(start 121.64187 -52.999894)
		(mid 121.999883 -53.358288)
		(end 122.35815 -53.000148)
		(stroke
			(width 0.2)
			(type default)
		)
		(layer "In6.Cu")
	)
	(gr_line
		(start 121.64187 -52.00015)
		(end 121.64187 -52.999894)
		(stroke
			(width 0.2)
			(type default)
		)
		(layer "In6.Cu")
	)
	(gr_arc
		(start 121.8692 -39.878)
		(mid 121.884079 -39.913921)
		(end 121.92 -39.9288)
		(stroke
			(width 0.2)
			(type default)
		)
		(layer "In6.Cu")
	)
	(gr_line
		(start 121.8692 -39.0652)
		(end 121.8692 -39.878)
		(stroke
			(width 0.2)
			(type default)
		)
		(layer "In6.Cu")
	)
	(gr_line
		(start 121.92 -39.9288)
		(end 122.1232 -39.9288)
		(stroke
			(width 0.2)
			(type default)
		)
		(layer "In6.Cu")
	)
	(gr_arc
		(start 121.92 -39.0144)
		(mid 121.884079 -39.029279)
		(end 121.8692 -39.0652)
		(stroke
			(width 0.2)
			(type default)
		)
		(layer "In6.Cu")
	)
	(gr_arc
		(start 122.1232 -39.9288)
		(mid 122.159121 -39.913921)
		(end 122.174 -39.878)
		(stroke
			(width 0.2)
			(type default)
		)
		(layer "In6.Cu")
	)
	(gr_line
		(start 122.1232 -39.0144)
		(end 121.92 -39.0144)
		(stroke
			(width 0.2)
			(type default)
		)
		(layer "In6.Cu")
	)
	(gr_line
		(start 122.174 -39.878)
		(end 122.174 -39.0652)
		(stroke
			(width 0.2)
			(type default)
		)
		(layer "In6.Cu")
	)
	(gr_arc
		(start 122.174 -39.0652)
		(mid 122.159121 -39.029279)
		(end 122.1232 -39.0144)
		(stroke
			(width 0.2)
			(type default)
		)
		(layer "In6.Cu")
	)
	(gr_line
		(start 122.35815 -56.000142)
		(end 122.35815 -55.000144)
		(stroke
			(width 0.2)
			(type default)
		)
		(layer "In6.Cu")
	)
	(gr_arc
		(start 122.35815 -55.000144)
		(mid 122.00001 -54.642004)
		(end 121.64187 -55.000144)
		(stroke
			(width 0.2)
			(type default)
		)
		(layer "In6.Cu")
	)
	(gr_line
		(start 122.35815 -53.000148)
		(end 122.35815 -52.00015)
		(stroke
			(width 0.2)
			(type default)
		)
		(layer "In6.Cu")
	)
	(gr_arc
		(start 122.35815 -52.00015)
		(mid 122.00001 -51.64201)
		(end 121.64187 -52.00015)
		(stroke
			(width 0.2)
			(type default)
		)
		(layer "In6.Cu")
	)
	(gr_line
		(start 122.56135 -12.400026)
		(end 122.56135 -10.999978)
		(stroke
			(width 0.2)
			(type default)
		)
		(layer "In6.Cu")
	)
	(gr_arc
		(start 122.56135 -10.999978)
		(mid 122.00001 -10.438638)
		(end 121.43867 -10.999978)
		(stroke
			(width 0.2)
			(type default)
		)
		(layer "In6.Cu")
	)
	(gr_line
		(start 122.56135 -5.200142)
		(end 122.56135 -3.800094)
		(stroke
			(width 0.2)
			(type default)
		)
		(layer "In6.Cu")
	)
	(gr_arc
		(start 122.56135 -3.800094)
		(mid 122.00001 -3.238754)
		(end 121.43867 -3.800094)
		(stroke
			(width 0.2)
			(type default)
		)
		(layer "In6.Cu")
	)
	(gr_arc
		(start 122.641868 -55.999888)
		(mid 122.999881 -56.358282)
		(end 123.358148 -56.000142)
		(stroke
			(width 0.2)
			(type default)
		)
		(layer "In6.Cu")
	)
	(gr_line
		(start 122.641868 -55.000144)
		(end 122.641868 -55.999888)
		(stroke
			(width 0.2)
			(type default)
		)
		(layer "In6.Cu")
	)
	(gr_arc
		(start 122.641868 -51.999896)
		(mid 122.999881 -52.35829)
		(end 123.358148 -52.00015)
		(stroke
			(width 0.2)
			(type default)
		)
		(layer "In6.Cu")
	)
	(gr_line
		(start 122.641868 -51.000152)
		(end 122.641868 -51.999896)
		(stroke
			(width 0.2)
			(type default)
		)
		(layer "In6.Cu")
	)
	(gr_arc
		(start 123.063 -39.878)
		(mid 123.077879 -39.913921)
		(end 123.1138 -39.9288)
		(stroke
			(width 0.2)
			(type default)
		)
		(layer "In6.Cu")
	)
	(gr_line
		(start 123.063 -39.0652)
		(end 123.063 -39.878)
		(stroke
			(width 0.2)
			(type default)
		)
		(layer "In6.Cu")
	)
	(gr_line
		(start 123.1138 -39.9288)
		(end 123.317 -39.9288)
		(stroke
			(width 0.2)
			(type default)
		)
		(layer "In6.Cu")
	)
	(gr_arc
		(start 123.1138 -39.0144)
		(mid 123.077879 -39.029279)
		(end 123.063 -39.0652)
		(stroke
			(width 0.2)
			(type default)
		)
		(layer "In6.Cu")
	)
	(gr_arc
		(start 123.238768 -11.199876)
		(mid 123.799981 -11.76147)
		(end 124.361448 -11.20013)
		(stroke
			(width 0.2)
			(type default)
		)
		(layer "In6.Cu")
	)
	(gr_line
		(start 123.238768 -9.800082)
		(end 123.238768 -11.199876)
		(stroke
			(width 0.2)
			(type default)
		)
		(layer "In6.Cu")
	)
	(gr_arc
		(start 123.238768 -3.999738)
		(mid 123.799981 -4.561332)
		(end 124.361448 -3.999992)
		(stroke
			(width 0.2)
			(type default)
		)
		(layer "In6.Cu")
	)
	(gr_line
		(start 123.238768 -2.600198)
		(end 123.238768 -3.999738)
		(stroke
			(width 0.2)
			(type default)
		)
		(layer "In6.Cu")
	)
	(gr_arc
		(start 123.317 -39.9288)
		(mid 123.352921 -39.913921)
		(end 123.3678 -39.878)
		(stroke
			(width 0.2)
			(type default)
		)
		(layer "In6.Cu")
	)
	(gr_line
		(start 123.317 -39.0144)
		(end 123.1138 -39.0144)
		(stroke
			(width 0.2)
			(type default)
		)
		(layer "In6.Cu")
	)
	(gr_line
		(start 123.358148 -56.000142)
		(end 123.358148 -55.000144)
		(stroke
			(width 0.2)
			(type default)
		)
		(layer "In6.Cu")
	)
	(gr_arc
		(start 123.358148 -55.000144)
		(mid 123.000008 -54.642004)
		(end 122.641868 -55.000144)
		(stroke
			(width 0.2)
			(type default)
		)
		(layer "In6.Cu")
	)
	(gr_line
		(start 123.358148 -52.00015)
		(end 123.358148 -51.000152)
		(stroke
			(width 0.2)
			(type default)
		)
		(layer "In6.Cu")
	)
	(gr_arc
		(start 123.358148 -51.000152)
		(mid 123.000008 -50.642012)
		(end 122.641868 -51.000152)
		(stroke
			(width 0.2)
			(type default)
		)
		(layer "In6.Cu")
	)
	(gr_line
		(start 123.3678 -39.878)
		(end 123.3678 -39.0652)
		(stroke
			(width 0.2)
			(type default)
		)
		(layer "In6.Cu")
	)
	(gr_arc
		(start 123.3678 -39.0652)
		(mid 123.352921 -39.029279)
		(end 123.317 -39.0144)
		(stroke
			(width 0.2)
			(type default)
		)
		(layer "In6.Cu")
	)
	(gr_arc
		(start 123.641866 -55.999888)
		(mid 123.999879 -56.358282)
		(end 124.358146 -56.000142)
		(stroke
			(width 0.2)
			(type default)
		)
		(layer "In6.Cu")
	)
	(gr_line
		(start 123.641866 -55.000144)
		(end 123.641866 -55.999888)
		(stroke
			(width 0.2)
			(type default)
		)
		(layer "In6.Cu")
	)
	(gr_arc
		(start 123.641866 -52.999894)
		(mid 123.999879 -53.358288)
		(end 124.358146 -53.000148)
		(stroke
			(width 0.2)
			(type default)
		)
		(layer "In6.Cu")
	)
	(gr_line
		(start 123.641866 -52.00015)
		(end 123.641866 -52.999894)
		(stroke
			(width 0.2)
			(type default)
		)
		(layer "In6.Cu")
	)
	(gr_arc
		(start 123.6472 -39.878)
		(mid 123.662079 -39.913921)
		(end 123.698 -39.9288)
		(stroke
			(width 0.2)
			(type default)
		)
		(layer "In6.Cu")
	)
	(gr_line
		(start 123.6472 -39.0652)
		(end 123.6472 -39.878)
		(stroke
			(width 0.2)
			(type default)
		)
		(layer "In6.Cu")
	)
	(gr_line
		(start 123.698 -39.9288)
		(end 123.9012 -39.9288)
		(stroke
			(width 0.2)
			(type default)
		)
		(layer "In6.Cu")
	)
	(gr_arc
		(start 123.698 -39.0144)
		(mid 123.662079 -39.029279)
		(end 123.6472 -39.0652)
		(stroke
			(width 0.2)
			(type default)
		)
		(layer "In6.Cu")
	)
	(gr_arc
		(start 123.9012 -39.9288)
		(mid 123.937121 -39.913921)
		(end 123.952 -39.878)
		(stroke
			(width 0.2)
			(type default)
		)
		(layer "In6.Cu")
	)
	(gr_line
		(start 123.9012 -39.0144)
		(end 123.698 -39.0144)
		(stroke
			(width 0.2)
			(type default)
		)
		(layer "In6.Cu")
	)
	(gr_line
		(start 123.952 -39.878)
		(end 123.952 -39.0652)
		(stroke
			(width 0.2)
			(type default)
		)
		(layer "In6.Cu")
	)
	(gr_arc
		(start 123.952 -39.0652)
		(mid 123.937121 -39.029279)
		(end 123.9012 -39.0144)
		(stroke
			(width 0.2)
			(type default)
		)
		(layer "In6.Cu")
	)
	(gr_arc
		(start 124.225558 -47.001684)
		(mid 124.682631 -47.459138)
		(end 125.139958 -47.001938)
		(stroke
			(width 0.2)
			(type default)
		)
		(layer "In6.Cu")
	)
	(gr_line
		(start 124.225558 -45.858938)
		(end 124.225558 -47.001684)
		(stroke
			(width 0.2)
			(type default)
		)
		(layer "In6.Cu")
	)
	(gr_line
		(start 124.358146 -56.000142)
		(end 124.358146 -55.000144)
		(stroke
			(width 0.2)
			(type default)
		)
		(layer "In6.Cu")
	)
	(gr_arc
		(start 124.358146 -55.000144)
		(mid 124.000006 -54.642004)
		(end 123.641866 -55.000144)
		(stroke
			(width 0.2)
			(type default)
		)
		(layer "In6.Cu")
	)
	(gr_line
		(start 124.358146 -53.000148)
		(end 124.358146 -52.00015)
		(stroke
			(width 0.2)
			(type default)
		)
		(layer "In6.Cu")
	)
	(gr_arc
		(start 124.358146 -52.00015)
		(mid 124.000006 -51.64201)
		(end 123.641866 -52.00015)
		(stroke
			(width 0.2)
			(type default)
		)
		(layer "In6.Cu")
	)
	(gr_line
		(start 124.361448 -11.20013)
		(end 124.361448 -9.800082)
		(stroke
			(width 0.2)
			(type default)
		)
		(layer "In6.Cu")
	)
	(gr_arc
		(start 124.361448 -9.800082)
		(mid 123.800108 -9.238742)
		(end 123.238768 -9.800082)
		(stroke
			(width 0.2)
			(type default)
		)
		(layer "In6.Cu")
	)
	(gr_line
		(start 124.361448 -3.999992)
		(end 124.361448 -2.600198)
		(stroke
			(width 0.2)
			(type default)
		)
		(layer "In6.Cu")
	)
	(gr_arc
		(start 124.361448 -2.600198)
		(mid 123.800108 -2.038858)
		(end 123.238768 -2.600198)
		(stroke
			(width 0.2)
			(type default)
		)
		(layer "In6.Cu")
	)
	(gr_arc
		(start 124.841 -39.878)
		(mid 124.855879 -39.913921)
		(end 124.8918 -39.9288)
		(stroke
			(width 0.2)
			(type default)
		)
		(layer "In6.Cu")
	)
	(gr_line
		(start 124.841 -39.0652)
		(end 124.841 -39.878)
		(stroke
			(width 0.2)
			(type default)
		)
		(layer "In6.Cu")
	)
	(gr_line
		(start 124.8918 -39.9288)
		(end 125.095 -39.9288)
		(stroke
			(width 0.2)
			(type default)
		)
		(layer "In6.Cu")
	)
	(gr_arc
		(start 124.8918 -39.0144)
		(mid 124.855879 -39.029279)
		(end 124.841 -39.0652)
		(stroke
			(width 0.2)
			(type default)
		)
		(layer "In6.Cu")
	)
	(gr_line
		(start 125.002544 -142.999968)
		(end 125.002544 -132.263642)
		(stroke
			(width 1.524)
			(type default)
		)
		(layer "In6.Cu")
	)
	(gr_arc
		(start 125.002544 -142.999968)
		(mid 125.58832 -144.414185)
		(end 127.00254 -144.999964)
		(stroke
			(width 1.524)
			(type default)
		)
		(layer "In6.Cu")
	)
	(gr_arc
		(start 125.002544 -132.263642)
		(mid 123.807045 -129.019301)
		(end 120.79224 -127.32639)
		(stroke
			(width 1.524)
			(type default)
		)
		(layer "In6.Cu")
	)
	(gr_arc
		(start 125.038866 -12.399772)
		(mid 125.600079 -12.961366)
		(end 126.161546 -12.400026)
		(stroke
			(width 0.2)
			(type default)
		)
		(layer "In6.Cu")
	)
	(gr_line
		(start 125.038866 -10.999978)
		(end 125.038866 -12.399772)
		(stroke
			(width 0.2)
			(type default)
		)
		(layer "In6.Cu")
	)
	(gr_arc
		(start 125.038866 -5.199888)
		(mid 125.600079 -5.761482)
		(end 126.161546 -5.200142)
		(stroke
			(width 0.2)
			(type default)
		)
		(layer "In6.Cu")
	)
	(gr_line
		(start 125.038866 -3.800094)
		(end 125.038866 -5.199888)
		(stroke
			(width 0.2)
			(type default)
		)
		(layer "In6.Cu")
	)
	(gr_arc
		(start 125.095 -39.9288)
		(mid 125.130921 -39.913921)
		(end 125.1458 -39.878)
		(stroke
			(width 0.2)
			(type default)
		)
		(layer "In6.Cu")
	)
	(gr_line
		(start 125.095 -39.0144)
		(end 124.8918 -39.0144)
		(stroke
			(width 0.2)
			(type default)
		)
		(layer "In6.Cu")
	)
	(gr_line
		(start 125.139958 -47.001938)
		(end 125.139958 -45.858938)
		(stroke
			(width 0.2)
			(type default)
		)
		(layer "In6.Cu")
	)
	(gr_arc
		(start 125.139958 -45.858938)
		(mid 124.682758 -45.401738)
		(end 124.225558 -45.858938)
		(stroke
			(width 0.2)
			(type default)
		)
		(layer "In6.Cu")
	)
	(gr_line
		(start 125.1458 -39.878)
		(end 125.1458 -39.0652)
		(stroke
			(width 0.2)
			(type default)
		)
		(layer "In6.Cu")
	)
	(gr_arc
		(start 125.1458 -39.0652)
		(mid 125.130921 -39.029279)
		(end 125.095 -39.0144)
		(stroke
			(width 0.2)
			(type default)
		)
		(layer "In6.Cu")
	)
	(gr_arc
		(start 125.4252 -39.878)
		(mid 125.440079 -39.913921)
		(end 125.476 -39.9288)
		(stroke
			(width 0.2)
			(type default)
		)
		(layer "In6.Cu")
	)
	(gr_line
		(start 125.4252 -39.0652)
		(end 125.4252 -39.878)
		(stroke
			(width 0.2)
			(type default)
		)
		(layer "In6.Cu")
	)
	(gr_line
		(start 125.476 -39.9288)
		(end 125.6792 -39.9288)
		(stroke
			(width 0.2)
			(type default)
		)
		(layer "In6.Cu")
	)
	(gr_arc
		(start 125.476 -39.0144)
		(mid 125.440079 -39.029279)
		(end 125.4252 -39.0652)
		(stroke
			(width 0.2)
			(type default)
		)
		(layer "In6.Cu")
	)
	(gr_arc
		(start 125.6792 -39.9288)
		(mid 125.715121 -39.913921)
		(end 125.73 -39.878)
		(stroke
			(width 0.2)
			(type default)
		)
		(layer "In6.Cu")
	)
	(gr_line
		(start 125.6792 -39.0144)
		(end 125.476 -39.0144)
		(stroke
			(width 0.2)
			(type default)
		)
		(layer "In6.Cu")
	)
	(gr_line
		(start 125.73 -39.878)
		(end 125.73 -39.0652)
		(stroke
			(width 0.2)
			(type default)
		)
		(layer "In6.Cu")
	)
	(gr_arc
		(start 125.73 -39.0652)
		(mid 125.715121 -39.029279)
		(end 125.6792 -39.0144)
		(stroke
			(width 0.2)
			(type default)
		)
		(layer "In6.Cu")
	)
	(gr_line
		(start 126.000002 -77.35824)
		(end 127 -77.35824)
		(stroke
			(width 0.2)
			(type default)
		)
		(layer "In6.Cu")
	)
	(gr_line
		(start 126.000002 -76.358242)
		(end 127 -76.358242)
		(stroke
			(width 0.2)
			(type default)
		)
		(layer "In6.Cu")
	)
	(gr_line
		(start 126.000002 -75.358244)
		(end 127 -75.358244)
		(stroke
			(width 0.2)
			(type default)
		)
		(layer "In6.Cu")
	)
	(gr_line
		(start 126.000002 -74.358246)
		(end 127 -74.358246)
		(stroke
			(width 0.2)
			(type default)
		)
		(layer "In6.Cu")
	)
	(gr_line
		(start 126.000002 -73.358248)
		(end 127 -73.358248)
		(stroke
			(width 0.2)
			(type default)
		)
		(layer "In6.Cu")
	)
	(gr_line
		(start 126.000002 -72.35825)
		(end 127 -72.35825)
		(stroke
			(width 0.2)
			(type default)
		)
		(layer "In6.Cu")
	)
	(gr_line
		(start 126.000002 -71.358252)
		(end 127 -71.358252)
		(stroke
			(width 0.2)
			(type default)
		)
		(layer "In6.Cu")
	)
	(gr_line
		(start 126.000002 -70.358254)
		(end 127 -70.358254)
		(stroke
			(width 0.2)
			(type default)
		)
		(layer "In6.Cu")
	)
	(gr_line
		(start 126.000002 -69.358256)
		(end 127 -69.358256)
		(stroke
			(width 0.2)
			(type default)
		)
		(layer "In6.Cu")
	)
	(gr_line
		(start 126.000002 -68.358258)
		(end 127 -68.358258)
		(stroke
			(width 0.2)
			(type default)
		)
		(layer "In6.Cu")
	)
	(gr_line
		(start 126.000002 -66.358262)
		(end 127 -66.358262)
		(stroke
			(width 0.2)
			(type default)
		)
		(layer "In6.Cu")
	)
	(gr_line
		(start 126.000002 -65.358264)
		(end 127 -65.358264)
		(stroke
			(width 0.2)
			(type default)
		)
		(layer "In6.Cu")
	)
	(gr_line
		(start 126.000002 -64.358266)
		(end 127 -64.358266)
		(stroke
			(width 0.2)
			(type default)
		)
		(layer "In6.Cu")
	)
	(gr_line
		(start 126.000002 -63.358268)
		(end 127 -63.358268)
		(stroke
			(width 0.2)
			(type default)
		)
		(layer "In6.Cu")
	)
	(gr_line
		(start 126.000002 -62.35827)
		(end 127 -62.35827)
		(stroke
			(width 0.2)
			(type default)
		)
		(layer "In6.Cu")
	)
	(gr_line
		(start 126.000002 -61.358272)
		(end 127 -61.358272)
		(stroke
			(width 0.2)
			(type default)
		)
		(layer "In6.Cu")
	)
	(gr_line
		(start 126.000002 -60.358274)
		(end 127 -60.358274)
		(stroke
			(width 0.2)
			(type default)
		)
		(layer "In6.Cu")
	)
	(gr_line
		(start 126.000002 -59.358276)
		(end 127 -59.358276)
		(stroke
			(width 0.2)
			(type default)
		)
		(layer "In6.Cu")
	)
	(gr_line
		(start 126.000002 -58.358278)
		(end 127 -58.358278)
		(stroke
			(width 0.2)
			(type default)
		)
		(layer "In6.Cu")
	)
	(gr_line
		(start 126.000002 -57.35828)
		(end 127 -57.35828)
		(stroke
			(width 0.2)
			(type default)
		)
		(layer "In6.Cu")
	)
	(gr_line
		(start 126.000002 -56.358282)
		(end 127 -56.358282)
		(stroke
			(width 0.2)
			(type default)
		)
		(layer "In6.Cu")
	)
	(gr_line
		(start 126.000002 -55.358284)
		(end 127 -55.358284)
		(stroke
			(width 0.2)
			(type default)
		)
		(layer "In6.Cu")
	)
	(gr_line
		(start 126.000002 -54.358286)
		(end 127 -54.358286)
		(stroke
			(width 0.2)
			(type default)
		)
		(layer "In6.Cu")
	)
	(gr_arc
		(start 126.000256 -76.64196)
		(mid 125.641862 -76.999973)
		(end 126.000002 -77.35824)
		(stroke
			(width 0.2)
			(type default)
		)
		(layer "In6.Cu")
	)
	(gr_arc
		(start 126.000256 -75.641962)
		(mid 125.641862 -75.999975)
		(end 126.000002 -76.358242)
		(stroke
			(width 0.2)
			(type default)
		)
		(layer "In6.Cu")
	)
	(gr_arc
		(start 126.000256 -74.641964)
		(mid 125.641862 -74.999977)
		(end 126.000002 -75.358244)
		(stroke
			(width 0.2)
			(type default)
		)
		(layer "In6.Cu")
	)
	(gr_arc
		(start 126.000256 -73.641966)
		(mid 125.641862 -73.999979)
		(end 126.000002 -74.358246)
		(stroke
			(width 0.2)
			(type default)
		)
		(layer "In6.Cu")
	)
	(gr_arc
		(start 126.000256 -72.641968)
		(mid 125.641862 -72.999981)
		(end 126.000002 -73.358248)
		(stroke
			(width 0.2)
			(type default)
		)
		(layer "In6.Cu")
	)
	(gr_arc
		(start 126.000256 -71.64197)
		(mid 125.641862 -71.999983)
		(end 126.000002 -72.35825)
		(stroke
			(width 0.2)
			(type default)
		)
		(layer "In6.Cu")
	)
	(gr_arc
		(start 126.000256 -70.641972)
		(mid 125.641862 -70.999985)
		(end 126.000002 -71.358252)
		(stroke
			(width 0.2)
			(type default)
		)
		(layer "In6.Cu")
	)
	(gr_arc
		(start 126.000256 -69.641974)
		(mid 125.641862 -69.999987)
		(end 126.000002 -70.358254)
		(stroke
			(width 0.2)
			(type default)
		)
		(layer "In6.Cu")
	)
	(gr_arc
		(start 126.000256 -68.641976)
		(mid 125.641862 -68.999989)
		(end 126.000002 -69.358256)
		(stroke
			(width 0.2)
			(type default)
		)
		(layer "In6.Cu")
	)
	(gr_arc
		(start 126.000256 -67.641978)
		(mid 125.641862 -67.999991)
		(end 126.000002 -68.358258)
		(stroke
			(width 0.2)
			(type default)
		)
		(layer "In6.Cu")
	)
	(gr_arc
		(start 126.000256 -65.641982)
		(mid 125.641862 -65.999995)
		(end 126.000002 -66.358262)
		(stroke
			(width 0.2)
			(type default)
		)
		(layer "In6.Cu")
	)
	(gr_arc
		(start 126.000256 -64.641984)
		(mid 125.641862 -64.999997)
		(end 126.000002 -65.358264)
		(stroke
			(width 0.2)
			(type default)
		)
		(layer "In6.Cu")
	)
	(gr_arc
		(start 126.000256 -63.641986)
		(mid 125.641862 -63.999999)
		(end 126.000002 -64.358266)
		(stroke
			(width 0.2)
			(type default)
		)
		(layer "In6.Cu")
	)
	(gr_arc
		(start 126.000256 -62.641988)
		(mid 125.641862 -63.000001)
		(end 126.000002 -63.358268)
		(stroke
			(width 0.2)
			(type default)
		)
		(layer "In6.Cu")
	)
	(gr_arc
		(start 126.000256 -61.64199)
		(mid 125.641862 -62.000003)
		(end 126.000002 -62.35827)
		(stroke
			(width 0.2)
			(type default)
		)
		(layer "In6.Cu")
	)
	(gr_arc
		(start 126.000256 -60.641992)
		(mid 125.641862 -61.000005)
		(end 126.000002 -61.358272)
		(stroke
			(width 0.2)
			(type default)
		)
		(layer "In6.Cu")
	)
	(gr_arc
		(start 126.000256 -59.641994)
		(mid 125.641862 -60.000007)
		(end 126.000002 -60.358274)
		(stroke
			(width 0.2)
			(type default)
		)
		(layer "In6.Cu")
	)
	(gr_arc
		(start 126.000256 -58.641996)
		(mid 125.641862 -59.000009)
		(end 126.000002 -59.358276)
		(stroke
			(width 0.2)
			(type default)
		)
		(layer "In6.Cu")
	)
	(gr_arc
		(start 126.000256 -57.641998)
		(mid 125.641862 -58.000011)
		(end 126.000002 -58.358278)
		(stroke
			(width 0.2)
			(type default)
		)
		(layer "In6.Cu")
	)
	(gr_arc
		(start 126.000256 -56.642)
		(mid 125.641862 -57.000013)
		(end 126.000002 -57.35828)
		(stroke
			(width 0.2)
			(type default)
		)
		(layer "In6.Cu")
	)
	(gr_arc
		(start 126.000256 -55.642002)
		(mid 125.641862 -56.000015)
		(end 126.000002 -56.358282)
		(stroke
			(width 0.2)
			(type default)
		)
		(layer "In6.Cu")
	)
	(gr_arc
		(start 126.000256 -54.642004)
		(mid 125.641862 -55.000017)
		(end 126.000002 -55.358284)
		(stroke
			(width 0.2)
			(type default)
		)
		(layer "In6.Cu")
	)
	(gr_arc
		(start 126.000256 -53.642006)
		(mid 125.641862 -54.000019)
		(end 126.000002 -54.358286)
		(stroke
			(width 0.2)
			(type default)
		)
		(layer "In6.Cu")
	)
	(gr_line
		(start 126.161546 -12.400026)
		(end 126.161546 -10.999978)
		(stroke
			(width 0.2)
			(type default)
		)
		(layer "In6.Cu")
	)
	(gr_arc
		(start 126.161546 -10.999978)
		(mid 125.600206 -10.438638)
		(end 125.038866 -10.999978)
		(stroke
			(width 0.2)
			(type default)
		)
		(layer "In6.Cu")
	)
	(gr_line
		(start 126.161546 -5.200142)
		(end 126.161546 -3.800094)
		(stroke
			(width 0.2)
			(type default)
		)
		(layer "In6.Cu")
	)
	(gr_arc
		(start 126.161546 -3.800094)
		(mid 125.600206 -3.238754)
		(end 125.038866 -3.800094)
		(stroke
			(width 0.2)
			(type default)
		)
		(layer "In6.Cu")
	)
	(gr_arc
		(start 126.619508 -46.986952)
		(mid 127.076581 -47.444406)
		(end 127.533908 -46.987206)
		(stroke
			(width 0.2)
			(type default)
		)
		(layer "In6.Cu")
	)
	(gr_line
		(start 126.619508 -45.844206)
		(end 126.619508 -46.986952)
		(stroke
			(width 0.2)
			(type default)
		)
		(layer "In6.Cu")
	)
	(gr_arc
		(start 126.7206 -39.878)
		(mid 126.735479 -39.913921)
		(end 126.7714 -39.9288)
		(stroke
			(width 0.2)
			(type default)
		)
		(layer "In6.Cu")
	)
	(gr_line
		(start 126.7206 -39.0652)
		(end 126.7206 -39.878)
		(stroke
			(width 0.2)
			(type default)
		)
		(layer "In6.Cu")
	)
	(gr_line
		(start 126.7714 -39.9288)
		(end 126.9746 -39.9288)
		(stroke
			(width 0.2)
			(type default)
		)
		(layer "In6.Cu")
	)
	(gr_arc
		(start 126.7714 -39.0144)
		(mid 126.735479 -39.029279)
		(end 126.7206 -39.0652)
		(stroke
			(width 0.2)
			(type default)
		)
		(layer "In6.Cu")
	)
	(gr_arc
		(start 126.83871 -11.199876)
		(mid 127.399923 -11.76147)
		(end 127.96139 -11.20013)
		(stroke
			(width 0.2)
			(type default)
		)
		(layer "In6.Cu")
	)
	(gr_line
		(start 126.83871 -9.800082)
		(end 126.83871 -11.199876)
		(stroke
			(width 0.2)
			(type default)
		)
		(layer "In6.Cu")
	)
	(gr_arc
		(start 126.83871 -3.999738)
		(mid 127.399923 -4.561332)
		(end 127.96139 -3.999992)
		(stroke
			(width 0.2)
			(type default)
		)
		(layer "In6.Cu")
	)
	(gr_line
		(start 126.83871 -2.600198)
		(end 126.83871 -3.999738)
		(stroke
			(width 0.2)
			(type default)
		)
		(layer "In6.Cu")
	)
	(gr_arc
		(start 126.9746 -39.9288)
		(mid 127.010521 -39.913921)
		(end 127.0254 -39.878)
		(stroke
			(width 0.2)
			(type default)
		)
		(layer "In6.Cu")
	)
	(gr_line
		(start 126.9746 -39.0144)
		(end 126.7714 -39.0144)
		(stroke
			(width 0.2)
			(type default)
		)
		(layer "In6.Cu")
	)
	(gr_arc
		(start 127 -77.35824)
		(mid 127.35814 -77.0001)
		(end 127 -76.64196)
		(stroke
			(width 0.2)
			(type default)
		)
		(layer "In6.Cu")
	)
	(gr_line
		(start 127 -76.64196)
		(end 126.000256 -76.64196)
		(stroke
			(width 0.2)
			(type default)
		)
		(layer "In6.Cu")
	)
	(gr_arc
		(start 127 -76.358242)
		(mid 127.35814 -76.000102)
		(end 127 -75.641962)
		(stroke
			(width 0.2)
			(type default)
		)
		(layer "In6.Cu")
	)
	(gr_line
		(start 127 -75.641962)
		(end 126.000256 -75.641962)
		(stroke
			(width 0.2)
			(type default)
		)
		(layer "In6.Cu")
	)
	(gr_arc
		(start 127 -75.358244)
		(mid 127.35814 -75.000104)
		(end 127 -74.641964)
		(stroke
			(width 0.2)
			(type default)
		)
		(layer "In6.Cu")
	)
	(gr_line
		(start 127 -74.641964)
		(end 126.000256 -74.641964)
		(stroke
			(width 0.2)
			(type default)
		)
		(layer "In6.Cu")
	)
	(gr_arc
		(start 127 -74.358246)
		(mid 127.35814 -74.000106)
		(end 127 -73.641966)
		(stroke
			(width 0.2)
			(type default)
		)
		(layer "In6.Cu")
	)
	(gr_line
		(start 127 -73.641966)
		(end 126.000256 -73.641966)
		(stroke
			(width 0.2)
			(type default)
		)
		(layer "In6.Cu")
	)
	(gr_arc
		(start 127 -73.358248)
		(mid 127.35814 -73.000108)
		(end 127 -72.641968)
		(stroke
			(width 0.2)
			(type default)
		)
		(layer "In6.Cu")
	)
	(gr_line
		(start 127 -72.641968)
		(end 126.000256 -72.641968)
		(stroke
			(width 0.2)
			(type default)
		)
		(layer "In6.Cu")
	)
	(gr_arc
		(start 127 -72.35825)
		(mid 127.35814 -72.00011)
		(end 127 -71.64197)
		(stroke
			(width 0.2)
			(type default)
		)
		(layer "In6.Cu")
	)
	(gr_line
		(start 127 -71.64197)
		(end 126.000256 -71.64197)
		(stroke
			(width 0.2)
			(type default)
		)
		(layer "In6.Cu")
	)
	(gr_arc
		(start 127 -71.358252)
		(mid 127.35814 -71.000112)
		(end 127 -70.641972)
		(stroke
			(width 0.2)
			(type default)
		)
		(layer "In6.Cu")
	)
	(gr_line
		(start 127 -70.641972)
		(end 126.000256 -70.641972)
		(stroke
			(width 0.2)
			(type default)
		)
		(layer "In6.Cu")
	)
	(gr_arc
		(start 127 -70.358254)
		(mid 127.35814 -70.000114)
		(end 127 -69.641974)
		(stroke
			(width 0.2)
			(type default)
		)
		(layer "In6.Cu")
	)
	(gr_line
		(start 127 -69.641974)
		(end 126.000256 -69.641974)
		(stroke
			(width 0.2)
			(type default)
		)
		(layer "In6.Cu")
	)
	(gr_arc
		(start 127 -69.358256)
		(mid 127.35814 -69.000116)
		(end 127 -68.641976)
		(stroke
			(width 0.2)
			(type default)
		)
		(layer "In6.Cu")
	)
	(gr_line
		(start 127 -68.641976)
		(end 126.000256 -68.641976)
		(stroke
			(width 0.2)
			(type default)
		)
		(layer "In6.Cu")
	)
	(gr_arc
		(start 127 -68.358258)
		(mid 127.35814 -68.000118)
		(end 127 -67.641978)
		(stroke
			(width 0.2)
			(type default)
		)
		(layer "In6.Cu")
	)
	(gr_line
		(start 127 -67.641978)
		(end 126.000256 -67.641978)
		(stroke
			(width 0.2)
			(type default)
		)
		(layer "In6.Cu")
	)
	(gr_arc
		(start 127 -66.358262)
		(mid 127.35814 -66.000122)
		(end 127 -65.641982)
		(stroke
			(width 0.2)
			(type default)
		)
		(layer "In6.Cu")
	)
	(gr_line
		(start 127 -65.641982)
		(end 126.000256 -65.641982)
		(stroke
			(width 0.2)
			(type default)
		)
		(layer "In6.Cu")
	)
	(gr_arc
		(start 127 -65.358264)
		(mid 127.35814 -65.000124)
		(end 127 -64.641984)
		(stroke
			(width 0.2)
			(type default)
		)
		(layer "In6.Cu")
	)
	(gr_line
		(start 127 -64.641984)
		(end 126.000256 -64.641984)
		(stroke
			(width 0.2)
			(type default)
		)
		(layer "In6.Cu")
	)
	(gr_arc
		(start 127 -64.358266)
		(mid 127.35814 -64.000126)
		(end 127 -63.641986)
		(stroke
			(width 0.2)
			(type default)
		)
		(layer "In6.Cu")
	)
	(gr_line
		(start 127 -63.641986)
		(end 126.000256 -63.641986)
		(stroke
			(width 0.2)
			(type default)
		)
		(layer "In6.Cu")
	)
	(gr_arc
		(start 127 -63.358268)
		(mid 127.35814 -63.000128)
		(end 127 -62.641988)
		(stroke
			(width 0.2)
			(type default)
		)
		(layer "In6.Cu")
	)
	(gr_line
		(start 127 -62.641988)
		(end 126.000256 -62.641988)
		(stroke
			(width 0.2)
			(type default)
		)
		(layer "In6.Cu")
	)
	(gr_arc
		(start 127 -62.35827)
		(mid 127.35814 -62.00013)
		(end 127 -61.64199)
		(stroke
			(width 0.2)
			(type default)
		)
		(layer "In6.Cu")
	)
	(gr_line
		(start 127 -61.64199)
		(end 126.000256 -61.64199)
		(stroke
			(width 0.2)
			(type default)
		)
		(layer "In6.Cu")
	)
	(gr_arc
		(start 127 -61.358272)
		(mid 127.35814 -61.000132)
		(end 127 -60.641992)
		(stroke
			(width 0.2)
			(type default)
		)
		(layer "In6.Cu")
	)
	(gr_line
		(start 127 -60.641992)
		(end 126.000256 -60.641992)
		(stroke
			(width 0.2)
			(type default)
		)
		(layer "In6.Cu")
	)
	(gr_arc
		(start 127 -60.358274)
		(mid 127.35814 -60.000134)
		(end 127 -59.641994)
		(stroke
			(width 0.2)
			(type default)
		)
		(layer "In6.Cu")
	)
	(gr_line
		(start 127 -59.641994)
		(end 126.000256 -59.641994)
		(stroke
			(width 0.2)
			(type default)
		)
		(layer "In6.Cu")
	)
	(gr_arc
		(start 127 -59.358276)
		(mid 127.35814 -59.000136)
		(end 127 -58.641996)
		(stroke
			(width 0.2)
			(type default)
		)
		(layer "In6.Cu")
	)
	(gr_line
		(start 127 -58.641996)
		(end 126.000256 -58.641996)
		(stroke
			(width 0.2)
			(type default)
		)
		(layer "In6.Cu")
	)
	(gr_arc
		(start 127 -58.358278)
		(mid 127.35814 -58.000138)
		(end 127 -57.641998)
		(stroke
			(width 0.2)
			(type default)
		)
		(layer "In6.Cu")
	)
	(gr_line
		(start 127 -57.641998)
		(end 126.000256 -57.641998)
		(stroke
			(width 0.2)
			(type default)
		)
		(layer "In6.Cu")
	)
	(gr_arc
		(start 127 -57.35828)
		(mid 127.35814 -57.00014)
		(end 127 -56.642)
		(stroke
			(width 0.2)
			(type default)
		)
		(layer "In6.Cu")
	)
	(gr_line
		(start 127 -56.642)
		(end 126.000256 -56.642)
		(stroke
			(width 0.2)
			(type default)
		)
		(layer "In6.Cu")
	)
	(gr_arc
		(start 127 -56.358282)
		(mid 127.35814 -56.000142)
		(end 127 -55.642002)
		(stroke
			(width 0.2)
			(type default)
		)
		(layer "In6.Cu")
	)
	(gr_line
		(start 127 -55.642002)
		(end 126.000256 -55.642002)
		(stroke
			(width 0.2)
			(type default)
		)
		(layer "In6.Cu")
	)
	(gr_arc
		(start 127 -55.358284)
		(mid 127.35814 -55.000144)
		(end 127 -54.642004)
		(stroke
			(width 0.2)
			(type default)
		)
		(layer "In6.Cu")
	)
	(gr_line
		(start 127 -54.642004)
		(end 126.000256 -54.642004)
		(stroke
			(width 0.2)
			(type default)
		)
		(layer "In6.Cu")
	)
	(gr_arc
		(start 127 -54.358286)
		(mid 127.35814 -54.000146)
		(end 127 -53.642006)
		(stroke
			(width 0.2)
			(type default)
		)
		(layer "In6.Cu")
	)
	(gr_line
		(start 127 -53.642006)
		(end 126.000256 -53.642006)
		(stroke
			(width 0.2)
			(type default)
		)
		(layer "In6.Cu")
	)
	(gr_line
		(start 127 -53.358288)
		(end 127.999998 -53.358288)
		(stroke
			(width 0.2)
			(type default)
		)
		(layer "In6.Cu")
	)
	(gr_arc
		(start 127.000254 -52.642008)
		(mid 126.64186 -53.000021)
		(end 127 -53.358288)
		(stroke
			(width 0.2)
			(type default)
		)
		(layer "In6.Cu")
	)
	(gr_line
		(start 127.0254 -39.878)
		(end 127.0254 -39.0652)
		(stroke
			(width 0.2)
			(type default)
		)
		(layer "In6.Cu")
	)
	(gr_arc
		(start 127.0254 -39.0652)
		(mid 127.010521 -39.029279)
		(end 126.9746 -39.0144)
		(stroke
			(width 0.2)
			(type default)
		)
		(layer "In6.Cu")
	)
	(gr_arc
		(start 127.3048 -39.878)
		(mid 127.319679 -39.913921)
		(end 127.3556 -39.9288)
		(stroke
			(width 0.2)
			(type default)
		)
		(layer "In6.Cu")
	)
	(gr_line
		(start 127.3048 -39.0652)
		(end 127.3048 -39.878)
		(stroke
			(width 0.2)
			(type default)
		)
		(layer "In6.Cu")
	)
	(gr_line
		(start 127.3556 -39.9288)
		(end 127.5588 -39.9288)
		(stroke
			(width 0.2)
			(type default)
		)
		(layer "In6.Cu")
	)
	(gr_arc
		(start 127.3556 -39.0144)
		(mid 127.319679 -39.029279)
		(end 127.3048 -39.0652)
		(stroke
			(width 0.2)
			(type default)
		)
		(layer "In6.Cu")
	)
	(gr_line
		(start 127.533908 -46.987206)
		(end 127.533908 -45.844206)
		(stroke
			(width 0.2)
			(type default)
		)
		(layer "In6.Cu")
	)
	(gr_arc
		(start 127.533908 -45.844206)
		(mid 127.076708 -45.387006)
		(end 126.619508 -45.844206)
		(stroke
			(width 0.2)
			(type default)
		)
		(layer "In6.Cu")
	)
	(gr_arc
		(start 127.5588 -39.9288)
		(mid 127.594721 -39.913921)
		(end 127.6096 -39.878)
		(stroke
			(width 0.2)
			(type default)
		)
		(layer "In6.Cu")
	)
	(gr_line
		(start 127.5588 -39.0144)
		(end 127.3556 -39.0144)
		(stroke
			(width 0.2)
			(type default)
		)
		(layer "In6.Cu")
	)
	(gr_line
		(start 127.6096 -39.878)
		(end 127.6096 -39.0652)
		(stroke
			(width 0.2)
			(type default)
		)
		(layer "In6.Cu")
	)
	(gr_arc
		(start 127.6096 -39.0652)
		(mid 127.594721 -39.029279)
		(end 127.5588 -39.0144)
		(stroke
			(width 0.2)
			(type default)
		)
		(layer "In6.Cu")
	)
	(gr_line
		(start 127.96139 -11.20013)
		(end 127.96139 -9.800082)
		(stroke
			(width 0.2)
			(type default)
		)
		(layer "In6.Cu")
	)
	(gr_arc
		(start 127.96139 -9.800082)
		(mid 127.40005 -9.238742)
		(end 126.83871 -9.800082)
		(stroke
			(width 0.2)
			(type default)
		)
		(layer "In6.Cu")
	)
	(gr_line
		(start 127.96139 -3.999992)
		(end 127.96139 -2.600198)
		(stroke
			(width 0.2)
			(type default)
		)
		(layer "In6.Cu")
	)
	(gr_arc
		(start 127.96139 -2.600198)
		(mid 127.40005 -2.038858)
		(end 126.83871 -2.600198)
		(stroke
			(width 0.2)
			(type default)
		)
		(layer "In6.Cu")
	)
	(gr_arc
		(start 127.999998 -53.358288)
		(mid 128.358138 -53.000148)
		(end 127.999998 -52.642008)
		(stroke
			(width 0.2)
			(type default)
		)
		(layer "In6.Cu")
	)
	(gr_line
		(start 127.999998 -52.642008)
		(end 127.000254 -52.642008)
		(stroke
			(width 0.2)
			(type default)
		)
		(layer "In6.Cu")
	)
	(gr_arc
		(start 128.0668 -41.275)
		(mid 128.081679 -41.310921)
		(end 128.1176 -41.3258)
		(stroke
			(width 0.2)
			(type default)
		)
		(layer "In6.Cu")
	)
	(gr_line
		(start 128.0668 -40.4622)
		(end 128.0668 -41.275)
		(stroke
			(width 0.2)
			(type default)
		)
		(layer "In6.Cu")
	)
	(gr_line
		(start 128.1176 -41.3258)
		(end 128.3208 -41.3258)
		(stroke
			(width 0.2)
			(type default)
		)
		(layer "In6.Cu")
	)
	(gr_arc
		(start 128.1176 -40.4114)
		(mid 128.081679 -40.426279)
		(end 128.0668 -40.4622)
		(stroke
			(width 0.2)
			(type default)
		)
		(layer "In6.Cu")
	)
	(gr_arc
		(start 128.3208 -41.3258)
		(mid 128.356721 -41.310921)
		(end 128.3716 -41.275)
		(stroke
			(width 0.2)
			(type default)
		)
		(layer "In6.Cu")
	)
	(gr_line
		(start 128.3208 -40.4114)
		(end 128.1176 -40.4114)
		(stroke
			(width 0.2)
			(type default)
		)
		(layer "In6.Cu")
	)
	(gr_line
		(start 128.3716 -41.275)
		(end 128.3716 -40.4622)
		(stroke
			(width 0.2)
			(type default)
		)
		(layer "In6.Cu")
	)
	(gr_arc
		(start 128.3716 -40.4622)
		(mid 128.356721 -40.426279)
		(end 128.3208 -40.4114)
		(stroke
			(width 0.2)
			(type default)
		)
		(layer "In6.Cu")
	)
	(gr_arc
		(start 128.638808 -12.399772)
		(mid 129.200021 -12.961366)
		(end 129.761488 -12.400026)
		(stroke
			(width 0.2)
			(type default)
		)
		(layer "In6.Cu")
	)
	(gr_line
		(start 128.638808 -10.999978)
		(end 128.638808 -12.399772)
		(stroke
			(width 0.2)
			(type default)
		)
		(layer "In6.Cu")
	)
	(gr_arc
		(start 128.638808 -5.199888)
		(mid 129.200021 -5.761482)
		(end 129.761488 -5.200142)
		(stroke
			(width 0.2)
			(type default)
		)
		(layer "In6.Cu")
	)
	(gr_line
		(start 128.638808 -3.800094)
		(end 128.638808 -5.199888)
		(stroke
			(width 0.2)
			(type default)
		)
		(layer "In6.Cu")
	)
	(gr_arc
		(start 128.651 -41.275)
		(mid 128.665879 -41.310921)
		(end 128.7018 -41.3258)
		(stroke
			(width 0.2)
			(type default)
		)
		(layer "In6.Cu")
	)
	(gr_line
		(start 128.651 -40.4622)
		(end 128.651 -41.275)
		(stroke
			(width 0.2)
			(type default)
		)
		(layer "In6.Cu")
	)
	(gr_line
		(start 128.7018 -41.3258)
		(end 128.905 -41.3258)
		(stroke
			(width 0.2)
			(type default)
		)
		(layer "In6.Cu")
	)
	(gr_arc
		(start 128.7018 -40.4114)
		(mid 128.665879 -40.426279)
		(end 128.651 -40.4622)
		(stroke
			(width 0.2)
			(type default)
		)
		(layer "In6.Cu")
	)
	(gr_arc
		(start 128.905 -41.3258)
		(mid 128.940921 -41.310921)
		(end 128.9558 -41.275)
		(stroke
			(width 0.2)
			(type default)
		)
		(layer "In6.Cu")
	)
	(gr_line
		(start 128.905 -40.4114)
		(end 128.7018 -40.4114)
		(stroke
			(width 0.2)
			(type default)
		)
		(layer "In6.Cu")
	)
	(gr_line
		(start 128.9558 -41.275)
		(end 128.9558 -40.4622)
		(stroke
			(width 0.2)
			(type default)
		)
		(layer "In6.Cu")
	)
	(gr_arc
		(start 128.9558 -40.4622)
		(mid 128.940921 -40.426279)
		(end 128.905 -40.4114)
		(stroke
			(width 0.2)
			(type default)
		)
		(layer "In6.Cu")
	)
	(gr_line
		(start 128.999996 -72.35825)
		(end 129.999994 -72.35825)
		(stroke
			(width 0.2)
			(type default)
		)
		(layer "In6.Cu")
	)
	(gr_line
		(start 128.999996 -70.358254)
		(end 129.999994 -70.358254)
		(stroke
			(width 0.2)
			(type default)
		)
		(layer "In6.Cu")
	)
	(gr_line
		(start 128.999996 -68.358258)
		(end 129.999994 -68.358258)
		(stroke
			(width 0.2)
			(type default)
		)
		(layer "In6.Cu")
	)
	(gr_line
		(start 128.999996 -65.358264)
		(end 129.999994 -65.358264)
		(stroke
			(width 0.2)
			(type default)
		)
		(layer "In6.Cu")
	)
	(gr_line
		(start 128.999996 -63.358268)
		(end 129.999994 -63.358268)
		(stroke
			(width 0.2)
			(type default)
		)
		(layer "In6.Cu")
	)
	(gr_line
		(start 128.999996 -61.358272)
		(end 129.999994 -61.358272)
		(stroke
			(width 0.2)
			(type default)
		)
		(layer "In6.Cu")
	)
	(gr_arc
		(start 129.00025 -71.64197)
		(mid 128.641856 -71.999983)
		(end 128.999996 -72.35825)
		(stroke
			(width 0.2)
			(type default)
		)
		(layer "In6.Cu")
	)
	(gr_arc
		(start 129.00025 -69.641974)
		(mid 128.641856 -69.999987)
		(end 128.999996 -70.358254)
		(stroke
			(width 0.2)
			(type default)
		)
		(layer "In6.Cu")
	)
	(gr_arc
		(start 129.00025 -67.641978)
		(mid 128.641856 -67.999991)
		(end 128.999996 -68.358258)
		(stroke
			(width 0.2)
			(type default)
		)
		(layer "In6.Cu")
	)
	(gr_arc
		(start 129.00025 -64.641984)
		(mid 128.641856 -64.999997)
		(end 128.999996 -65.358264)
		(stroke
			(width 0.2)
			(type default)
		)
		(layer "In6.Cu")
	)
	(gr_arc
		(start 129.00025 -62.641988)
		(mid 128.641856 -63.000001)
		(end 128.999996 -63.358268)
		(stroke
			(width 0.2)
			(type default)
		)
		(layer "In6.Cu")
	)
	(gr_arc
		(start 129.00025 -60.641992)
		(mid 128.641856 -61.000005)
		(end 128.999996 -61.358272)
		(stroke
			(width 0.2)
			(type default)
		)
		(layer "In6.Cu")
	)
	(gr_arc
		(start 129.191258 -46.97222)
		(mid 129.648331 -47.429674)
		(end 130.105658 -46.972474)
		(stroke
			(width 0.2)
			(type default)
		)
		(layer "In6.Cu")
	)
	(gr_line
		(start 129.191258 -45.829474)
		(end 129.191258 -46.97222)
		(stroke
			(width 0.2)
			(type default)
		)
		(layer "In6.Cu")
	)
	(gr_line
		(start 129.761488 -12.400026)
		(end 129.761488 -10.999978)
		(stroke
			(width 0.2)
			(type default)
		)
		(layer "In6.Cu")
	)
	(gr_arc
		(start 129.761488 -10.999978)
		(mid 129.200148 -10.438638)
		(end 128.638808 -10.999978)
		(stroke
			(width 0.2)
			(type default)
		)
		(layer "In6.Cu")
	)
	(gr_line
		(start 129.761488 -5.200142)
		(end 129.761488 -3.800094)
		(stroke
			(width 0.2)
			(type default)
		)
		(layer "In6.Cu")
	)
	(gr_arc
		(start 129.761488 -3.800094)
		(mid 129.200148 -3.238754)
		(end 128.638808 -3.800094)
		(stroke
			(width 0.2)
			(type default)
		)
		(layer "In6.Cu")
	)
	(gr_line
		(start 129.999994 -73.358248)
		(end 130.999992 -73.358248)
		(stroke
			(width 0.2)
			(type default)
		)
		(layer "In6.Cu")
	)
	(gr_arc
		(start 129.999994 -72.35825)
		(mid 130.358134 -72.00011)
		(end 129.999994 -71.64197)
		(stroke
			(width 0.2)
			(type default)
		)
		(layer "In6.Cu")
	)
	(gr_line
		(start 129.999994 -71.64197)
		(end 129.00025 -71.64197)
		(stroke
			(width 0.2)
			(type default)
		)
		(layer "In6.Cu")
	)
	(gr_line
		(start 129.999994 -71.358252)
		(end 130.999992 -71.358252)
		(stroke
			(width 0.2)
			(type default)
		)
		(layer "In6.Cu")
	)
	(gr_arc
		(start 129.999994 -70.358254)
		(mid 130.358134 -70.000114)
		(end 129.999994 -69.641974)
		(stroke
			(width 0.2)
			(type default)
		)
		(layer "In6.Cu")
	)
	(gr_line
		(start 129.999994 -69.641974)
		(end 129.00025 -69.641974)
		(stroke
			(width 0.2)
			(type default)
		)
		(layer "In6.Cu")
	)
	(gr_line
		(start 129.999994 -69.358256)
		(end 130.999992 -69.358256)
		(stroke
			(width 0.2)
			(type default)
		)
		(layer "In6.Cu")
	)
	(gr_arc
		(start 129.999994 -68.358258)
		(mid 130.358134 -68.000118)
		(end 129.999994 -67.641978)
		(stroke
			(width 0.2)
			(type default)
		)
		(layer "In6.Cu")
	)
	(gr_line
		(start 129.999994 -67.641978)
		(end 129.00025 -67.641978)
		(stroke
			(width 0.2)
			(type default)
		)
		(layer "In6.Cu")
	)
	(gr_line
		(start 129.999994 -66.358262)
		(end 130.999992 -66.358262)
		(stroke
			(width 0.2)
			(type default)
		)
		(layer "In6.Cu")
	)
	(gr_arc
		(start 129.999994 -65.358264)
		(mid 130.358134 -65.000124)
		(end 129.999994 -64.641984)
		(stroke
			(width 0.2)
			(type default)
		)
		(layer "In6.Cu")
	)
	(gr_line
		(start 129.999994 -64.641984)
		(end 129.00025 -64.641984)
		(stroke
			(width 0.2)
			(type default)
		)
		(layer "In6.Cu")
	)
	(gr_line
		(start 129.999994 -64.358266)
		(end 130.999992 -64.358266)
		(stroke
			(width 0.2)
			(type default)
		)
		(layer "In6.Cu")
	)
	(gr_arc
		(start 129.999994 -63.358268)
		(mid 130.358134 -63.000128)
		(end 129.999994 -62.641988)
		(stroke
			(width 0.2)
			(type default)
		)
		(layer "In6.Cu")
	)
	(gr_line
		(start 129.999994 -62.641988)
		(end 129.00025 -62.641988)
		(stroke
			(width 0.2)
			(type default)
		)
		(layer "In6.Cu")
	)
	(gr_line
		(start 129.999994 -62.35827)
		(end 130.999992 -62.35827)
		(stroke
			(width 0.2)
			(type default)
		)
		(layer "In6.Cu")
	)
	(gr_arc
		(start 129.999994 -61.358272)
		(mid 130.358134 -61.000132)
		(end 129.999994 -60.641992)
		(stroke
			(width 0.2)
			(type default)
		)
		(layer "In6.Cu")
	)
	(gr_line
		(start 129.999994 -60.641992)
		(end 129.00025 -60.641992)
		(stroke
			(width 0.2)
			(type default)
		)
		(layer "In6.Cu")
	)
	(gr_arc
		(start 130.000248 -72.641968)
		(mid 129.641854 -72.999981)
		(end 129.999994 -73.358248)
		(stroke
			(width 0.2)
			(type default)
		)
		(layer "In6.Cu")
	)
	(gr_arc
		(start 130.000248 -70.641972)
		(mid 129.641854 -70.999985)
		(end 129.999994 -71.358252)
		(stroke
			(width 0.2)
			(type default)
		)
		(layer "In6.Cu")
	)
	(gr_arc
		(start 130.000248 -68.641976)
		(mid 129.641854 -68.999989)
		(end 129.999994 -69.358256)
		(stroke
			(width 0.2)
			(type default)
		)
		(layer "In6.Cu")
	)
	(gr_arc
		(start 130.000248 -65.641982)
		(mid 129.641854 -65.999995)
		(end 129.999994 -66.358262)
		(stroke
			(width 0.2)
			(type default)
		)
		(layer "In6.Cu")
	)
	(gr_arc
		(start 130.000248 -63.641986)
		(mid 129.641854 -63.999999)
		(end 129.999994 -64.358266)
		(stroke
			(width 0.2)
			(type default)
		)
		(layer "In6.Cu")
	)
	(gr_arc
		(start 130.000248 -61.64199)
		(mid 129.641854 -62.000003)
		(end 129.999994 -62.35827)
		(stroke
			(width 0.2)
			(type default)
		)
		(layer "In6.Cu")
	)
	(gr_line
		(start 130.105658 -46.972474)
		(end 130.105658 -45.829474)
		(stroke
			(width 0.2)
			(type default)
		)
		(layer "In6.Cu")
	)
	(gr_arc
		(start 130.105658 -45.829474)
		(mid 129.648458 -45.372274)
		(end 129.191258 -45.829474)
		(stroke
			(width 0.2)
			(type default)
		)
		(layer "In6.Cu")
	)
	(gr_arc
		(start 130.438652 -11.199876)
		(mid 130.999865 -11.76147)
		(end 131.561332 -11.20013)
		(stroke
			(width 0.2)
			(type default)
		)
		(layer "In6.Cu")
	)
	(gr_line
		(start 130.438652 -9.800082)
		(end 130.438652 -11.199876)
		(stroke
			(width 0.2)
			(type default)
		)
		(layer "In6.Cu")
	)
	(gr_arc
		(start 130.438652 -3.999738)
		(mid 130.999865 -4.561332)
		(end 131.561332 -3.999992)
		(stroke
			(width 0.2)
			(type default)
		)
		(layer "In6.Cu")
	)
	(gr_line
		(start 130.438652 -2.600198)
		(end 130.438652 -3.999738)
		(stroke
			(width 0.2)
			(type default)
		)
		(layer "In6.Cu")
	)
	(gr_arc
		(start 130.67157 -44.785788)
		(mid 130.686449 -44.821709)
		(end 130.72237 -44.836588)
		(stroke
			(width 0.2)
			(type default)
		)
		(layer "In6.Cu")
	)
	(gr_line
		(start 130.67157 -43.972988)
		(end 130.67157 -44.785788)
		(stroke
			(width 0.2)
			(type default)
		)
		(layer "In6.Cu")
	)
	(gr_line
		(start 130.72237 -44.836588)
		(end 130.92557 -44.836588)
		(stroke
			(width 0.2)
			(type default)
		)
		(layer "In6.Cu")
	)
	(gr_arc
		(start 130.72237 -43.922188)
		(mid 130.686449 -43.937067)
		(end 130.67157 -43.972988)
		(stroke
			(width 0.2)
			(type default)
		)
		(layer "In6.Cu")
	)
	(gr_arc
		(start 130.92557 -44.836588)
		(mid 130.961491 -44.821709)
		(end 130.97637 -44.785788)
		(stroke
			(width 0.2)
			(type default)
		)
		(layer "In6.Cu")
	)
	(gr_line
		(start 130.92557 -43.922188)
		(end 130.72237 -43.922188)
		(stroke
			(width 0.2)
			(type default)
		)
		(layer "In6.Cu")
	)
	(gr_line
		(start 130.97637 -44.785788)
		(end 130.97637 -43.972988)
		(stroke
			(width 0.2)
			(type default)
		)
		(layer "In6.Cu")
	)
	(gr_arc
		(start 130.97637 -43.972988)
		(mid 130.961491 -43.937067)
		(end 130.92557 -43.922188)
		(stroke
			(width 0.2)
			(type default)
		)
		(layer "In6.Cu")
	)
	(gr_arc
		(start 130.999992 -73.358248)
		(mid 131.358132 -73.000108)
		(end 130.999992 -72.641968)
		(stroke
			(width 0.2)
			(type default)
		)
		(layer "In6.Cu")
	)
	(gr_line
		(start 130.999992 -72.641968)
		(end 130.000248 -72.641968)
		(stroke
			(width 0.2)
			(type default)
		)
		(layer "In6.Cu")
	)
	(gr_arc
		(start 130.999992 -71.358252)
		(mid 131.358132 -71.000112)
		(end 130.999992 -70.641972)
		(stroke
			(width 0.2)
			(type default)
		)
		(layer "In6.Cu")
	)
	(gr_line
		(start 130.999992 -70.641972)
		(end 130.000248 -70.641972)
		(stroke
			(width 0.2)
			(type default)
		)
		(layer "In6.Cu")
	)
	(gr_arc
		(start 130.999992 -69.358256)
		(mid 131.358132 -69.000116)
		(end 130.999992 -68.641976)
		(stroke
			(width 0.2)
			(type default)
		)
		(layer "In6.Cu")
	)
	(gr_line
		(start 130.999992 -68.641976)
		(end 130.000248 -68.641976)
		(stroke
			(width 0.2)
			(type default)
		)
		(layer "In6.Cu")
	)
	(gr_arc
		(start 130.999992 -66.358262)
		(mid 131.358132 -66.000122)
		(end 130.999992 -65.641982)
		(stroke
			(width 0.2)
			(type default)
		)
		(layer "In6.Cu")
	)
	(gr_line
		(start 130.999992 -65.641982)
		(end 130.000248 -65.641982)
		(stroke
			(width 0.2)
			(type default)
		)
		(layer "In6.Cu")
	)
	(gr_arc
		(start 130.999992 -64.358266)
		(mid 131.358132 -64.000126)
		(end 130.999992 -63.641986)
		(stroke
			(width 0.2)
			(type default)
		)
		(layer "In6.Cu")
	)
	(gr_line
		(start 130.999992 -63.641986)
		(end 130.000248 -63.641986)
		(stroke
			(width 0.2)
			(type default)
		)
		(layer "In6.Cu")
	)
	(gr_arc
		(start 130.999992 -62.35827)
		(mid 131.358132 -62.00013)
		(end 130.999992 -61.64199)
		(stroke
			(width 0.2)
			(type default)
		)
		(layer "In6.Cu")
	)
	(gr_line
		(start 130.999992 -61.64199)
		(end 130.000248 -61.64199)
		(stroke
			(width 0.2)
			(type default)
		)
		(layer "In6.Cu")
	)
	(gr_arc
		(start 131.23037 -44.785788)
		(mid 131.245249 -44.821709)
		(end 131.28117 -44.836588)
		(stroke
			(width 0.2)
			(type default)
		)
		(layer "In6.Cu")
	)
	(gr_line
		(start 131.23037 -43.972988)
		(end 131.23037 -44.785788)
		(stroke
			(width 0.2)
			(type default)
		)
		(layer "In6.Cu")
	)
	(gr_line
		(start 131.28117 -44.836588)
		(end 131.48437 -44.836588)
		(stroke
			(width 0.2)
			(type default)
		)
		(layer "In6.Cu")
	)
	(gr_arc
		(start 131.28117 -43.922188)
		(mid 131.245249 -43.937067)
		(end 131.23037 -43.972988)
		(stroke
			(width 0.2)
			(type default)
		)
		(layer "In6.Cu")
	)
	(gr_arc
		(start 131.48437 -44.836588)
		(mid 131.520291 -44.821709)
		(end 131.53517 -44.785788)
		(stroke
			(width 0.2)
			(type default)
		)
		(layer "In6.Cu")
	)
	(gr_line
		(start 131.48437 -43.922188)
		(end 131.28117 -43.922188)
		(stroke
			(width 0.2)
			(type default)
		)
		(layer "In6.Cu")
	)
	(gr_line
		(start 131.53517 -44.785788)
		(end 131.53517 -43.972988)
		(stroke
			(width 0.2)
			(type default)
		)
		(layer "In6.Cu")
	)
	(gr_arc
		(start 131.53517 -43.972988)
		(mid 131.520291 -43.937067)
		(end 131.48437 -43.922188)
		(stroke
			(width 0.2)
			(type default)
		)
		(layer "In6.Cu")
	)
	(gr_line
		(start 131.561332 -11.20013)
		(end 131.561332 -9.800082)
		(stroke
			(width 0.2)
			(type default)
		)
		(layer "In6.Cu")
	)
	(gr_arc
		(start 131.561332 -9.800082)
		(mid 130.999992 -9.238742)
		(end 130.438652 -9.800082)
		(stroke
			(width 0.2)
			(type default)
		)
		(layer "In6.Cu")
	)
	(gr_line
		(start 131.561332 -3.999992)
		(end 131.561332 -2.600198)
		(stroke
			(width 0.2)
			(type default)
		)
		(layer "In6.Cu")
	)
	(gr_arc
		(start 131.561332 -2.600198)
		(mid 130.999992 -2.038858)
		(end 130.438652 -2.600198)
		(stroke
			(width 0.2)
			(type default)
		)
		(layer "In6.Cu")
	)
	(gr_arc
		(start 131.763008 -46.957488)
		(mid 132.220081 -47.414942)
		(end 132.677408 -46.957742)
		(stroke
			(width 0.2)
			(type default)
		)
		(layer "In6.Cu")
	)
	(gr_line
		(start 131.763008 -45.814742)
		(end 131.763008 -46.957488)
		(stroke
			(width 0.2)
			(type default)
		)
		(layer "In6.Cu")
	)
	(gr_arc
		(start 132.23875 -12.399772)
		(mid 132.799963 -12.961366)
		(end 133.36143 -12.400026)
		(stroke
			(width 0.2)
			(type default)
		)
		(layer "In6.Cu")
	)
	(gr_line
		(start 132.23875 -10.999978)
		(end 132.23875 -12.399772)
		(stroke
			(width 0.2)
			(type default)
		)
		(layer "In6.Cu")
	)
	(gr_arc
		(start 132.23875 -5.199888)
		(mid 132.799963 -5.761482)
		(end 133.36143 -5.200142)
		(stroke
			(width 0.2)
			(type default)
		)
		(layer "In6.Cu")
	)
	(gr_line
		(start 132.23875 -3.800094)
		(end 132.23875 -5.199888)
		(stroke
			(width 0.2)
			(type default)
		)
		(layer "In6.Cu")
	)
	(gr_line
		(start 132.677408 -46.957742)
		(end 132.677408 -45.814742)
		(stroke
			(width 0.2)
			(type default)
		)
		(layer "In6.Cu")
	)
	(gr_arc
		(start 132.677408 -45.814742)
		(mid 132.220208 -45.357542)
		(end 131.763008 -45.814742)
		(stroke
			(width 0.2)
			(type default)
		)
		(layer "In6.Cu")
	)
	(gr_arc
		(start 133.1214 -44.8056)
		(mid 133.136279 -44.841521)
		(end 133.1722 -44.8564)
		(stroke
			(width 0.2)
			(type default)
		)
		(layer "In6.Cu")
	)
	(gr_line
		(start 133.1214 -43.9928)
		(end 133.1214 -44.8056)
		(stroke
			(width 0.2)
			(type default)
		)
		(layer "In6.Cu")
	)
	(gr_line
		(start 133.1722 -44.8564)
		(end 133.3754 -44.8564)
		(stroke
			(width 0.2)
			(type default)
		)
		(layer "In6.Cu")
	)
	(gr_arc
		(start 133.1722 -43.942)
		(mid 133.136279 -43.956879)
		(end 133.1214 -43.9928)
		(stroke
			(width 0.2)
			(type default)
		)
		(layer "In6.Cu")
	)
	(gr_line
		(start 133.36143 -12.400026)
		(end 133.36143 -10.999978)
		(stroke
			(width 0.2)
			(type default)
		)
		(layer "In6.Cu")
	)
	(gr_arc
		(start 133.36143 -10.999978)
		(mid 132.80009 -10.438638)
		(end 132.23875 -10.999978)
		(stroke
			(width 0.2)
			(type default)
		)
		(layer "In6.Cu")
	)
	(gr_line
		(start 133.36143 -5.200142)
		(end 133.36143 -3.800094)
		(stroke
			(width 0.2)
			(type default)
		)
		(layer "In6.Cu")
	)
	(gr_arc
		(start 133.36143 -3.800094)
		(mid 132.80009 -3.238754)
		(end 132.23875 -3.800094)
		(stroke
			(width 0.2)
			(type default)
		)
		(layer "In6.Cu")
	)
	(gr_arc
		(start 133.3754 -44.8564)
		(mid 133.411321 -44.841521)
		(end 133.4262 -44.8056)
		(stroke
			(width 0.2)
			(type default)
		)
		(layer "In6.Cu")
	)
	(gr_line
		(start 133.3754 -43.942)
		(end 133.1722 -43.942)
		(stroke
			(width 0.2)
			(type default)
		)
		(layer "In6.Cu")
	)
	(gr_line
		(start 133.4262 -44.8056)
		(end 133.4262 -43.9928)
		(stroke
			(width 0.2)
			(type default)
		)
		(layer "In6.Cu")
	)
	(gr_arc
		(start 133.4262 -43.9928)
		(mid 133.411321 -43.956879)
		(end 133.3754 -43.942)
		(stroke
			(width 0.2)
			(type default)
		)
		(layer "In6.Cu")
	)
	(gr_arc
		(start 133.6802 -44.8056)
		(mid 133.695079 -44.841521)
		(end 133.731 -44.8564)
		(stroke
			(width 0.2)
			(type default)
		)
		(layer "In6.Cu")
	)
	(gr_line
		(start 133.6802 -43.9928)
		(end 133.6802 -44.8056)
		(stroke
			(width 0.2)
			(type default)
		)
		(layer "In6.Cu")
	)
	(gr_line
		(start 133.731 -44.8564)
		(end 133.9342 -44.8564)
		(stroke
			(width 0.2)
			(type default)
		)
		(layer "In6.Cu")
	)
	(gr_arc
		(start 133.731 -43.942)
		(mid 133.695079 -43.956879)
		(end 133.6802 -43.9928)
		(stroke
			(width 0.2)
			(type default)
		)
		(layer "In6.Cu")
	)
	(gr_arc
		(start 133.9342 -44.8564)
		(mid 133.970121 -44.841521)
		(end 133.985 -44.8056)
		(stroke
			(width 0.2)
			(type default)
		)
		(layer "In6.Cu")
	)
	(gr_line
		(start 133.9342 -43.942)
		(end 133.731 -43.942)
		(stroke
			(width 0.2)
			(type default)
		)
		(layer "In6.Cu")
	)
	(gr_line
		(start 133.985 -44.8056)
		(end 133.985 -43.9928)
		(stroke
			(width 0.2)
			(type default)
		)
		(layer "In6.Cu")
	)
	(gr_arc
		(start 133.985 -43.9928)
		(mid 133.970121 -43.956879)
		(end 133.9342 -43.942)
		(stroke
			(width 0.2)
			(type default)
		)
		(layer "In6.Cu")
	)
	(gr_arc
		(start 134.036054 -65.168018)
		(mid 134.050933 -65.203939)
		(end 134.086854 -65.218818)
		(stroke
			(width 0.2)
			(type default)
		)
		(layer "In6.Cu")
	)
	(gr_line
		(start 134.036054 -64.964818)
		(end 134.036054 -65.168018)
		(stroke
			(width 0.2)
			(type default)
		)
		(layer "In6.Cu")
	)
	(gr_arc
		(start 134.036054 -64.609218)
		(mid 134.050933 -64.645139)
		(end 134.086854 -64.660018)
		(stroke
			(width 0.2)
			(type default)
		)
		(layer "In6.Cu")
	)
	(gr_line
		(start 134.036054 -64.406018)
		(end 134.036054 -64.609218)
		(stroke
			(width 0.2)
			(type default)
		)
		(layer "In6.Cu")
	)
	(gr_arc
		(start 134.038848 -11.199876)
		(mid 134.600061 -11.76147)
		(end 135.161528 -11.20013)
		(stroke
			(width 0.2)
			(type default)
		)
		(layer "In6.Cu")
	)
	(gr_line
		(start 134.038848 -9.800082)
		(end 134.038848 -11.199876)
		(stroke
			(width 0.2)
			(type default)
		)
		(layer "In6.Cu")
	)
	(gr_arc
		(start 134.038848 -3.999738)
		(mid 134.600061 -4.561332)
		(end 135.161528 -3.999992)
		(stroke
			(width 0.2)
			(type default)
		)
		(layer "In6.Cu")
	)
	(gr_line
		(start 134.038848 -2.600198)
		(end 134.038848 -3.999738)
		(stroke
			(width 0.2)
			(type default)
		)
		(layer "In6.Cu")
	)
	(gr_line
		(start 134.086854 -65.218818)
		(end 134.899654 -65.218818)
		(stroke
			(width 0.2)
			(type default)
		)
		(layer "In6.Cu")
	)
	(gr_arc
		(start 134.086854 -64.914018)
		(mid 134.050933 -64.928897)
		(end 134.036054 -64.964818)
		(stroke
			(width 0.2)
			(type default)
		)
		(layer "In6.Cu")
	)
	(gr_line
		(start 134.086854 -64.660018)
		(end 134.899654 -64.660018)
		(stroke
			(width 0.2)
			(type default)
		)
		(layer "In6.Cu")
	)
	(gr_arc
		(start 134.086854 -64.355218)
		(mid 134.050933 -64.370097)
		(end 134.036054 -64.406018)
		(stroke
			(width 0.2)
			(type default)
		)
		(layer "In6.Cu")
	)
	(gr_arc
		(start 134.694422 -56.786018)
		(mid 134.709301 -56.821939)
		(end 134.745222 -56.836818)
		(stroke
			(width 0.2)
			(type default)
		)
		(layer "In6.Cu")
	)
	(gr_line
		(start 134.694422 -55.973218)
		(end 134.694422 -56.786018)
		(stroke
			(width 0.2)
			(type default)
		)
		(layer "In6.Cu")
	)
	(gr_line
		(start 134.745222 -56.836818)
		(end 134.948422 -56.836818)
		(stroke
			(width 0.2)
			(type default)
		)
		(layer "In6.Cu")
	)
	(gr_arc
		(start 134.745222 -55.922418)
		(mid 134.709301 -55.937297)
		(end 134.694422 -55.973218)
		(stroke
			(width 0.2)
			(type default)
		)
		(layer "In6.Cu")
	)
	(gr_arc
		(start 134.899654 -65.218818)
		(mid 134.935575 -65.203939)
		(end 134.950454 -65.168018)
		(stroke
			(width 0.2)
			(type default)
		)
		(layer "In6.Cu")
	)
	(gr_line
		(start 134.899654 -64.914018)
		(end 134.086854 -64.914018)
		(stroke
			(width 0.2)
			(type default)
		)
		(layer "In6.Cu")
	)
	(gr_arc
		(start 134.899654 -64.660018)
		(mid 134.935575 -64.645139)
		(end 134.950454 -64.609218)
		(stroke
			(width 0.2)
			(type default)
		)
		(layer "In6.Cu")
	)
	(gr_line
		(start 134.899654 -64.355218)
		(end 134.086854 -64.355218)
		(stroke
			(width 0.2)
			(type default)
		)
		(layer "In6.Cu")
	)
	(gr_arc
		(start 134.948422 -56.836818)
		(mid 134.984343 -56.821939)
		(end 134.999222 -56.786018)
		(stroke
			(width 0.2)
			(type default)
		)
		(layer "In6.Cu")
	)
	(gr_line
		(start 134.948422 -55.922418)
		(end 134.745222 -55.922418)
		(stroke
			(width 0.2)
			(type default)
		)
		(layer "In6.Cu")
	)
	(gr_line
		(start 134.950454 -65.168018)
		(end 134.950454 -64.964818)
		(stroke
			(width 0.2)
			(type default)
		)
		(layer "In6.Cu")
	)
	(gr_arc
		(start 134.950454 -64.964818)
		(mid 134.935575 -64.928897)
		(end 134.899654 -64.914018)
		(stroke
			(width 0.2)
			(type default)
		)
		(layer "In6.Cu")
	)
	(gr_line
		(start 134.950454 -64.609218)
		(end 134.950454 -64.406018)
		(stroke
			(width 0.2)
			(type default)
		)
		(layer "In6.Cu")
	)
	(gr_arc
		(start 134.950454 -64.406018)
		(mid 134.935575 -64.370097)
		(end 134.899654 -64.355218)
		(stroke
			(width 0.2)
			(type default)
		)
		(layer "In6.Cu")
	)
	(gr_arc
		(start 134.95528 -61.711078)
		(mid 134.970159 -61.746999)
		(end 135.00608 -61.761878)
		(stroke
			(width 0.2)
			(type default)
		)
		(layer "In6.Cu")
	)
	(gr_line
		(start 134.95528 -60.898278)
		(end 134.95528 -61.711078)
		(stroke
			(width 0.2)
			(type default)
		)
		(layer "In6.Cu")
	)
	(gr_line
		(start 134.999222 -56.786018)
		(end 134.999222 -55.973218)
		(stroke
			(width 0.2)
			(type default)
		)
		(layer "In6.Cu")
	)
	(gr_arc
		(start 134.999222 -55.973218)
		(mid 134.984343 -55.937297)
		(end 134.948422 -55.922418)
		(stroke
			(width 0.2)
			(type default)
		)
		(layer "In6.Cu")
	)
	(gr_line
		(start 135.00608 -61.761878)
		(end 135.20928 -61.761878)
		(stroke
			(width 0.2)
			(type default)
		)
		(layer "In6.Cu")
	)
	(gr_arc
		(start 135.00608 -60.847478)
		(mid 134.970159 -60.862357)
		(end 134.95528 -60.898278)
		(stroke
			(width 0.2)
			(type default)
		)
		(layer "In6.Cu")
	)
	(gr_line
		(start 135.161528 -11.20013)
		(end 135.161528 -9.800082)
		(stroke
			(width 0.2)
			(type default)
		)
		(layer "In6.Cu")
	)
	(gr_arc
		(start 135.161528 -9.800082)
		(mid 134.600188 -9.238742)
		(end 134.038848 -9.800082)
		(stroke
			(width 0.2)
			(type default)
		)
		(layer "In6.Cu")
	)
	(gr_line
		(start 135.161528 -3.999992)
		(end 135.161528 -2.600198)
		(stroke
			(width 0.2)
			(type default)
		)
		(layer "In6.Cu")
	)
	(gr_arc
		(start 135.161528 -2.600198)
		(mid 134.600188 -2.038858)
		(end 134.038848 -2.600198)
		(stroke
			(width 0.2)
			(type default)
		)
		(layer "In6.Cu")
	)
	(gr_arc
		(start 135.20928 -61.761878)
		(mid 135.245201 -61.746999)
		(end 135.26008 -61.711078)
		(stroke
			(width 0.2)
			(type default)
		)
		(layer "In6.Cu")
	)
	(gr_line
		(start 135.20928 -60.847478)
		(end 135.00608 -60.847478)
		(stroke
			(width 0.2)
			(type default)
		)
		(layer "In6.Cu")
	)
	(gr_arc
		(start 135.253222 -56.786018)
		(mid 135.268101 -56.821939)
		(end 135.304022 -56.836818)
		(stroke
			(width 0.2)
			(type default)
		)
		(layer "In6.Cu")
	)
	(gr_line
		(start 135.253222 -55.973218)
		(end 135.253222 -56.786018)
		(stroke
			(width 0.2)
			(type default)
		)
		(layer "In6.Cu")
	)
	(gr_line
		(start 135.26008 -61.711078)
		(end 135.26008 -60.898278)
		(stroke
			(width 0.2)
			(type default)
		)
		(layer "In6.Cu")
	)
	(gr_arc
		(start 135.26008 -60.898278)
		(mid 135.245201 -60.862357)
		(end 135.20928 -60.847478)
		(stroke
			(width 0.2)
			(type default)
		)
		(layer "In6.Cu")
	)
	(gr_line
		(start 135.304022 -56.836818)
		(end 135.507222 -56.836818)
		(stroke
			(width 0.2)
			(type default)
		)
		(layer "In6.Cu")
	)
	(gr_arc
		(start 135.304022 -55.922418)
		(mid 135.268101 -55.937297)
		(end 135.253222 -55.973218)
		(stroke
			(width 0.2)
			(type default)
		)
		(layer "In6.Cu")
	)
	(gr_arc
		(start 135.507222 -56.836818)
		(mid 135.543143 -56.821939)
		(end 135.558022 -56.786018)
		(stroke
			(width 0.2)
			(type default)
		)
		(layer "In6.Cu")
	)
	(gr_line
		(start 135.507222 -55.922418)
		(end 135.304022 -55.922418)
		(stroke
			(width 0.2)
			(type default)
		)
		(layer "In6.Cu")
	)
	(gr_arc
		(start 135.51408 -61.711078)
		(mid 135.528959 -61.746999)
		(end 135.56488 -61.761878)
		(stroke
			(width 0.2)
			(type default)
		)
		(layer "In6.Cu")
	)
	(gr_line
		(start 135.51408 -60.898278)
		(end 135.51408 -61.711078)
		(stroke
			(width 0.2)
			(type default)
		)
		(layer "In6.Cu")
	)
	(gr_line
		(start 135.558022 -56.786018)
		(end 135.558022 -55.973218)
		(stroke
			(width 0.2)
			(type default)
		)
		(layer "In6.Cu")
	)
	(gr_arc
		(start 135.558022 -55.973218)
		(mid 135.543143 -55.937297)
		(end 135.507222 -55.922418)
		(stroke
			(width 0.2)
			(type default)
		)
		(layer "In6.Cu")
	)
	(gr_line
		(start 135.56488 -61.761878)
		(end 135.76808 -61.761878)
		(stroke
			(width 0.2)
			(type default)
		)
		(layer "In6.Cu")
	)
	(gr_arc
		(start 135.56488 -60.847478)
		(mid 135.528959 -60.862357)
		(end 135.51408 -60.898278)
		(stroke
			(width 0.2)
			(type default)
		)
		(layer "In6.Cu")
	)
	(gr_arc
		(start 135.7122 -75.692)
		(mid 135.727079 -75.727921)
		(end 135.763 -75.7428)
		(stroke
			(width 0.2)
			(type default)
		)
		(layer "In6.Cu")
	)
	(gr_line
		(start 135.7122 -75.4888)
		(end 135.7122 -75.692)
		(stroke
			(width 0.2)
			(type default)
		)
		(layer "In6.Cu")
	)
	(gr_line
		(start 135.763 -75.7428)
		(end 136.5758 -75.7428)
		(stroke
			(width 0.2)
			(type default)
		)
		(layer "In6.Cu")
	)
	(gr_arc
		(start 135.763 -75.438)
		(mid 135.727079 -75.452879)
		(end 135.7122 -75.4888)
		(stroke
			(width 0.2)
			(type default)
		)
		(layer "In6.Cu")
	)
	(gr_arc
		(start 135.76808 -61.761878)
		(mid 135.804001 -61.746999)
		(end 135.81888 -61.711078)
		(stroke
			(width 0.2)
			(type default)
		)
		(layer "In6.Cu")
	)
	(gr_line
		(start 135.76808 -60.847478)
		(end 135.56488 -60.847478)
		(stroke
			(width 0.2)
			(type default)
		)
		(layer "In6.Cu")
	)
	(gr_line
		(start 135.81888 -61.711078)
		(end 135.81888 -60.898278)
		(stroke
			(width 0.2)
			(type default)
		)
		(layer "In6.Cu")
	)
	(gr_arc
		(start 135.81888 -60.898278)
		(mid 135.804001 -60.862357)
		(end 135.76808 -60.847478)
		(stroke
			(width 0.2)
			(type default)
		)
		(layer "In6.Cu")
	)
	(gr_arc
		(start 135.838692 -12.399772)
		(mid 136.399905 -12.961366)
		(end 136.961372 -12.400026)
		(stroke
			(width 0.2)
			(type default)
		)
		(layer "In6.Cu")
	)
	(gr_line
		(start 135.838692 -10.999978)
		(end 135.838692 -12.399772)
		(stroke
			(width 0.2)
			(type default)
		)
		(layer "In6.Cu")
	)
	(gr_arc
		(start 135.838692 -5.199888)
		(mid 136.399905 -5.761482)
		(end 136.961372 -5.200142)
		(stroke
			(width 0.2)
			(type default)
		)
		(layer "In6.Cu")
	)
	(gr_line
		(start 135.838692 -3.800094)
		(end 135.838692 -5.199888)
		(stroke
			(width 0.2)
			(type default)
		)
		(layer "In6.Cu")
	)
	(gr_arc
		(start 136.5758 -75.7428)
		(mid 136.611721 -75.727921)
		(end 136.6266 -75.692)
		(stroke
			(width 0.2)
			(type default)
		)
		(layer "In6.Cu")
	)
	(gr_line
		(start 136.5758 -75.438)
		(end 135.763 -75.438)
		(stroke
			(width 0.2)
			(type default)
		)
		(layer "In6.Cu")
	)
	(gr_line
		(start 136.6266 -75.692)
		(end 136.6266 -75.4888)
		(stroke
			(width 0.2)
			(type default)
		)
		(layer "In6.Cu")
	)
	(gr_arc
		(start 136.6266 -75.4888)
		(mid 136.611721 -75.452879)
		(end 136.5758 -75.438)
		(stroke
			(width 0.2)
			(type default)
		)
		(layer "In6.Cu")
	)
	(gr_arc
		(start 136.9568 -74.7014)
		(mid 136.971679 -74.737321)
		(end 137.0076 -74.7522)
		(stroke
			(width 0.2)
			(type default)
		)
		(layer "In6.Cu")
	)
	(gr_line
		(start 136.9568 -74.4982)
		(end 136.9568 -74.7014)
		(stroke
			(width 0.2)
			(type default)
		)
		(layer "In6.Cu")
	)
	(gr_arc
		(start 136.9568 -74.1426)
		(mid 136.971679 -74.178521)
		(end 137.0076 -74.1934)
		(stroke
			(width 0.2)
			(type default)
		)
		(layer "In6.Cu")
	)
	(gr_line
		(start 136.9568 -73.9394)
		(end 136.9568 -74.1426)
		(stroke
			(width 0.2)
			(type default)
		)
		(layer "In6.Cu")
	)
	(gr_line
		(start 136.961372 -12.400026)
		(end 136.961372 -10.999978)
		(stroke
			(width 0.2)
			(type default)
		)
		(layer "In6.Cu")
	)
	(gr_arc
		(start 136.961372 -10.999978)
		(mid 136.400032 -10.438638)
		(end 135.838692 -10.999978)
		(stroke
			(width 0.2)
			(type default)
		)
		(layer "In6.Cu")
	)
	(gr_line
		(start 136.961372 -5.200142)
		(end 136.961372 -3.800094)
		(stroke
			(width 0.2)
			(type default)
		)
		(layer "In6.Cu")
	)
	(gr_arc
		(start 136.961372 -3.800094)
		(mid 136.400032 -3.238754)
		(end 135.838692 -3.800094)
		(stroke
			(width 0.2)
			(type default)
		)
		(layer "In6.Cu")
	)
	(gr_line
		(start 137.0076 -74.7522)
		(end 137.8204 -74.7522)
		(stroke
			(width 0.2)
			(type default)
		)
		(layer "In6.Cu")
	)
	(gr_arc
		(start 137.0076 -74.4474)
		(mid 136.971679 -74.462279)
		(end 136.9568 -74.4982)
		(stroke
			(width 0.2)
			(type default)
		)
		(layer "In6.Cu")
	)
	(gr_line
		(start 137.0076 -74.1934)
		(end 137.8204 -74.1934)
		(stroke
			(width 0.2)
			(type default)
		)
		(layer "In6.Cu")
	)
	(gr_arc
		(start 137.0076 -73.8886)
		(mid 136.971679 -73.903479)
		(end 136.9568 -73.9394)
		(stroke
			(width 0.2)
			(type default)
		)
		(layer "In6.Cu")
	)
	(gr_arc
		(start 137.0076 -73.1012)
		(mid 137.022479 -73.137121)
		(end 137.0584 -73.152)
		(stroke
			(width 0.2)
			(type default)
		)
		(layer "In6.Cu")
	)
	(gr_line
		(start 137.0076 -72.898)
		(end 137.0076 -73.1012)
		(stroke
			(width 0.2)
			(type default)
		)
		(layer "In6.Cu")
	)
	(gr_arc
		(start 137.0076 -72.5424)
		(mid 137.022479 -72.578321)
		(end 137.0584 -72.5932)
		(stroke
			(width 0.2)
			(type default)
		)
		(layer "In6.Cu")
	)
	(gr_line
		(start 137.0076 -72.3392)
		(end 137.0076 -72.5424)
		(stroke
			(width 0.2)
			(type default)
		)
		(layer "In6.Cu")
	)
	(gr_arc
		(start 137.0076 -71.5518)
		(mid 137.022479 -71.587721)
		(end 137.0584 -71.6026)
		(stroke
			(width 0.2)
			(type default)
		)
		(layer "In6.Cu")
	)
	(gr_line
		(start 137.0076 -71.3486)
		(end 137.0076 -71.5518)
		(stroke
			(width 0.2)
			(type default)
		)
		(layer "In6.Cu")
	)
	(gr_arc
		(start 137.0076 -70.993)
		(mid 137.022479 -71.028921)
		(end 137.0584 -71.0438)
		(stroke
			(width 0.2)
			(type default)
		)
		(layer "In6.Cu")
	)
	(gr_line
		(start 137.0076 -70.7898)
		(end 137.0076 -70.993)
		(stroke
			(width 0.2)
			(type default)
		)
		(layer "In6.Cu")
	)
	(gr_arc
		(start 137.0076 -70.0024)
		(mid 137.022479 -70.038321)
		(end 137.0584 -70.0532)
		(stroke
			(width 0.2)
			(type default)
		)
		(layer "In6.Cu")
	)
	(gr_line
		(start 137.0076 -69.7992)
		(end 137.0076 -70.0024)
		(stroke
			(width 0.2)
			(type default)
		)
		(layer "In6.Cu")
	)
	(gr_arc
		(start 137.0076 -69.4436)
		(mid 137.022479 -69.479521)
		(end 137.0584 -69.4944)
		(stroke
			(width 0.2)
			(type default)
		)
		(layer "In6.Cu")
	)
	(gr_line
		(start 137.0076 -69.2404)
		(end 137.0076 -69.4436)
		(stroke
			(width 0.2)
			(type default)
		)
		(layer "In6.Cu")
	)
	(gr_arc
		(start 137.0076 -68.453)
		(mid 137.022479 -68.488921)
		(end 137.0584 -68.5038)
		(stroke
			(width 0.2)
			(type default)
		)
		(layer "In6.Cu")
	)
	(gr_line
		(start 137.0076 -68.2498)
		(end 137.0076 -68.453)
		(stroke
			(width 0.2)
			(type default)
		)
		(layer "In6.Cu")
	)
	(gr_arc
		(start 137.0076 -67.8942)
		(mid 137.022479 -67.930121)
		(end 137.0584 -67.945)
		(stroke
			(width 0.2)
			(type default)
		)
		(layer "In6.Cu")
	)
	(gr_line
		(start 137.0076 -67.691)
		(end 137.0076 -67.8942)
		(stroke
			(width 0.2)
			(type default)
		)
		(layer "In6.Cu")
	)
	(gr_arc
		(start 137.0076 -66.929)
		(mid 137.022479 -66.964921)
		(end 137.0584 -66.9798)
		(stroke
			(width 0.2)
			(type default)
		)
		(layer "In6.Cu")
	)
	(gr_line
		(start 137.0076 -66.7258)
		(end 137.0076 -66.929)
		(stroke
			(width 0.2)
			(type default)
		)
		(layer "In6.Cu")
	)
	(gr_arc
		(start 137.0076 -66.3702)
		(mid 137.022479 -66.406121)
		(end 137.0584 -66.421)
		(stroke
			(width 0.2)
			(type default)
		)
		(layer "In6.Cu")
	)
	(gr_line
		(start 137.0076 -66.167)
		(end 137.0076 -66.3702)
		(stroke
			(width 0.2)
			(type default)
		)
		(layer "In6.Cu")
	)
	(gr_line
		(start 137.0584 -73.152)
		(end 137.8712 -73.152)
		(stroke
			(width 0.2)
			(type default)
		)
		(layer "In6.Cu")
	)
	(gr_arc
		(start 137.0584 -72.8472)
		(mid 137.022479 -72.862079)
		(end 137.0076 -72.898)
		(stroke
			(width 0.2)
			(type default)
		)
		(layer "In6.Cu")
	)
	(gr_line
		(start 137.0584 -72.5932)
		(end 137.8712 -72.5932)
		(stroke
			(width 0.2)
			(type default)
		)
		(layer "In6.Cu")
	)
	(gr_arc
		(start 137.0584 -72.2884)
		(mid 137.022479 -72.303279)
		(end 137.0076 -72.3392)
		(stroke
			(width 0.2)
			(type default)
		)
		(layer "In6.Cu")
	)
	(gr_line
		(start 137.0584 -71.6026)
		(end 137.8712 -71.6026)
		(stroke
			(width 0.2)
			(type default)
		)
		(layer "In6.Cu")
	)
	(gr_arc
		(start 137.0584 -71.2978)
		(mid 137.022479 -71.312679)
		(end 137.0076 -71.3486)
		(stroke
			(width 0.2)
			(type default)
		)
		(layer "In6.Cu")
	)
	(gr_line
		(start 137.0584 -71.0438)
		(end 137.8712 -71.0438)
		(stroke
			(width 0.2)
			(type default)
		)
		(layer "In6.Cu")
	)
	(gr_arc
		(start 137.0584 -70.739)
		(mid 137.022479 -70.753879)
		(end 137.0076 -70.7898)
		(stroke
			(width 0.2)
			(type default)
		)
		(layer "In6.Cu")
	)
	(gr_line
		(start 137.0584 -70.0532)
		(end 137.8712 -70.0532)
		(stroke
			(width 0.2)
			(type default)
		)
		(layer "In6.Cu")
	)
	(gr_arc
		(start 137.0584 -69.7484)
		(mid 137.022479 -69.763279)
		(end 137.0076 -69.7992)
		(stroke
			(width 0.2)
			(type default)
		)
		(layer "In6.Cu")
	)
	(gr_line
		(start 137.0584 -69.4944)
		(end 137.8712 -69.4944)
		(stroke
			(width 0.2)
			(type default)
		)
		(layer "In6.Cu")
	)
	(gr_arc
		(start 137.0584 -69.1896)
		(mid 137.022479 -69.204479)
		(end 137.0076 -69.2404)
		(stroke
			(width 0.2)
			(type default)
		)
		(layer "In6.Cu")
	)
	(gr_line
		(start 137.0584 -68.5038)
		(end 137.8712 -68.5038)
		(stroke
			(width 0.2)
			(type default)
		)
		(layer "In6.Cu")
	)
	(gr_arc
		(start 137.0584 -68.199)
		(mid 137.022479 -68.213879)
		(end 137.0076 -68.2498)
		(stroke
			(width 0.2)
			(type default)
		)
		(layer "In6.Cu")
	)
	(gr_line
		(start 137.0584 -67.945)
		(end 137.8712 -67.945)
		(stroke
			(width 0.2)
			(type default)
		)
		(layer "In6.Cu")
	)
	(gr_arc
		(start 137.0584 -67.6402)
		(mid 137.022479 -67.655079)
		(end 137.0076 -67.691)
		(stroke
			(width 0.2)
			(type default)
		)
		(layer "In6.Cu")
	)
	(gr_line
		(start 137.0584 -66.9798)
		(end 137.8712 -66.9798)
		(stroke
			(width 0.2)
			(type default)
		)
		(layer "In6.Cu")
	)
	(gr_arc
		(start 137.0584 -66.675)
		(mid 137.022479 -66.689879)
		(end 137.0076 -66.7258)
		(stroke
			(width 0.2)
			(type default)
		)
		(layer "In6.Cu")
	)
	(gr_line
		(start 137.0584 -66.421)
		(end 137.8712 -66.421)
		(stroke
			(width 0.2)
			(type default)
		)
		(layer "In6.Cu")
	)
	(gr_arc
		(start 137.0584 -66.1162)
		(mid 137.022479 -66.131079)
		(end 137.0076 -66.167)
		(stroke
			(width 0.2)
			(type default)
		)
		(layer "In6.Cu")
	)
	(gr_arc
		(start 137.63879 -11.199876)
		(mid 138.200003 -11.76147)
		(end 138.76147 -11.20013)
		(stroke
			(width 0.2)
			(type default)
		)
		(layer "In6.Cu")
	)
	(gr_line
		(start 137.63879 -9.800082)
		(end 137.63879 -11.199876)
		(stroke
			(width 0.2)
			(type default)
		)
		(layer "In6.Cu")
	)
	(gr_arc
		(start 137.63879 -3.999738)
		(mid 138.200003 -4.561332)
		(end 138.76147 -3.999992)
		(stroke
			(width 0.2)
			(type default)
		)
		(layer "In6.Cu")
	)
	(gr_line
		(start 137.63879 -2.600198)
		(end 137.63879 -3.999738)
		(stroke
			(width 0.2)
			(type default)
		)
		(layer "In6.Cu")
	)
	(gr_arc
		(start 137.8204 -74.7522)
		(mid 137.856321 -74.737321)
		(end 137.8712 -74.7014)
		(stroke
			(width 0.2)
			(type default)
		)
		(layer "In6.Cu")
	)
	(gr_line
		(start 137.8204 -74.4474)
		(end 137.0076 -74.4474)
		(stroke
			(width 0.2)
			(type default)
		)
		(layer "In6.Cu")
	)
	(gr_arc
		(start 137.8204 -74.1934)
		(mid 137.856321 -74.178521)
		(end 137.8712 -74.1426)
		(stroke
			(width 0.2)
			(type default)
		)
		(layer "In6.Cu")
	)
	(gr_line
		(start 137.8204 -73.8886)
		(end 137.0076 -73.8886)
		(stroke
			(width 0.2)
			(type default)
		)
		(layer "In6.Cu")
	)
	(gr_line
		(start 137.8712 -74.7014)
		(end 137.8712 -74.4982)
		(stroke
			(width 0.2)
			(type default)
		)
		(layer "In6.Cu")
	)
	(gr_arc
		(start 137.8712 -74.4982)
		(mid 137.856321 -74.462279)
		(end 137.8204 -74.4474)
		(stroke
			(width 0.2)
			(type default)
		)
		(layer "In6.Cu")
	)
	(gr_line
		(start 137.8712 -74.1426)
		(end 137.8712 -73.9394)
		(stroke
			(width 0.2)
			(type default)
		)
		(layer "In6.Cu")
	)
	(gr_arc
		(start 137.8712 -73.9394)
		(mid 137.856321 -73.903479)
		(end 137.8204 -73.8886)
		(stroke
			(width 0.2)
			(type default)
		)
		(layer "In6.Cu")
	)
	(gr_arc
		(start 137.8712 -73.152)
		(mid 137.907121 -73.137121)
		(end 137.922 -73.1012)
		(stroke
			(width 0.2)
			(type default)
		)
		(layer "In6.Cu")
	)
	(gr_line
		(start 137.8712 -72.8472)
		(end 137.0584 -72.8472)
		(stroke
			(width 0.2)
			(type default)
		)
		(layer "In6.Cu")
	)
	(gr_arc
		(start 137.8712 -72.5932)
		(mid 137.907121 -72.578321)
		(end 137.922 -72.5424)
		(stroke
			(width 0.2)
			(type default)
		)
		(layer "In6.Cu")
	)
	(gr_line
		(start 137.8712 -72.2884)
		(end 137.0584 -72.2884)
		(stroke
			(width 0.2)
			(type default)
		)
		(layer "In6.Cu")
	)
	(gr_arc
		(start 137.8712 -71.6026)
		(mid 137.907121 -71.587721)
		(end 137.922 -71.5518)
		(stroke
			(width 0.2)
			(type default)
		)
		(layer "In6.Cu")
	)
	(gr_line
		(start 137.8712 -71.2978)
		(end 137.0584 -71.2978)
		(stroke
			(width 0.2)
			(type default)
		)
		(layer "In6.Cu")
	)
	(gr_arc
		(start 137.8712 -71.0438)
		(mid 137.907121 -71.028921)
		(end 137.922 -70.993)
		(stroke
			(width 0.2)
			(type default)
		)
		(layer "In6.Cu")
	)
	(gr_line
		(start 137.8712 -70.739)
		(end 137.0584 -70.739)
		(stroke
			(width 0.2)
			(type default)
		)
		(layer "In6.Cu")
	)
	(gr_arc
		(start 137.8712 -70.0532)
		(mid 137.907121 -70.038321)
		(end 137.922 -70.0024)
		(stroke
			(width 0.2)
			(type default)
		)
		(layer "In6.Cu")
	)
	(gr_line
		(start 137.8712 -69.7484)
		(end 137.0584 -69.7484)
		(stroke
			(width 0.2)
			(type default)
		)
		(layer "In6.Cu")
	)
	(gr_arc
		(start 137.8712 -69.4944)
		(mid 137.907121 -69.479521)
		(end 137.922 -69.4436)
		(stroke
			(width 0.2)
			(type default)
		)
		(layer "In6.Cu")
	)
	(gr_line
		(start 137.8712 -69.1896)
		(end 137.0584 -69.1896)
		(stroke
			(width 0.2)
			(type default)
		)
		(layer "In6.Cu")
	)
	(gr_arc
		(start 137.8712 -68.5038)
		(mid 137.907121 -68.488921)
		(end 137.922 -68.453)
		(stroke
			(width 0.2)
			(type default)
		)
		(layer "In6.Cu")
	)
	(gr_line
		(start 137.8712 -68.199)
		(end 137.0584 -68.199)
		(stroke
			(width 0.2)
			(type default)
		)
		(layer "In6.Cu")
	)
	(gr_arc
		(start 137.8712 -67.945)
		(mid 137.907121 -67.930121)
		(end 137.922 -67.8942)
		(stroke
			(width 0.2)
			(type default)
		)
		(layer "In6.Cu")
	)
	(gr_line
		(start 137.8712 -67.6402)
		(end 137.0584 -67.6402)
		(stroke
			(width 0.2)
			(type default)
		)
		(layer "In6.Cu")
	)
	(gr_arc
		(start 137.8712 -66.9798)
		(mid 137.907121 -66.964921)
		(end 137.922 -66.929)
		(stroke
			(width 0.2)
			(type default)
		)
		(layer "In6.Cu")
	)
	(gr_line
		(start 137.8712 -66.675)
		(end 137.0584 -66.675)
		(stroke
			(width 0.2)
			(type default)
		)
		(layer "In6.Cu")
	)
	(gr_arc
		(start 137.8712 -66.421)
		(mid 137.907121 -66.406121)
		(end 137.922 -66.3702)
		(stroke
			(width 0.2)
			(type default)
		)
		(layer "In6.Cu")
	)
	(gr_line
		(start 137.8712 -66.1162)
		(end 137.0584 -66.1162)
		(stroke
			(width 0.2)
			(type default)
		)
		(layer "In6.Cu")
	)
	(gr_line
		(start 137.922 -73.1012)
		(end 137.922 -72.898)
		(stroke
			(width 0.2)
			(type default)
		)
		(layer "In6.Cu")
	)
	(gr_arc
		(start 137.922 -72.898)
		(mid 137.907121 -72.862079)
		(end 137.8712 -72.8472)
		(stroke
			(width 0.2)
			(type default)
		)
		(layer "In6.Cu")
	)
	(gr_line
		(start 137.922 -72.5424)
		(end 137.922 -72.3392)
		(stroke
			(width 0.2)
			(type default)
		)
		(layer "In6.Cu")
	)
	(gr_arc
		(start 137.922 -72.3392)
		(mid 137.907121 -72.303279)
		(end 137.8712 -72.2884)
		(stroke
			(width 0.2)
			(type default)
		)
		(layer "In6.Cu")
	)
	(gr_line
		(start 137.922 -71.5518)
		(end 137.922 -71.3486)
		(stroke
			(width 0.2)
			(type default)
		)
		(layer "In6.Cu")
	)
	(gr_arc
		(start 137.922 -71.3486)
		(mid 137.907121 -71.312679)
		(end 137.8712 -71.2978)
		(stroke
			(width 0.2)
			(type default)
		)
		(layer "In6.Cu")
	)
	(gr_line
		(start 137.922 -70.993)
		(end 137.922 -70.7898)
		(stroke
			(width 0.2)
			(type default)
		)
		(layer "In6.Cu")
	)
	(gr_arc
		(start 137.922 -70.7898)
		(mid 137.907121 -70.753879)
		(end 137.8712 -70.739)
		(stroke
			(width 0.2)
			(type default)
		)
		(layer "In6.Cu")
	)
	(gr_line
		(start 137.922 -70.0024)
		(end 137.922 -69.7992)
		(stroke
			(width 0.2)
			(type default)
		)
		(layer "In6.Cu")
	)
	(gr_arc
		(start 137.922 -69.7992)
		(mid 137.907121 -69.763279)
		(end 137.8712 -69.7484)
		(stroke
			(width 0.2)
			(type default)
		)
		(layer "In6.Cu")
	)
	(gr_line
		(start 137.922 -69.4436)
		(end 137.922 -69.2404)
		(stroke
			(width 0.2)
			(type default)
		)
		(layer "In6.Cu")
	)
	(gr_arc
		(start 137.922 -69.2404)
		(mid 137.907121 -69.204479)
		(end 137.8712 -69.1896)
		(stroke
			(width 0.2)
			(type default)
		)
		(layer "In6.Cu")
	)
	(gr_line
		(start 137.922 -68.453)
		(end 137.922 -68.2498)
		(stroke
			(width 0.2)
			(type default)
		)
		(layer "In6.Cu")
	)
	(gr_arc
		(start 137.922 -68.2498)
		(mid 137.907121 -68.213879)
		(end 137.8712 -68.199)
		(stroke
			(width 0.2)
			(type default)
		)
		(layer "In6.Cu")
	)
	(gr_line
		(start 137.922 -67.8942)
		(end 137.922 -67.691)
		(stroke
			(width 0.2)
			(type default)
		)
		(layer "In6.Cu")
	)
	(gr_arc
		(start 137.922 -67.691)
		(mid 137.907121 -67.655079)
		(end 137.8712 -67.6402)
		(stroke
			(width 0.2)
			(type default)
		)
		(layer "In6.Cu")
	)
	(gr_line
		(start 137.922 -66.929)
		(end 137.922 -66.7258)
		(stroke
			(width 0.2)
			(type default)
		)
		(layer "In6.Cu")
	)
	(gr_arc
		(start 137.922 -66.7258)
		(mid 137.907121 -66.689879)
		(end 137.8712 -66.675)
		(stroke
			(width 0.2)
			(type default)
		)
		(layer "In6.Cu")
	)
	(gr_line
		(start 137.922 -66.3702)
		(end 137.922 -66.167)
		(stroke
			(width 0.2)
			(type default)
		)
		(layer "In6.Cu")
	)
	(gr_arc
		(start 137.922 -66.167)
		(mid 137.907121 -66.131079)
		(end 137.8712 -66.1162)
		(stroke
			(width 0.2)
			(type default)
		)
		(layer "In6.Cu")
	)
	(gr_line
		(start 138.479022 -76.90866)
		(end 139.622022 -76.90866)
		(stroke
			(width 0.2)
			(type default)
		)
		(layer "In6.Cu")
	)
	(gr_line
		(start 138.479022 -76.907898)
		(end 138.479022 -76.90866)
		(stroke
			(width 0.2)
			(type default)
		)
		(layer "In6.Cu")
	)
	(gr_arc
		(start 138.479022 -76.142342)
		(mid 138.096244 -76.52512)
		(end 138.479022 -76.907898)
		(stroke
			(width 0.2)
			(type default)
		)
		(layer "In6.Cu")
	)
	(gr_line
		(start 138.479022 -76.141834)
		(end 138.479022 -76.142342)
		(stroke
			(width 0.2)
			(type default)
		)
		(layer "In6.Cu")
	)
	(gr_line
		(start 138.479276 -76.14158)
		(end 138.479022 -76.141834)
		(stroke
			(width 0.2)
			(type default)
		)
		(layer "In6.Cu")
	)
	(gr_line
		(start 138.486134 -78.811374)
		(end 139.62888 -78.811374)
		(stroke
			(width 0.2)
			(type default)
		)
		(layer "In6.Cu")
	)
	(gr_line
		(start 138.486134 -78.810612)
		(end 138.486134 -78.811374)
		(stroke
			(width 0.2)
			(type default)
		)
		(layer "In6.Cu")
	)
	(gr_arc
		(start 138.486134 -78.045056)
		(mid 138.103356 -78.427834)
		(end 138.486134 -78.810612)
		(stroke
			(width 0.2)
			(type default)
		)
		(layer "In6.Cu")
	)
	(gr_line
		(start 138.486134 -78.044294)
		(end 138.486134 -78.045056)
		(stroke
			(width 0.2)
			(type default)
		)
		(layer "In6.Cu")
	)
	(gr_line
		(start 138.500612 -80.580992)
		(end 139.643612 -80.580992)
		(stroke
			(width 0.2)
			(type default)
		)
		(layer "In6.Cu")
	)
	(gr_line
		(start 138.500612 -80.58023)
		(end 138.500612 -80.580992)
		(stroke
			(width 0.2)
			(type default)
		)
		(layer "In6.Cu")
	)
	(gr_arc
		(start 138.500612 -79.814674)
		(mid 138.117834 -80.197452)
		(end 138.500612 -80.58023)
		(stroke
			(width 0.2)
			(type default)
		)
		(layer "In6.Cu")
	)
	(gr_line
		(start 138.500612 -79.814166)
		(end 138.500612 -79.814674)
		(stroke
			(width 0.2)
			(type default)
		)
		(layer "In6.Cu")
	)
	(gr_line
		(start 138.500866 -79.813912)
		(end 138.500612 -79.814166)
		(stroke
			(width 0.2)
			(type default)
		)
		(layer "In6.Cu")
	)
	(gr_line
		(start 138.739118 -65.426844)
		(end 139.881864 -65.426844)
		(stroke
			(width 0.2)
			(type default)
		)
		(layer "In6.Cu")
	)
	(gr_arc
		(start 138.739118 -64.517524)
		(mid 138.284458 -64.972184)
		(end 138.739118 -65.426844)
		(stroke
			(width 0.2)
			(type default)
		)
		(layer "In6.Cu")
	)
	(gr_line
		(start 138.76147 -11.20013)
		(end 138.76147 -9.800082)
		(stroke
			(width 0.2)
			(type default)
		)
		(layer "In6.Cu")
	)
	(gr_arc
		(start 138.76147 -9.800082)
		(mid 138.20013 -9.238742)
		(end 137.63879 -9.800082)
		(stroke
			(width 0.2)
			(type default)
		)
		(layer "In6.Cu")
	)
	(gr_line
		(start 138.76147 -3.999992)
		(end 138.76147 -2.600198)
		(stroke
			(width 0.2)
			(type default)
		)
		(layer "In6.Cu")
	)
	(gr_arc
		(start 138.76147 -2.600198)
		(mid 138.20013 -2.038858)
		(end 137.63879 -2.600198)
		(stroke
			(width 0.2)
			(type default)
		)
		(layer "In6.Cu")
	)
	(gr_line
		(start 138.80465 -63.499746)
		(end 139.947396 -63.499746)
		(stroke
			(width 0.2)
			(type default)
		)
		(layer "In6.Cu")
	)
	(gr_arc
		(start 138.80465 -62.590426)
		(mid 138.34999 -63.045086)
		(end 138.80465 -63.499746)
		(stroke
			(width 0.2)
			(type default)
		)
		(layer "In6.Cu")
	)
	(gr_line
		(start 138.843258 -82.691986)
		(end 139.986258 -82.691986)
		(stroke
			(width 0.2)
			(type default)
		)
		(layer "In6.Cu")
	)
	(gr_line
		(start 138.843258 -82.691224)
		(end 138.843258 -82.691986)
		(stroke
			(width 0.2)
			(type default)
		)
		(layer "In6.Cu")
	)
	(gr_arc
		(start 138.843258 -81.925668)
		(mid 138.46048 -82.308446)
		(end 138.843258 -82.691224)
		(stroke
			(width 0.2)
			(type default)
		)
		(layer "In6.Cu")
	)
	(gr_line
		(start 138.843258 -81.92516)
		(end 138.843258 -81.925668)
		(stroke
			(width 0.2)
			(type default)
		)
		(layer "In6.Cu")
	)
	(gr_line
		(start 138.843512 -81.924906)
		(end 138.843258 -81.92516)
		(stroke
			(width 0.2)
			(type default)
		)
		(layer "In6.Cu")
	)
	(gr_line
		(start 139.03071 -61.576712)
		(end 140.173456 -61.576712)
		(stroke
			(width 0.2)
			(type default)
		)
		(layer "In6.Cu")
	)
	(gr_arc
		(start 139.03071 -60.667392)
		(mid 138.57605 -61.122052)
		(end 139.03071 -61.576712)
		(stroke
			(width 0.2)
			(type default)
		)
		(layer "In6.Cu")
	)
	(gr_arc
		(start 139.438634 -12.399772)
		(mid 139.999847 -12.961366)
		(end 140.561314 -12.400026)
		(stroke
			(width 0.2)
			(type default)
		)
		(layer "In6.Cu")
	)
	(gr_line
		(start 139.438634 -10.999978)
		(end 139.438634 -12.399772)
		(stroke
			(width 0.2)
			(type default)
		)
		(layer "In6.Cu")
	)
	(gr_arc
		(start 139.438634 -5.199888)
		(mid 139.999847 -5.761482)
		(end 140.561314 -5.200142)
		(stroke
			(width 0.2)
			(type default)
		)
		(layer "In6.Cu")
	)
	(gr_line
		(start 139.438634 -3.800094)
		(end 139.438634 -5.199888)
		(stroke
			(width 0.2)
			(type default)
		)
		(layer "In6.Cu")
	)
	(gr_line
		(start 139.446 -59.35726)
		(end 140.588746 -59.35726)
		(stroke
			(width 0.2)
			(type default)
		)
		(layer "In6.Cu")
	)
	(gr_arc
		(start 139.446 -58.44794)
		(mid 138.99134 -58.9026)
		(end 139.446 -59.35726)
		(stroke
			(width 0.2)
			(type default)
		)
		(layer "In6.Cu")
	)
	(gr_line
		(start 139.622022 -76.90866)
		(end 139.622022 -76.907898)
		(stroke
			(width 0.2)
			(type default)
		)
		(layer "In6.Cu")
	)
	(gr_arc
		(start 139.622022 -76.907898)
		(mid 140.0048 -76.52512)
		(end 139.622022 -76.142342)
		(stroke
			(width 0.2)
			(type default)
		)
		(layer "In6.Cu")
	)
	(gr_line
		(start 139.622022 -76.142342)
		(end 139.622022 -76.14158)
		(stroke
			(width 0.2)
			(type default)
		)
		(layer "In6.Cu")
	)
	(gr_line
		(start 139.622022 -76.14158)
		(end 138.479276 -76.14158)
		(stroke
			(width 0.2)
			(type default)
		)
		(layer "In6.Cu")
	)
	(gr_line
		(start 139.62888 -78.811374)
		(end 139.629134 -78.81112)
		(stroke
			(width 0.2)
			(type default)
		)
		(layer "In6.Cu")
	)
	(gr_line
		(start 139.629134 -78.81112)
		(end 139.629134 -78.810612)
		(stroke
			(width 0.2)
			(type default)
		)
		(layer "In6.Cu")
	)
	(gr_arc
		(start 139.629134 -78.810612)
		(mid 140.011912 -78.427834)
		(end 139.629134 -78.045056)
		(stroke
			(width 0.2)
			(type default)
		)
		(layer "In6.Cu")
	)
	(gr_line
		(start 139.629134 -78.045056)
		(end 139.629134 -78.044294)
		(stroke
			(width 0.2)
			(type default)
		)
		(layer "In6.Cu")
	)
	(gr_line
		(start 139.629134 -78.044294)
		(end 138.486134 -78.044294)
		(stroke
			(width 0.2)
			(type default)
		)
		(layer "In6.Cu")
	)
	(gr_line
		(start 139.643612 -80.580992)
		(end 139.643612 -80.58023)
		(stroke
			(width 0.2)
			(type default)
		)
		(layer "In6.Cu")
	)
	(gr_arc
		(start 139.643612 -80.58023)
		(mid 140.02639 -80.197452)
		(end 139.643612 -79.814674)
		(stroke
			(width 0.2)
			(type default)
		)
		(layer "In6.Cu")
	)
	(gr_line
		(start 139.643612 -79.814674)
		(end 139.643612 -79.813912)
		(stroke
			(width 0.2)
			(type default)
		)
		(layer "In6.Cu")
	)
	(gr_line
		(start 139.643612 -79.813912)
		(end 138.500866 -79.813912)
		(stroke
			(width 0.2)
			(type default)
		)
		(layer "In6.Cu")
	)
	(gr_arc
		(start 139.881864 -65.426844)
		(mid 140.336778 -64.972311)
		(end 139.882118 -64.517524)
		(stroke
			(width 0.2)
			(type default)
		)
		(layer "In6.Cu")
	)
	(gr_line
		(start 139.882118 -64.517524)
		(end 138.739118 -64.517524)
		(stroke
			(width 0.2)
			(type default)
		)
		(layer "In6.Cu")
	)
	(gr_arc
		(start 139.947396 -63.499746)
		(mid 140.40231 -63.045213)
		(end 139.94765 -62.590426)
		(stroke
			(width 0.2)
			(type default)
		)
		(layer "In6.Cu")
	)
	(gr_line
		(start 139.94765 -62.590426)
		(end 138.80465 -62.590426)
		(stroke
			(width 0.2)
			(type default)
		)
		(layer "In6.Cu")
	)
	(gr_line
		(start 139.986258 -82.691986)
		(end 139.986258 -82.691224)
		(stroke
			(width 0.2)
			(type default)
		)
		(layer "In6.Cu")
	)
	(gr_arc
		(start 139.986258 -82.691224)
		(mid 140.369036 -82.308446)
		(end 139.986258 -81.925668)
		(stroke
			(width 0.2)
			(type default)
		)
		(layer "In6.Cu")
	)
	(gr_line
		(start 139.986258 -81.925668)
		(end 139.986258 -81.924906)
		(stroke
			(width 0.2)
			(type default)
		)
		(layer "In6.Cu")
	)
	(gr_line
		(start 139.986258 -81.924906)
		(end 138.843512 -81.924906)
		(stroke
			(width 0.2)
			(type default)
		)
		(layer "In6.Cu")
	)
	(gr_arc
		(start 140.173456 -61.576712)
		(mid 140.62837 -61.122179)
		(end 140.17371 -60.667392)
		(stroke
			(width 0.2)
			(type default)
		)
		(layer "In6.Cu")
	)
	(gr_line
		(start 140.17371 -60.667392)
		(end 139.03071 -60.667392)
		(stroke
			(width 0.2)
			(type default)
		)
		(layer "In6.Cu")
	)
	(gr_line
		(start 140.561314 -12.400026)
		(end 140.561314 -10.999978)
		(stroke
			(width 0.2)
			(type default)
		)
		(layer "In6.Cu")
	)
	(gr_arc
		(start 140.561314 -10.999978)
		(mid 139.999974 -10.438638)
		(end 139.438634 -10.999978)
		(stroke
			(width 0.2)
			(type default)
		)
		(layer "In6.Cu")
	)
	(gr_line
		(start 140.561314 -5.200142)
		(end 140.561314 -3.800094)
		(stroke
			(width 0.2)
			(type default)
		)
		(layer "In6.Cu")
	)
	(gr_arc
		(start 140.561314 -3.800094)
		(mid 139.999974 -3.238754)
		(end 139.438634 -3.800094)
		(stroke
			(width 0.2)
			(type default)
		)
		(layer "In6.Cu")
	)
	(gr_arc
		(start 140.588746 -59.35726)
		(mid 141.04366 -58.902727)
		(end 140.589 -58.44794)
		(stroke
			(width 0.2)
			(type default)
		)
		(layer "In6.Cu")
	)
	(gr_line
		(start 140.589 -58.44794)
		(end 139.446 -58.44794)
		(stroke
			(width 0.2)
			(type default)
		)
		(layer "In6.Cu")
	)
	(gr_arc
		(start 141.238732 -11.199876)
		(mid 141.799945 -11.76147)
		(end 142.361412 -11.20013)
		(stroke
			(width 0.2)
			(type default)
		)
		(layer "In6.Cu")
	)
	(gr_line
		(start 141.238732 -9.800082)
		(end 141.238732 -11.199876)
		(stroke
			(width 0.2)
			(type default)
		)
		(layer "In6.Cu")
	)
	(gr_arc
		(start 141.238732 -3.999738)
		(mid 141.799945 -4.561332)
		(end 142.361412 -3.999992)
		(stroke
			(width 0.2)
			(type default)
		)
		(layer "In6.Cu")
	)
	(gr_line
		(start 141.238732 -2.600198)
		(end 141.238732 -3.999738)
		(stroke
			(width 0.2)
			(type default)
		)
		(layer "In6.Cu")
	)
	(gr_line
		(start 142.361412 -11.20013)
		(end 142.361412 -9.800082)
		(stroke
			(width 0.2)
			(type default)
		)
		(layer "In6.Cu")
	)
	(gr_arc
		(start 142.361412 -9.800082)
		(mid 141.800072 -9.238742)
		(end 141.238732 -9.800082)
		(stroke
			(width 0.2)
			(type default)
		)
		(layer "In6.Cu")
	)
	(gr_line
		(start 142.361412 -3.999992)
		(end 142.361412 -2.600198)
		(stroke
			(width 0.2)
			(type default)
		)
		(layer "In6.Cu")
	)
	(gr_arc
		(start 142.361412 -2.600198)
		(mid 141.800072 -2.038858)
		(end 141.238732 -2.600198)
		(stroke
			(width 0.2)
			(type default)
		)
		(layer "In6.Cu")
	)
	(gr_arc
		(start 143.03883 -12.399772)
		(mid 143.600043 -12.961366)
		(end 144.16151 -12.400026)
		(stroke
			(width 0.2)
			(type default)
		)
		(layer "In6.Cu")
	)
	(gr_line
		(start 143.03883 -10.999978)
		(end 143.03883 -12.399772)
		(stroke
			(width 0.2)
			(type default)
		)
		(layer "In6.Cu")
	)
	(gr_arc
		(start 143.03883 -5.199888)
		(mid 143.600043 -5.761482)
		(end 144.16151 -5.200142)
		(stroke
			(width 0.2)
			(type default)
		)
		(layer "In6.Cu")
	)
	(gr_line
		(start 143.03883 -3.800094)
		(end 143.03883 -5.199888)
		(stroke
			(width 0.2)
			(type default)
		)
		(layer "In6.Cu")
	)
	(gr_line
		(start 144.16151 -12.400026)
		(end 144.16151 -10.999978)
		(stroke
			(width 0.2)
			(type default)
		)
		(layer "In6.Cu")
	)
	(gr_arc
		(start 144.16151 -10.999978)
		(mid 143.60017 -10.438638)
		(end 143.03883 -10.999978)
		(stroke
			(width 0.2)
			(type default)
		)
		(layer "In6.Cu")
	)
	(gr_line
		(start 144.16151 -5.200142)
		(end 144.16151 -3.800094)
		(stroke
			(width 0.2)
			(type default)
		)
		(layer "In6.Cu")
	)
	(gr_arc
		(start 144.16151 -3.800094)
		(mid 143.60017 -3.238754)
		(end 143.03883 -3.800094)
		(stroke
			(width 0.2)
			(type default)
		)
		(layer "In6.Cu")
	)
	(gr_arc
		(start 144.838674 -11.199876)
		(mid 145.399887 -11.76147)
		(end 145.961354 -11.20013)
		(stroke
			(width 0.2)
			(type default)
		)
		(layer "In6.Cu")
	)
	(gr_line
		(start 144.838674 -9.800082)
		(end 144.838674 -11.199876)
		(stroke
			(width 0.2)
			(type default)
		)
		(layer "In6.Cu")
	)
	(gr_arc
		(start 144.838674 -3.999738)
		(mid 145.399887 -4.561332)
		(end 145.961354 -3.999992)
		(stroke
			(width 0.2)
			(type default)
		)
		(layer "In6.Cu")
	)
	(gr_line
		(start 144.838674 -2.600198)
		(end 144.838674 -3.999738)
		(stroke
			(width 0.2)
			(type default)
		)
		(layer "In6.Cu")
	)
	(gr_arc
		(start 145.839434 -33.377886)
		(mid 146.191732 -33.920176)
		(end 146.734022 -33.567878)
		(stroke
			(width 0.2)
			(type default)
		)
		(layer "In6.Cu")
	)
	(gr_line
		(start 145.961354 -11.20013)
		(end 145.961354 -9.800082)
		(stroke
			(width 0.2)
			(type default)
		)
		(layer "In6.Cu")
	)
	(gr_arc
		(start 145.961354 -9.800082)
		(mid 145.400014 -9.238742)
		(end 144.838674 -9.800082)
		(stroke
			(width 0.2)
			(type default)
		)
		(layer "In6.Cu")
	)
	(gr_line
		(start 145.961354 -3.999992)
		(end 145.961354 -2.600198)
		(stroke
			(width 0.2)
			(type default)
		)
		(layer "In6.Cu")
	)
	(gr_arc
		(start 145.961354 -2.600198)
		(mid 145.400014 -2.038858)
		(end 144.838674 -2.600198)
		(stroke
			(width 0.2)
			(type default)
		)
		(layer "In6.Cu")
	)
	(gr_line
		(start 146.077178 -32.259778)
		(end 145.839434 -33.377886)
		(stroke
			(width 0.2)
			(type default)
		)
		(layer "In6.Cu")
	)
	(gr_arc
		(start 146.638772 -12.399772)
		(mid 147.199985 -12.961366)
		(end 147.761452 -12.400026)
		(stroke
			(width 0.2)
			(type default)
		)
		(layer "In6.Cu")
	)
	(gr_line
		(start 146.638772 -10.999978)
		(end 146.638772 -12.399772)
		(stroke
			(width 0.2)
			(type default)
		)
		(layer "In6.Cu")
	)
	(gr_arc
		(start 146.638772 -5.199888)
		(mid 147.199985 -5.761482)
		(end 147.761452 -5.200142)
		(stroke
			(width 0.2)
			(type default)
		)
		(layer "In6.Cu")
	)
	(gr_line
		(start 146.638772 -3.800094)
		(end 146.638772 -5.199888)
		(stroke
			(width 0.2)
			(type default)
		)
		(layer "In6.Cu")
	)
	(gr_line
		(start 146.734022 -33.567878)
		(end 146.969226 -32.460184)
		(stroke
			(width 0.2)
			(type default)
		)
		(layer "In6.Cu")
	)
	(gr_arc
		(start 146.859752 -47.469298)
		(mid 147.21205 -48.011588)
		(end 147.75434 -47.65929)
		(stroke
			(width 0.2)
			(type default)
		)
		(layer "In6.Cu")
	)
	(gr_arc
		(start 146.969226 -32.460184)
		(mid 146.624662 -31.908815)
		(end 146.077178 -32.259778)
		(stroke
			(width 0.2)
			(type default)
		)
		(layer "In6.Cu")
	)
	(gr_line
		(start 147.097496 -46.35119)
		(end 146.859752 -47.469298)
		(stroke
			(width 0.2)
			(type default)
		)
		(layer "In6.Cu")
	)
	(gr_line
		(start 147.75434 -47.65929)
		(end 147.989544 -46.551596)
		(stroke
			(width 0.2)
			(type default)
		)
		(layer "In6.Cu")
	)
	(gr_line
		(start 147.761452 -12.400026)
		(end 147.761452 -10.999978)
		(stroke
			(width 0.2)
			(type default)
		)
		(layer "In6.Cu")
	)
	(gr_arc
		(start 147.761452 -10.999978)
		(mid 147.200112 -10.438638)
		(end 146.638772 -10.999978)
		(stroke
			(width 0.2)
			(type default)
		)
		(layer "In6.Cu")
	)
	(gr_line
		(start 147.761452 -5.200142)
		(end 147.761452 -3.800094)
		(stroke
			(width 0.2)
			(type default)
		)
		(layer "In6.Cu")
	)
	(gr_arc
		(start 147.761452 -3.800094)
		(mid 147.200112 -3.238754)
		(end 146.638772 -3.800094)
		(stroke
			(width 0.2)
			(type default)
		)
		(layer "In6.Cu")
	)
	(gr_arc
		(start 147.907502 -51.437794)
		(mid 148.2598 -51.980084)
		(end 148.80209 -51.627786)
		(stroke
			(width 0.2)
			(type default)
		)
		(layer "In6.Cu")
	)
	(gr_arc
		(start 147.989544 -46.551596)
		(mid 147.64498 -46.000227)
		(end 147.097496 -46.35119)
		(stroke
			(width 0.2)
			(type default)
		)
		(layer "In6.Cu")
	)
	(gr_line
		(start 148.145246 -50.319686)
		(end 147.907502 -51.437794)
		(stroke
			(width 0.2)
			(type default)
		)
		(layer "In6.Cu")
	)
	(gr_arc
		(start 148.179536 -41.25849)
		(mid 148.531834 -41.80078)
		(end 149.074124 -41.448482)
		(stroke
			(width 0.2)
			(type default)
		)
		(layer "In6.Cu")
	)
	(gr_line
		(start 148.41728 -40.140382)
		(end 148.179536 -41.25849)
		(stroke
			(width 0.2)
			(type default)
		)
		(layer "In6.Cu")
	)
	(gr_arc
		(start 148.438616 -11.199876)
		(mid 148.999829 -11.76147)
		(end 149.561296 -11.20013)
		(stroke
			(width 0.2)
			(type default)
		)
		(layer "In6.Cu")
	)
	(gr_line
		(start 148.438616 -9.800082)
		(end 148.438616 -11.199876)
		(stroke
			(width 0.2)
			(type default)
		)
		(layer "In6.Cu")
	)
	(gr_arc
		(start 148.438616 -3.999738)
		(mid 148.999829 -4.561332)
		(end 149.561296 -3.999992)
		(stroke
			(width 0.2)
			(type default)
		)
		(layer "In6.Cu")
	)
	(gr_line
		(start 148.438616 -2.600198)
		(end 148.438616 -3.999738)
		(stroke
			(width 0.2)
			(type default)
		)
		(layer "In6.Cu")
	)
	(gr_arc
		(start 148.684742 -36.130992)
		(mid 149.03704 -36.673282)
		(end 149.57933 -36.320984)
		(stroke
			(width 0.2)
			(type default)
		)
		(layer "In6.Cu")
	)
	(gr_line
		(start 148.80209 -51.627786)
		(end 149.037294 -50.520092)
		(stroke
			(width 0.2)
			(type default)
		)
		(layer "In6.Cu")
	)
	(gr_line
		(start 148.922486 -35.012884)
		(end 148.684742 -36.130992)
		(stroke
			(width 0.2)
			(type default)
		)
		(layer "In6.Cu")
	)
	(gr_arc
		(start 148.957792 -55.395876)
		(mid 149.302356 -55.947245)
		(end 149.84984 -55.596282)
		(stroke
			(width 0.2)
			(type default)
		)
		(layer "In6.Cu")
	)
	(gr_arc
		(start 149.037294 -50.520092)
		(mid 148.69273 -49.968723)
		(end 148.145246 -50.319686)
		(stroke
			(width 0.2)
			(type default)
		)
		(layer "In6.Cu")
	)
	(gr_line
		(start 149.074124 -41.448482)
		(end 149.309328 -40.340788)
		(stroke
			(width 0.2)
			(type default)
		)
		(layer "In6.Cu")
	)
	(gr_arc
		(start 149.100286 -45.226986)
		(mid 149.452584 -45.769276)
		(end 149.994874 -45.416978)
		(stroke
			(width 0.2)
			(type default)
		)
		(layer "In6.Cu")
	)
	(gr_line
		(start 149.192996 -54.288182)
		(end 148.957792 -55.395876)
		(stroke
			(width 0.2)
			(type default)
		)
		(layer "In6.Cu")
	)
	(gr_arc
		(start 149.309328 -40.340788)
		(mid 148.964764 -39.789419)
		(end 148.41728 -40.140382)
		(stroke
			(width 0.2)
			(type default)
		)
		(layer "In6.Cu")
	)
	(gr_line
		(start 149.33803 -44.108878)
		(end 149.100286 -45.226986)
		(stroke
			(width 0.2)
			(type default)
		)
		(layer "In6.Cu")
	)
	(gr_line
		(start 149.561296 -11.20013)
		(end 149.561296 -9.800082)
		(stroke
			(width 0.2)
			(type default)
		)
		(layer "In6.Cu")
	)
	(gr_arc
		(start 149.561296 -9.800082)
		(mid 148.999956 -9.238742)
		(end 148.438616 -9.800082)
		(stroke
			(width 0.2)
			(type default)
		)
		(layer "In6.Cu")
	)
	(gr_line
		(start 149.561296 -3.999992)
		(end 149.561296 -2.600198)
		(stroke
			(width 0.2)
			(type default)
		)
		(layer "In6.Cu")
	)
	(gr_arc
		(start 149.561296 -2.600198)
		(mid 148.999956 -2.038858)
		(end 148.438616 -2.600198)
		(stroke
			(width 0.2)
			(type default)
		)
		(layer "In6.Cu")
	)
	(gr_line
		(start 149.57933 -36.320984)
		(end 149.814534 -35.21329)
		(stroke
			(width 0.2)
			(type default)
		)
		(layer "In6.Cu")
	)
	(gr_arc
		(start 149.814534 -35.21329)
		(mid 149.46997 -34.661921)
		(end 148.922486 -35.012884)
		(stroke
			(width 0.2)
			(type default)
		)
		(layer "In6.Cu")
	)
	(gr_line
		(start 149.84984 -55.596282)
		(end 150.087584 -54.478174)
		(stroke
			(width 0.2)
			(type default)
		)
		(layer "In6.Cu")
	)
	(gr_line
		(start 149.994874 -45.416978)
		(end 150.230078 -44.309284)
		(stroke
			(width 0.2)
			(type default)
		)
		(layer "In6.Cu")
	)
	(gr_arc
		(start 150.087584 -54.478174)
		(mid 149.735286 -53.935884)
		(end 149.192996 -54.288182)
		(stroke
			(width 0.2)
			(type default)
		)
		(layer "In6.Cu")
	)
	(gr_arc
		(start 150.230078 -44.309284)
		(mid 149.885514 -43.757915)
		(end 149.33803 -44.108878)
		(stroke
			(width 0.2)
			(type default)
		)
		(layer "In6.Cu")
	)
	(gr_arc
		(start 150.54707 -39.016178)
		(mid 150.899368 -39.558468)
		(end 151.441658 -39.20617)
		(stroke
			(width 0.2)
			(type default)
		)
		(layer "In6.Cu")
	)
	(gr_line
		(start 150.784814 -37.89807)
		(end 150.54707 -39.016178)
		(stroke
			(width 0.2)
			(type default)
		)
		(layer "In6.Cu")
	)
	(gr_line
		(start 151.441658 -39.20617)
		(end 151.676862 -38.098476)
		(stroke
			(width 0.2)
			(type default)
		)
		(layer "In6.Cu")
	)
	(gr_arc
		(start 151.676862 -38.098476)
		(mid 151.332298 -37.547107)
		(end 150.784814 -37.89807)
		(stroke
			(width 0.2)
			(type default)
		)
		(layer "In6.Cu")
	)
	(gr_arc
		(start 164.771578 -20.989544)
		(mid 164.786457 -21.025465)
		(end 164.822378 -21.040344)
		(stroke
			(width 0.2)
			(type default)
		)
		(layer "In6.Cu")
	)
	(gr_line
		(start 164.771578 -20.176744)
		(end 164.771578 -20.989544)
		(stroke
			(width 0.2)
			(type default)
		)
		(layer "In6.Cu")
	)
	(gr_line
		(start 164.822378 -21.040344)
		(end 165.025578 -21.040344)
		(stroke
			(width 0.2)
			(type default)
		)
		(layer "In6.Cu")
	)
	(gr_arc
		(start 164.822378 -20.125944)
		(mid 164.786457 -20.140823)
		(end 164.771578 -20.176744)
		(stroke
			(width 0.2)
			(type default)
		)
		(layer "In6.Cu")
	)
	(gr_arc
		(start 165.025578 -21.040344)
		(mid 165.061499 -21.025465)
		(end 165.076378 -20.989544)
		(stroke
			(width 0.2)
			(type default)
		)
		(layer "In6.Cu")
	)
	(gr_line
		(start 165.025578 -20.125944)
		(end 164.822378 -20.125944)
		(stroke
			(width 0.2)
			(type default)
		)
		(layer "In6.Cu")
	)
	(gr_line
		(start 165.076378 -20.989544)
		(end 165.076378 -20.176744)
		(stroke
			(width 0.2)
			(type default)
		)
		(layer "In6.Cu")
	)
	(gr_arc
		(start 165.076378 -20.176744)
		(mid 165.061499 -20.140823)
		(end 165.025578 -20.125944)
		(stroke
			(width 0.2)
			(type default)
		)
		(layer "In6.Cu")
	)
	(gr_line
		(start 165.399974 -37.183568)
		(end 166.199566 -37.183568)
		(stroke
			(width 0.2)
			(type default)
		)
		(layer "In6.Cu")
	)
	(gr_arc
		(start 165.399974 -36.416488)
		(mid 165.016434 -36.800028)
		(end 165.399974 -37.183568)
		(stroke
			(width 0.2)
			(type default)
		)
		(layer "In6.Cu")
	)
	(gr_line
		(start 165.399974 -34.783522)
		(end 166.199566 -34.783522)
		(stroke
			(width 0.2)
			(type default)
		)
		(layer "In6.Cu")
	)
	(gr_arc
		(start 165.399974 -34.016442)
		(mid 165.016434 -34.399982)
		(end 165.399974 -34.783522)
		(stroke
			(width 0.2)
			(type default)
		)
		(layer "In6.Cu")
	)
	(gr_arc
		(start 165.406578 -20.989544)
		(mid 165.421457 -21.025465)
		(end 165.457378 -21.040344)
		(stroke
			(width 0.2)
			(type default)
		)
		(layer "In6.Cu")
	)
	(gr_line
		(start 165.406578 -20.176744)
		(end 165.406578 -20.989544)
		(stroke
			(width 0.2)
			(type default)
		)
		(layer "In6.Cu")
	)
	(gr_line
		(start 165.457378 -21.040344)
		(end 165.660578 -21.040344)
		(stroke
			(width 0.2)
			(type default)
		)
		(layer "In6.Cu")
	)
	(gr_arc
		(start 165.457378 -20.125944)
		(mid 165.421457 -20.140823)
		(end 165.406578 -20.176744)
		(stroke
			(width 0.2)
			(type default)
		)
		(layer "In6.Cu")
	)
	(gr_arc
		(start 165.660578 -21.040344)
		(mid 165.696499 -21.025465)
		(end 165.711378 -20.989544)
		(stroke
			(width 0.2)
			(type default)
		)
		(layer "In6.Cu")
	)
	(gr_line
		(start 165.660578 -20.125944)
		(end 165.457378 -20.125944)
		(stroke
			(width 0.2)
			(type default)
		)
		(layer "In6.Cu")
	)
	(gr_line
		(start 165.711378 -20.989544)
		(end 165.711378 -20.176744)
		(stroke
			(width 0.2)
			(type default)
		)
		(layer "In6.Cu")
	)
	(gr_arc
		(start 165.711378 -20.176744)
		(mid 165.696499 -20.140823)
		(end 165.660578 -20.125944)
		(stroke
			(width 0.2)
			(type default)
		)
		(layer "In6.Cu")
	)
	(gr_arc
		(start 165.741858 -24.055578)
		(mid 166.125271 -24.439372)
		(end 166.508938 -24.055832)
		(stroke
			(width 0.2)
			(type default)
		)
		(layer "In6.Cu")
	)
	(gr_line
		(start 165.741858 -23.166832)
		(end 165.741858 -24.055578)
		(stroke
			(width 0.2)
			(type default)
		)
		(layer "In6.Cu")
	)
	(gr_arc
		(start 165.81628 -38.399974)
		(mid 166.19982 -38.783514)
		(end 166.58336 -38.399974)
		(stroke
			(width 0.2)
			(type default)
		)
		(layer "In6.Cu")
	)
	(gr_line
		(start 165.81628 -37.599874)
		(end 165.81628 -38.399974)
		(stroke
			(width 0.2)
			(type default)
		)
		(layer "In6.Cu")
	)
	(gr_arc
		(start 165.81628 -35.999928)
		(mid 166.19982 -36.383468)
		(end 166.58336 -35.999928)
		(stroke
			(width 0.2)
			(type default)
		)
		(layer "In6.Cu")
	)
	(gr_line
		(start 165.81628 -35.199828)
		(end 165.81628 -35.999928)
		(stroke
			(width 0.2)
			(type default)
		)
		(layer "In6.Cu")
	)
	(gr_arc
		(start 165.81628 -33.599882)
		(mid 166.19982 -33.983422)
		(end 166.58336 -33.599882)
		(stroke
			(width 0.2)
			(type default)
		)
		(layer "In6.Cu")
	)
	(gr_line
		(start 165.81628 -32.800036)
		(end 165.81628 -33.599882)
		(stroke
			(width 0.2)
			(type default)
		)
		(layer "In6.Cu")
	)
	(gr_arc
		(start 165.81628 -31.199836)
		(mid 166.19982 -31.583376)
		(end 166.58336 -31.199836)
		(stroke
			(width 0.2)
			(type default)
		)
		(layer "In6.Cu")
	)
	(gr_line
		(start 165.81628 -30.39999)
		(end 165.81628 -31.199836)
		(stroke
			(width 0.2)
			(type default)
		)
		(layer "In6.Cu")
	)
	(gr_arc
		(start 166.199566 -37.183568)
		(mid 166.58336 -36.800155)
		(end 166.19982 -36.416488)
		(stroke
			(width 0.2)
			(type default)
		)
		(layer "In6.Cu")
	)
	(gr_arc
		(start 166.199566 -34.783522)
		(mid 166.58336 -34.400109)
		(end 166.19982 -34.016442)
		(stroke
			(width 0.2)
			(type default)
		)
		(layer "In6.Cu")
	)
	(gr_line
		(start 166.19982 -36.416488)
		(end 165.399974 -36.416488)
		(stroke
			(width 0.2)
			(type default)
		)
		(layer "In6.Cu")
	)
	(gr_line
		(start 166.19982 -34.016442)
		(end 165.399974 -34.016442)
		(stroke
			(width 0.2)
			(type default)
		)
		(layer "In6.Cu")
	)
	(gr_line
		(start 166.19982 -29.98343)
		(end 166.999412 -29.983684)
		(stroke
			(width 0.2)
			(type default)
		)
		(layer "In6.Cu")
	)
	(gr_line
		(start 166.200074 -32.383476)
		(end 166.999666 -32.383476)
		(stroke
			(width 0.2)
			(type default)
		)
		(layer "In6.Cu")
	)
	(gr_arc
		(start 166.200074 -31.616396)
		(mid 165.816534 -31.999936)
		(end 166.200074 -32.383476)
		(stroke
			(width 0.2)
			(type default)
		)
		(layer "In6.Cu")
	)
	(gr_arc
		(start 166.200074 -29.21635)
		(mid 165.81628 -29.599763)
		(end 166.19982 -29.98343)
		(stroke
			(width 0.2)
			(type default)
		)
		(layer "In6.Cu")
	)
	(gr_arc
		(start 166.49192 -20.979384)
		(mid 166.506799 -21.015305)
		(end 166.54272 -21.030184)
		(stroke
			(width 0.2)
			(type default)
		)
		(layer "In6.Cu")
	)
	(gr_line
		(start 166.49192 -20.166584)
		(end 166.49192 -20.979384)
		(stroke
			(width 0.2)
			(type default)
		)
		(layer "In6.Cu")
	)
	(gr_line
		(start 166.508938 -24.055832)
		(end 166.508938 -23.166832)
		(stroke
			(width 0.2)
			(type default)
		)
		(layer "In6.Cu")
	)
	(gr_arc
		(start 166.508938 -23.166832)
		(mid 166.125398 -22.783292)
		(end 165.741858 -23.166832)
		(stroke
			(width 0.2)
			(type default)
		)
		(layer "In6.Cu")
	)
	(gr_line
		(start 166.54272 -21.030184)
		(end 166.74592 -21.030184)
		(stroke
			(width 0.2)
			(type default)
		)
		(layer "In6.Cu")
	)
	(gr_arc
		(start 166.54272 -20.115784)
		(mid 166.506799 -20.130663)
		(end 166.49192 -20.166584)
		(stroke
			(width 0.2)
			(type default)
		)
		(layer "In6.Cu")
	)
	(gr_line
		(start 166.58336 -38.399974)
		(end 166.58336 -37.600128)
		(stroke
			(width 0.2)
			(type default)
		)
		(layer "In6.Cu")
	)
	(gr_arc
		(start 166.58336 -37.600128)
		(mid 166.199947 -37.216334)
		(end 165.81628 -37.599874)
		(stroke
			(width 0.2)
			(type default)
		)
		(layer "In6.Cu")
	)
	(gr_line
		(start 166.58336 -35.999928)
		(end 166.58336 -35.200082)
		(stroke
			(width 0.2)
			(type default)
		)
		(layer "In6.Cu")
	)
	(gr_arc
		(start 166.58336 -35.200082)
		(mid 166.199947 -34.816288)
		(end 165.81628 -35.199828)
		(stroke
			(width 0.2)
			(type default)
		)
		(layer "In6.Cu")
	)
	(gr_line
		(start 166.58336 -33.599882)
		(end 166.58336 -32.80029)
		(stroke
			(width 0.2)
			(type default)
		)
		(layer "In6.Cu")
	)
	(gr_arc
		(start 166.58336 -32.80029)
		(mid 166.199947 -32.416496)
		(end 165.81628 -32.800036)
		(stroke
			(width 0.2)
			(type default)
		)
		(layer "In6.Cu")
	)
	(gr_line
		(start 166.58336 -31.199836)
		(end 166.58336 -30.400244)
		(stroke
			(width 0.2)
			(type default)
		)
		(layer "In6.Cu")
	)
	(gr_arc
		(start 166.58336 -30.400244)
		(mid 166.199947 -30.01645)
		(end 165.81628 -30.39999)
		(stroke
			(width 0.2)
			(type default)
		)
		(layer "In6.Cu")
	)
	(gr_arc
		(start 166.74592 -21.030184)
		(mid 166.781841 -21.015305)
		(end 166.79672 -20.979384)
		(stroke
			(width 0.2)
			(type default)
		)
		(layer "In6.Cu")
	)
	(gr_line
		(start 166.74592 -20.115784)
		(end 166.54272 -20.115784)
		(stroke
			(width 0.2)
			(type default)
		)
		(layer "In6.Cu")
	)
	(gr_line
		(start 166.79672 -20.979384)
		(end 166.79672 -20.166584)
		(stroke
			(width 0.2)
			(type default)
		)
		(layer "In6.Cu")
	)
	(gr_arc
		(start 166.79672 -20.166584)
		(mid 166.781841 -20.130663)
		(end 166.74592 -20.115784)
		(stroke
			(width 0.2)
			(type default)
		)
		(layer "In6.Cu")
	)
	(gr_arc
		(start 166.999412 -29.983684)
		(mid 167.383206 -29.600271)
		(end 166.999666 -29.216604)
		(stroke
			(width 0.2)
			(type default)
		)
		(layer "In6.Cu")
	)
	(gr_arc
		(start 166.999666 -32.383476)
		(mid 167.38346 -32.000063)
		(end 166.99992 -31.616396)
		(stroke
			(width 0.2)
			(type default)
		)
		(layer "In6.Cu")
	)
	(gr_line
		(start 166.999666 -29.216604)
		(end 166.200074 -29.21635)
		(stroke
			(width 0.2)
			(type default)
		)
		(layer "In6.Cu")
	)
	(gr_line
		(start 166.99992 -31.616396)
		(end 166.200074 -31.616396)
		(stroke
			(width 0.2)
			(type default)
		)
		(layer "In6.Cu")
	)
	(gr_arc
		(start 167.12692 -20.979384)
		(mid 167.141799 -21.015305)
		(end 167.17772 -21.030184)
		(stroke
			(width 0.2)
			(type default)
		)
		(layer "In6.Cu")
	)
	(gr_line
		(start 167.12692 -20.166584)
		(end 167.12692 -20.979384)
		(stroke
			(width 0.2)
			(type default)
		)
		(layer "In6.Cu")
	)
	(gr_line
		(start 167.17772 -21.030184)
		(end 167.38092 -21.030184)
		(stroke
			(width 0.2)
			(type default)
		)
		(layer "In6.Cu")
	)
	(gr_arc
		(start 167.17772 -20.115784)
		(mid 167.141799 -20.130663)
		(end 167.12692 -20.166584)
		(stroke
			(width 0.2)
			(type default)
		)
		(layer "In6.Cu")
	)
	(gr_arc
		(start 167.38092 -21.030184)
		(mid 167.416841 -21.015305)
		(end 167.43172 -20.979384)
		(stroke
			(width 0.2)
			(type default)
		)
		(layer "In6.Cu")
	)
	(gr_line
		(start 167.38092 -20.115784)
		(end 167.17772 -20.115784)
		(stroke
			(width 0.2)
			(type default)
		)
		(layer "In6.Cu")
	)
	(gr_line
		(start 167.43172 -20.979384)
		(end 167.43172 -20.166584)
		(stroke
			(width 0.2)
			(type default)
		)
		(layer "In6.Cu")
	)
	(gr_arc
		(start 167.43172 -20.166584)
		(mid 167.416841 -20.130663)
		(end 167.38092 -20.115784)
		(stroke
			(width 0.2)
			(type default)
		)
		(layer "In6.Cu")
	)
	(gr_line
		(start 167.441626 -30.400244)
		(end 167.44188 -31.199582)
		(stroke
			(width 0.2)
			(type default)
		)
		(layer "In6.Cu")
	)
	(gr_arc
		(start 167.44188 -31.199582)
		(mid 167.80002 -31.557976)
		(end 168.15816 -31.199582)
		(stroke
			(width 0.2)
			(type default)
		)
		(layer "In6.Cu")
	)
	(gr_arc
		(start 167.776398 -24.012652)
		(mid 168.159811 -24.396446)
		(end 168.543478 -24.012906)
		(stroke
			(width 0.2)
			(type default)
		)
		(layer "In6.Cu")
	)
	(gr_line
		(start 167.776398 -23.123906)
		(end 167.776398 -24.012652)
		(stroke
			(width 0.2)
			(type default)
		)
		(layer "In6.Cu")
	)
	(gr_arc
		(start 168.157906 -30.39999)
		(mid 167.799639 -30.04185)
		(end 167.441626 -30.400244)
		(stroke
			(width 0.2)
			(type default)
		)
		(layer "In6.Cu")
	)
	(gr_line
		(start 168.15816 -31.199582)
		(end 168.157906 -30.39999)
		(stroke
			(width 0.2)
			(type default)
		)
		(layer "In6.Cu")
	)
	(gr_arc
		(start 168.241726 -31.199582)
		(mid 168.599739 -31.557976)
		(end 168.958006 -31.199836)
		(stroke
			(width 0.2)
			(type default)
		)
		(layer "In6.Cu")
	)
	(gr_line
		(start 168.241726 -30.39999)
		(end 168.241726 -31.199582)
		(stroke
			(width 0.2)
			(type default)
		)
		(layer "In6.Cu")
	)
	(gr_line
		(start 168.543478 -24.012906)
		(end 168.543478 -23.123906)
		(stroke
			(width 0.2)
			(type default)
		)
		(layer "In6.Cu")
	)
	(gr_arc
		(start 168.543478 -23.123906)
		(mid 168.159938 -22.740366)
		(end 167.776398 -23.123906)
		(stroke
			(width 0.2)
			(type default)
		)
		(layer "In6.Cu")
	)
	(gr_arc
		(start 168.82999 -21.413216)
		(mid 168.844869 -21.449137)
		(end 168.88079 -21.464016)
		(stroke
			(width 0.2)
			(type default)
		)
		(layer "In6.Cu")
	)
	(gr_line
		(start 168.82999 -20.600416)
		(end 168.82999 -21.413216)
		(stroke
			(width 0.2)
			(type default)
		)
		(layer "In6.Cu")
	)
	(gr_line
		(start 168.88079 -21.464016)
		(end 169.08399 -21.464016)
		(stroke
			(width 0.2)
			(type default)
		)
		(layer "In6.Cu")
	)
	(gr_arc
		(start 168.88079 -20.549616)
		(mid 168.844869 -20.564495)
		(end 168.82999 -20.600416)
		(stroke
			(width 0.2)
			(type default)
		)
		(layer "In6.Cu")
	)
	(gr_line
		(start 168.958006 -31.199836)
		(end 168.958006 -30.39999)
		(stroke
			(width 0.2)
			(type default)
		)
		(layer "In6.Cu")
	)
	(gr_arc
		(start 168.958006 -30.39999)
		(mid 168.599866 -30.04185)
		(end 168.241726 -30.39999)
		(stroke
			(width 0.2)
			(type default)
		)
		(layer "In6.Cu")
	)
	(gr_arc
		(start 169.08399 -21.464016)
		(mid 169.119911 -21.449137)
		(end 169.13479 -21.413216)
		(stroke
			(width 0.2)
			(type default)
		)
		(layer "In6.Cu")
	)
	(gr_line
		(start 169.08399 -20.549616)
		(end 168.88079 -20.549616)
		(stroke
			(width 0.2)
			(type default)
		)
		(layer "In6.Cu")
	)
	(gr_line
		(start 169.13479 -21.413216)
		(end 169.13479 -20.600416)
		(stroke
			(width 0.2)
			(type default)
		)
		(layer "In6.Cu")
	)
	(gr_arc
		(start 169.13479 -20.600416)
		(mid 169.119911 -20.564495)
		(end 169.08399 -20.549616)
		(stroke
			(width 0.2)
			(type default)
		)
		(layer "In6.Cu")
	)
	(gr_arc
		(start 169.4053 -21.410676)
		(mid 169.420179 -21.446597)
		(end 169.4561 -21.461476)
		(stroke
			(width 0.2)
			(type default)
		)
		(layer "In6.Cu")
	)
	(gr_line
		(start 169.4053 -20.597876)
		(end 169.4053 -21.410676)
		(stroke
			(width 0.2)
			(type default)
		)
		(layer "In6.Cu")
	)
	(gr_line
		(start 169.4561 -21.461476)
		(end 169.6593 -21.461476)
		(stroke
			(width 0.2)
			(type default)
		)
		(layer "In6.Cu")
	)
	(gr_arc
		(start 169.4561 -20.547076)
		(mid 169.420179 -20.561955)
		(end 169.4053 -20.597876)
		(stroke
			(width 0.2)
			(type default)
		)
		(layer "In6.Cu")
	)
	(gr_arc
		(start 169.6593 -21.461476)
		(mid 169.695221 -21.446597)
		(end 169.7101 -21.410676)
		(stroke
			(width 0.2)
			(type default)
		)
		(layer "In6.Cu")
	)
	(gr_line
		(start 169.6593 -20.547076)
		(end 169.4561 -20.547076)
		(stroke
			(width 0.2)
			(type default)
		)
		(layer "In6.Cu")
	)
	(gr_line
		(start 169.7101 -21.410676)
		(end 169.7101 -20.597876)
		(stroke
			(width 0.2)
			(type default)
		)
		(layer "In6.Cu")
	)
	(gr_arc
		(start 169.7101 -20.597876)
		(mid 169.695221 -20.561955)
		(end 169.6593 -20.547076)
		(stroke
			(width 0.2)
			(type default)
		)
		(layer "In6.Cu")
	)
	(gr_arc
		(start 169.833544 -24.004016)
		(mid 170.216957 -24.38781)
		(end 170.600624 -24.00427)
		(stroke
			(width 0.2)
			(type default)
		)
		(layer "In6.Cu")
	)
	(gr_line
		(start 169.833544 -23.11527)
		(end 169.833544 -24.004016)
		(stroke
			(width 0.2)
			(type default)
		)
		(layer "In6.Cu")
	)
	(gr_line
		(start 169.841672 -30.400244)
		(end 169.841926 -31.199836)
		(stroke
			(width 0.2)
			(type default)
		)
		(layer "In6.Cu")
	)
	(gr_arc
		(start 169.841926 -31.199836)
		(mid 170.200066 -31.55823)
		(end 170.558206 -31.199836)
		(stroke
			(width 0.2)
			(type default)
		)
		(layer "In6.Cu")
	)
	(gr_arc
		(start 170.557952 -30.39999)
		(mid 170.199685 -30.04185)
		(end 169.841672 -30.400244)
		(stroke
			(width 0.2)
			(type default)
		)
		(layer "In6.Cu")
	)
	(gr_line
		(start 170.558206 -31.199836)
		(end 170.557952 -30.39999)
		(stroke
			(width 0.2)
			(type default)
		)
		(layer "In6.Cu")
	)
	(gr_line
		(start 170.600624 -24.00427)
		(end 170.600624 -23.11527)
		(stroke
			(width 0.2)
			(type default)
		)
		(layer "In6.Cu")
	)
	(gr_arc
		(start 170.600624 -23.11527)
		(mid 170.217084 -22.73173)
		(end 169.833544 -23.11527)
		(stroke
			(width 0.2)
			(type default)
		)
		(layer "In6.Cu")
	)
	(gr_line
		(start 170.641772 -30.400244)
		(end 170.642026 -31.199836)
		(stroke
			(width 0.2)
			(type default)
		)
		(layer "In6.Cu")
	)
	(gr_arc
		(start 170.642026 -31.199836)
		(mid 171.000166 -31.55823)
		(end 171.358306 -31.199836)
		(stroke
			(width 0.2)
			(type default)
		)
		(layer "In6.Cu")
	)
	(gr_arc
		(start 170.770804 -21.29282)
		(mid 170.785683 -21.328741)
		(end 170.821604 -21.34362)
		(stroke
			(width 0.2)
			(type default)
		)
		(layer "In6.Cu")
	)
	(gr_line
		(start 170.770804 -20.48002)
		(end 170.770804 -21.29282)
		(stroke
			(width 0.2)
			(type default)
		)
		(layer "In6.Cu")
	)
	(gr_line
		(start 170.821604 -21.34362)
		(end 171.024804 -21.34362)
		(stroke
			(width 0.2)
			(type default)
		)
		(layer "In6.Cu")
	)
	(gr_arc
		(start 170.821604 -20.42922)
		(mid 170.785683 -20.444099)
		(end 170.770804 -20.48002)
		(stroke
			(width 0.2)
			(type default)
		)
		(layer "In6.Cu")
	)
	(gr_arc
		(start 171.024804 -21.34362)
		(mid 171.060725 -21.328741)
		(end 171.075604 -21.29282)
		(stroke
			(width 0.2)
			(type default)
		)
		(layer "In6.Cu")
	)
	(gr_line
		(start 171.024804 -20.42922)
		(end 170.821604 -20.42922)
		(stroke
			(width 0.2)
			(type default)
		)
		(layer "In6.Cu")
	)
	(gr_line
		(start 171.075604 -21.29282)
		(end 171.075604 -20.48002)
		(stroke
			(width 0.2)
			(type default)
		)
		(layer "In6.Cu")
	)
	(gr_arc
		(start 171.075604 -20.48002)
		(mid 171.060725 -20.444099)
		(end 171.024804 -20.42922)
		(stroke
			(width 0.2)
			(type default)
		)
		(layer "In6.Cu")
	)
	(gr_arc
		(start 171.358052 -30.39999)
		(mid 170.999785 -30.04185)
		(end 170.641772 -30.400244)
		(stroke
			(width 0.2)
			(type default)
		)
		(layer "In6.Cu")
	)
	(gr_line
		(start 171.358306 -31.199836)
		(end 171.358052 -30.39999)
		(stroke
			(width 0.2)
			(type default)
		)
		(layer "In6.Cu")
	)
	(gr_arc
		(start 171.380404 -21.29282)
		(mid 171.395283 -21.328741)
		(end 171.431204 -21.34362)
		(stroke
			(width 0.2)
			(type default)
		)
		(layer "In6.Cu")
	)
	(gr_line
		(start 171.380404 -20.48002)
		(end 171.380404 -21.29282)
		(stroke
			(width 0.2)
			(type default)
		)
		(layer "In6.Cu")
	)
	(gr_line
		(start 171.431204 -21.34362)
		(end 171.634404 -21.34362)
		(stroke
			(width 0.2)
			(type default)
		)
		(layer "In6.Cu")
	)
	(gr_arc
		(start 171.431204 -20.42922)
		(mid 171.395283 -20.444099)
		(end 171.380404 -20.48002)
		(stroke
			(width 0.2)
			(type default)
		)
		(layer "In6.Cu")
	)
	(gr_arc
		(start 171.634404 -21.34362)
		(mid 171.670325 -21.328741)
		(end 171.685204 -21.29282)
		(stroke
			(width 0.2)
			(type default)
		)
		(layer "In6.Cu")
	)
	(gr_line
		(start 171.634404 -20.42922)
		(end 171.431204 -20.42922)
		(stroke
			(width 0.2)
			(type default)
		)
		(layer "In6.Cu")
	)
	(gr_line
		(start 171.685204 -21.29282)
		(end 171.685204 -20.48002)
		(stroke
			(width 0.2)
			(type default)
		)
		(layer "In6.Cu")
	)
	(gr_arc
		(start 171.685204 -20.48002)
		(mid 171.670325 -20.444099)
		(end 171.634404 -20.42922)
		(stroke
			(width 0.2)
			(type default)
		)
		(layer "In6.Cu")
	)
	(gr_arc
		(start 171.88561 -24.00173)
		(mid 172.269023 -24.385524)
		(end 172.65269 -24.001984)
		(stroke
			(width 0.2)
			(type default)
		)
		(layer "In6.Cu")
	)
	(gr_line
		(start 171.88561 -23.112984)
		(end 171.88561 -24.00173)
		(stroke
			(width 0.2)
			(type default)
		)
		(layer "In6.Cu")
	)
	(gr_line
		(start 172.241718 -30.400244)
		(end 172.241972 -31.199836)
		(stroke
			(width 0.2)
			(type default)
		)
		(layer "In6.Cu")
	)
	(gr_arc
		(start 172.241972 -31.199836)
		(mid 172.600112 -31.55823)
		(end 172.958252 -31.199836)
		(stroke
			(width 0.2)
			(type default)
		)
		(layer "In6.Cu")
	)
	(gr_line
		(start 172.65269 -24.001984)
		(end 172.65269 -23.112984)
		(stroke
			(width 0.2)
			(type default)
		)
		(layer "In6.Cu")
	)
	(gr_arc
		(start 172.65269 -23.112984)
		(mid 172.26915 -22.729444)
		(end 171.88561 -23.112984)
		(stroke
			(width 0.2)
			(type default)
		)
		(layer "In6.Cu")
	)
	(gr_arc
		(start 172.893482 -21.292566)
		(mid 172.908361 -21.328487)
		(end 172.944282 -21.343366)
		(stroke
			(width 0.2)
			(type default)
		)
		(layer "In6.Cu")
	)
	(gr_line
		(start 172.893482 -20.479766)
		(end 172.893482 -21.292566)
		(stroke
			(width 0.2)
			(type default)
		)
		(layer "In6.Cu")
	)
	(gr_line
		(start 172.944282 -21.343366)
		(end 173.147482 -21.343366)
		(stroke
			(width 0.2)
			(type default)
		)
		(layer "In6.Cu")
	)
	(gr_arc
		(start 172.944282 -20.428966)
		(mid 172.908361 -20.443845)
		(end 172.893482 -20.479766)
		(stroke
			(width 0.2)
			(type default)
		)
		(layer "In6.Cu")
	)
	(gr_arc
		(start 172.957998 -30.39999)
		(mid 172.599731 -30.04185)
		(end 172.241718 -30.400244)
		(stroke
			(width 0.2)
			(type default)
		)
		(layer "In6.Cu")
	)
	(gr_line
		(start 172.958252 -31.199836)
		(end 172.957998 -30.39999)
		(stroke
			(width 0.2)
			(type default)
		)
		(layer "In6.Cu")
	)
	(gr_line
		(start 173.041818 -30.400244)
		(end 173.042072 -31.199836)
		(stroke
			(width 0.2)
			(type default)
		)
		(layer "In6.Cu")
	)
	(gr_arc
		(start 173.042072 -31.199836)
		(mid 173.400212 -31.55823)
		(end 173.758352 -31.199836)
		(stroke
			(width 0.2)
			(type default)
		)
		(layer "In6.Cu")
	)
	(gr_arc
		(start 173.147482 -21.343366)
		(mid 173.183403 -21.328487)
		(end 173.198282 -21.292566)
		(stroke
			(width 0.2)
			(type default)
		)
		(layer "In6.Cu")
	)
	(gr_line
		(start 173.147482 -20.428966)
		(end 172.944282 -20.428966)
		(stroke
			(width 0.2)
			(type default)
		)
		(layer "In6.Cu")
	)
	(gr_line
		(start 173.198282 -21.292566)
		(end 173.198282 -20.479766)
		(stroke
			(width 0.2)
			(type default)
		)
		(layer "In6.Cu")
	)
	(gr_arc
		(start 173.198282 -20.479766)
		(mid 173.183403 -20.443845)
		(end 173.147482 -20.428966)
		(stroke
			(width 0.2)
			(type default)
		)
		(layer "In6.Cu")
	)
	(gr_arc
		(start 173.472602 -21.29282)
		(mid 173.487481 -21.328741)
		(end 173.523402 -21.34362)
		(stroke
			(width 0.2)
			(type default)
		)
		(layer "In6.Cu")
	)
	(gr_line
		(start 173.472602 -20.48002)
		(end 173.472602 -21.29282)
		(stroke
			(width 0.2)
			(type default)
		)
		(layer "In6.Cu")
	)
	(gr_line
		(start 173.523402 -21.34362)
		(end 173.726602 -21.34362)
		(stroke
			(width 0.2)
			(type default)
		)
		(layer "In6.Cu")
	)
	(gr_arc
		(start 173.523402 -20.42922)
		(mid 173.487481 -20.444099)
		(end 173.472602 -20.48002)
		(stroke
			(width 0.2)
			(type default)
		)
		(layer "In6.Cu")
	)
	(gr_arc
		(start 173.726602 -21.34362)
		(mid 173.762523 -21.328741)
		(end 173.777402 -21.29282)
		(stroke
			(width 0.2)
			(type default)
		)
		(layer "In6.Cu")
	)
	(gr_line
		(start 173.726602 -20.42922)
		(end 173.523402 -20.42922)
		(stroke
			(width 0.2)
			(type default)
		)
		(layer "In6.Cu")
	)
	(gr_arc
		(start 173.758098 -30.39999)
		(mid 173.399831 -30.04185)
		(end 173.041818 -30.400244)
		(stroke
			(width 0.2)
			(type default)
		)
		(layer "In6.Cu")
	)
	(gr_line
		(start 173.758352 -31.199836)
		(end 173.758098 -30.39999)
		(stroke
			(width 0.2)
			(type default)
		)
		(layer "In6.Cu")
	)
	(gr_line
		(start 173.777402 -21.29282)
		(end 173.777402 -20.48002)
		(stroke
			(width 0.2)
			(type default)
		)
		(layer "In6.Cu")
	)
	(gr_arc
		(start 173.777402 -20.48002)
		(mid 173.762523 -20.444099)
		(end 173.726602 -20.42922)
		(stroke
			(width 0.2)
			(type default)
		)
		(layer "In6.Cu")
	)
	(gr_arc
		(start 173.931326 -24.001222)
		(mid 174.314739 -24.385016)
		(end 174.698406 -24.001476)
		(stroke
			(width 0.2)
			(type default)
		)
		(layer "In6.Cu")
	)
	(gr_line
		(start 173.931326 -23.112476)
		(end 173.931326 -24.001222)
		(stroke
			(width 0.2)
			(type default)
		)
		(layer "In6.Cu")
	)
	(gr_line
		(start 174.641764 -30.400244)
		(end 174.642018 -31.199836)
		(stroke
			(width 0.2)
			(type default)
		)
		(layer "In6.Cu")
	)
	(gr_arc
		(start 174.642018 -31.199836)
		(mid 175.000158 -31.55823)
		(end 175.358298 -31.199836)
		(stroke
			(width 0.2)
			(type default)
		)
		(layer "In6.Cu")
	)
	(gr_line
		(start 174.698406 -24.001476)
		(end 174.698406 -23.112476)
		(stroke
			(width 0.2)
			(type default)
		)
		(layer "In6.Cu")
	)
	(gr_arc
		(start 174.698406 -23.112476)
		(mid 174.314866 -22.728936)
		(end 173.931326 -23.112476)
		(stroke
			(width 0.2)
			(type default)
		)
		(layer "In6.Cu")
	)
	(gr_arc
		(start 174.891446 -21.360892)
		(mid 174.906325 -21.396813)
		(end 174.942246 -21.411692)
		(stroke
			(width 0.2)
			(type default)
		)
		(layer "In6.Cu")
	)
	(gr_line
		(start 174.891446 -20.548092)
		(end 174.891446 -21.360892)
		(stroke
			(width 0.2)
			(type default)
		)
		(layer "In6.Cu")
	)
	(gr_line
		(start 174.942246 -21.411692)
		(end 175.145446 -21.411692)
		(stroke
			(width 0.2)
			(type default)
		)
		(layer "In6.Cu")
	)
	(gr_arc
		(start 174.942246 -20.497292)
		(mid 174.906325 -20.512171)
		(end 174.891446 -20.548092)
		(stroke
			(width 0.2)
			(type default)
		)
		(layer "In6.Cu")
	)
	(gr_arc
		(start 175.145446 -21.411692)
		(mid 175.181367 -21.396813)
		(end 175.196246 -21.360892)
		(stroke
			(width 0.2)
			(type default)
		)
		(layer "In6.Cu")
	)
	(gr_line
		(start 175.145446 -20.497292)
		(end 174.942246 -20.497292)
		(stroke
			(width 0.2)
			(type default)
		)
		(layer "In6.Cu")
	)
	(gr_line
		(start 175.196246 -21.360892)
		(end 175.196246 -20.548092)
		(stroke
			(width 0.2)
			(type default)
		)
		(layer "In6.Cu")
	)
	(gr_arc
		(start 175.196246 -20.548092)
		(mid 175.181367 -20.512171)
		(end 175.145446 -20.497292)
		(stroke
			(width 0.2)
			(type default)
		)
		(layer "In6.Cu")
	)
	(gr_arc
		(start 175.358044 -30.39999)
		(mid 174.999777 -30.04185)
		(end 174.641764 -30.400244)
		(stroke
			(width 0.2)
			(type default)
		)
		(layer "In6.Cu")
	)
	(gr_line
		(start 175.358298 -31.199836)
		(end 175.358044 -30.39999)
		(stroke
			(width 0.2)
			(type default)
		)
		(layer "In6.Cu")
	)
	(gr_arc
		(start 175.441864 -31.199836)
		(mid 175.799877 -31.55823)
		(end 176.158144 -31.20009)
		(stroke
			(width 0.2)
			(type default)
		)
		(layer "In6.Cu")
	)
	(gr_line
		(start 175.441864 -30.400244)
		(end 175.441864 -31.199836)
		(stroke
			(width 0.2)
			(type default)
		)
		(layer "In6.Cu")
	)
	(gr_arc
		(start 175.458628 -21.361146)
		(mid 175.473507 -21.397067)
		(end 175.509428 -21.411946)
		(stroke
			(width 0.2)
			(type default)
		)
		(layer "In6.Cu")
	)
	(gr_line
		(start 175.458628 -20.548346)
		(end 175.458628 -21.361146)
		(stroke
			(width 0.2)
			(type default)
		)
		(layer "In6.Cu")
	)
	(gr_line
		(start 175.509428 -21.411946)
		(end 175.712628 -21.411946)
		(stroke
			(width 0.2)
			(type default)
		)
		(layer "In6.Cu")
	)
	(gr_arc
		(start 175.509428 -20.497546)
		(mid 175.473507 -20.512425)
		(end 175.458628 -20.548346)
		(stroke
			(width 0.2)
			(type default)
		)
		(layer "In6.Cu")
	)
	(gr_arc
		(start 175.712628 -21.411946)
		(mid 175.748549 -21.397067)
		(end 175.763428 -21.361146)
		(stroke
			(width 0.2)
			(type default)
		)
		(layer "In6.Cu")
	)
	(gr_line
		(start 175.712628 -20.497546)
		(end 175.509428 -20.497546)
		(stroke
			(width 0.2)
			(type default)
		)
		(layer "In6.Cu")
	)
	(gr_line
		(start 175.763428 -21.361146)
		(end 175.763428 -20.548346)
		(stroke
			(width 0.2)
			(type default)
		)
		(layer "In6.Cu")
	)
	(gr_arc
		(start 175.763428 -20.548346)
		(mid 175.748549 -20.512425)
		(end 175.712628 -20.497546)
		(stroke
			(width 0.2)
			(type default)
		)
		(layer "In6.Cu")
	)
	(gr_arc
		(start 175.98517 -23.992078)
		(mid 176.368583 -24.375872)
		(end 176.75225 -23.992332)
		(stroke
			(width 0.2)
			(type default)
		)
		(layer "In6.Cu")
	)
	(gr_line
		(start 175.98517 -23.103332)
		(end 175.98517 -23.992078)
		(stroke
			(width 0.2)
			(type default)
		)
		(layer "In6.Cu")
	)
	(gr_line
		(start 176.158144 -31.20009)
		(end 176.158144 -30.400244)
		(stroke
			(width 0.2)
			(type default)
		)
		(layer "In6.Cu")
	)
	(gr_arc
		(start 176.158144 -30.400244)
		(mid 175.800004 -30.042104)
		(end 175.441864 -30.400244)
		(stroke
			(width 0.2)
			(type default)
		)
		(layer "In6.Cu")
	)
	(gr_line
		(start 176.75225 -23.992332)
		(end 176.75225 -23.103332)
		(stroke
			(width 0.2)
			(type default)
		)
		(layer "In6.Cu")
	)
	(gr_arc
		(start 176.75225 -23.103332)
		(mid 176.36871 -22.719792)
		(end 175.98517 -23.103332)
		(stroke
			(width 0.2)
			(type default)
		)
		(layer "In6.Cu")
	)
	(gr_arc
		(start 177.962814 -20.681442)
		(mid 177.977693 -20.717363)
		(end 178.013614 -20.732242)
		(stroke
			(width 0.2)
			(type default)
		)
		(layer "In6.Cu")
	)
	(gr_line
		(start 177.962814 -20.478242)
		(end 177.962814 -20.681442)
		(stroke
			(width 0.2)
			(type default)
		)
		(layer "In6.Cu")
	)
	(gr_arc
		(start 177.963576 -21.25218)
		(mid 177.978455 -21.288101)
		(end 178.014376 -21.30298)
		(stroke
			(width 0.2)
			(type default)
		)
		(layer "In6.Cu")
	)
	(gr_line
		(start 177.963576 -21.04898)
		(end 177.963576 -21.25218)
		(stroke
			(width 0.2)
			(type default)
		)
		(layer "In6.Cu")
	)
	(gr_line
		(start 178.013614 -20.732242)
		(end 178.826414 -20.732242)
		(stroke
			(width 0.2)
			(type default)
		)
		(layer "In6.Cu")
	)
	(gr_arc
		(start 178.013614 -20.427442)
		(mid 177.977693 -20.442321)
		(end 177.962814 -20.478242)
		(stroke
			(width 0.2)
			(type default)
		)
		(layer "In6.Cu")
	)
	(gr_line
		(start 178.014376 -21.30298)
		(end 178.827176 -21.30298)
		(stroke
			(width 0.2)
			(type default)
		)
		(layer "In6.Cu")
	)
	(gr_arc
		(start 178.014376 -20.99818)
		(mid 177.978455 -21.013059)
		(end 177.963576 -21.04898)
		(stroke
			(width 0.2)
			(type default)
		)
		(layer "In6.Cu")
	)
	(gr_arc
		(start 178.023774 -24.005286)
		(mid 178.407187 -24.38908)
		(end 178.790854 -24.00554)
		(stroke
			(width 0.2)
			(type default)
		)
		(layer "In6.Cu")
	)
	(gr_line
		(start 178.023774 -23.11654)
		(end 178.023774 -24.005286)
		(stroke
			(width 0.2)
			(type default)
		)
		(layer "In6.Cu")
	)
	(gr_line
		(start 178.790854 -24.00554)
		(end 178.790854 -23.11654)
		(stroke
			(width 0.2)
			(type default)
		)
		(layer "In6.Cu")
	)
	(gr_arc
		(start 178.790854 -23.11654)
		(mid 178.407314 -22.733)
		(end 178.023774 -23.11654)
		(stroke
			(width 0.2)
			(type default)
		)
		(layer "In6.Cu")
	)
	(gr_arc
		(start 178.826414 -20.732242)
		(mid 178.862335 -20.717363)
		(end 178.877214 -20.681442)
		(stroke
			(width 0.2)
			(type default)
		)
		(layer "In6.Cu")
	)
	(gr_line
		(start 178.826414 -20.427442)
		(end 178.013614 -20.427442)
		(stroke
			(width 0.2)
			(type default)
		)
		(layer "In6.Cu")
	)
	(gr_arc
		(start 178.827176 -21.30298)
		(mid 178.863097 -21.288101)
		(end 178.877976 -21.25218)
		(stroke
			(width 0.2)
			(type default)
		)
		(layer "In6.Cu")
	)
	(gr_line
		(start 178.827176 -20.99818)
		(end 178.014376 -20.99818)
		(stroke
			(width 0.2)
			(type default)
		)
		(layer "In6.Cu")
	)
	(gr_line
		(start 178.877214 -20.681442)
		(end 178.877214 -20.478242)
		(stroke
			(width 0.2)
			(type default)
		)
		(layer "In6.Cu")
	)
	(gr_arc
		(start 178.877214 -20.478242)
		(mid 178.862335 -20.442321)
		(end 178.826414 -20.427442)
		(stroke
			(width 0.2)
			(type default)
		)
		(layer "In6.Cu")
	)
	(gr_line
		(start 178.877976 -21.25218)
		(end 178.877976 -21.04898)
		(stroke
			(width 0.2)
			(type default)
		)
		(layer "In6.Cu")
	)
	(gr_arc
		(start 178.877976 -21.04898)
		(mid 178.863097 -21.013059)
		(end 178.827176 -20.99818)
		(stroke
			(width 0.2)
			(type default)
		)
		(layer "In6.Cu")
	)
	(gr_arc
		(start 179.438554 -12.399772)
		(mid 179.999767 -12.961366)
		(end 180.561234 -12.400026)
		(stroke
			(width 0.2)
			(type default)
		)
		(layer "In6.Cu")
	)
	(gr_line
		(start 179.438554 -10.999978)
		(end 179.438554 -12.399772)
		(stroke
			(width 0.2)
			(type default)
		)
		(layer "In6.Cu")
	)
	(gr_arc
		(start 179.438554 -8.79983)
		(mid 179.999767 -9.361424)
		(end 180.561234 -8.800084)
		(stroke
			(width 0.2)
			(type default)
		)
		(layer "In6.Cu")
	)
	(gr_line
		(start 179.438554 -7.400036)
		(end 179.438554 -8.79983)
		(stroke
			(width 0.2)
			(type default)
		)
		(layer "In6.Cu")
	)
	(gr_arc
		(start 179.438554 -5.199888)
		(mid 179.999767 -5.761482)
		(end 180.561234 -5.200142)
		(stroke
			(width 0.2)
			(type default)
		)
		(layer "In6.Cu")
	)
	(gr_line
		(start 179.438554 -3.800094)
		(end 179.438554 -5.199888)
		(stroke
			(width 0.2)
			(type default)
		)
		(layer "In6.Cu")
	)
	(gr_arc
		(start 180.052472 -24.485092)
		(mid 180.435885 -24.868886)
		(end 180.819552 -24.485346)
		(stroke
			(width 0.2)
			(type default)
		)
		(layer "In6.Cu")
	)
	(gr_line
		(start 180.052472 -23.596346)
		(end 180.052472 -24.485092)
		(stroke
			(width 0.2)
			(type default)
		)
		(layer "In6.Cu")
	)
	(gr_line
		(start 180.561234 -12.400026)
		(end 180.561234 -10.999978)
		(stroke
			(width 0.2)
			(type default)
		)
		(layer "In6.Cu")
	)
	(gr_arc
		(start 180.561234 -10.999978)
		(mid 179.999894 -10.438638)
		(end 179.438554 -10.999978)
		(stroke
			(width 0.2)
			(type default)
		)
		(layer "In6.Cu")
	)
	(gr_line
		(start 180.561234 -8.800084)
		(end 180.561234 -7.400036)
		(stroke
			(width 0.2)
			(type default)
		)
		(layer "In6.Cu")
	)
	(gr_arc
		(start 180.561234 -7.400036)
		(mid 179.999894 -6.838696)
		(end 179.438554 -7.400036)
		(stroke
			(width 0.2)
			(type default)
		)
		(layer "In6.Cu")
	)
	(gr_line
		(start 180.561234 -5.200142)
		(end 180.561234 -3.800094)
		(stroke
			(width 0.2)
			(type default)
		)
		(layer "In6.Cu")
	)
	(gr_arc
		(start 180.561234 -3.800094)
		(mid 179.999894 -3.238754)
		(end 179.438554 -3.800094)
		(stroke
			(width 0.2)
			(type default)
		)
		(layer "In6.Cu")
	)
	(gr_arc
		(start 180.812186 -21.943568)
		(mid 180.827065 -21.979489)
		(end 180.862986 -21.994368)
		(stroke
			(width 0.2)
			(type default)
		)
		(layer "In6.Cu")
	)
	(gr_line
		(start 180.812186 -21.740368)
		(end 180.812186 -21.943568)
		(stroke
			(width 0.2)
			(type default)
		)
		(layer "In6.Cu")
	)
	(gr_arc
		(start 180.81244 -21.37664)
		(mid 180.827319 -21.412561)
		(end 180.86324 -21.42744)
		(stroke
			(width 0.2)
			(type default)
		)
		(layer "In6.Cu")
	)
	(gr_line
		(start 180.81244 -21.17344)
		(end 180.81244 -21.37664)
		(stroke
			(width 0.2)
			(type default)
		)
		(layer "In6.Cu")
	)
	(gr_line
		(start 180.819552 -24.485346)
		(end 180.819552 -23.596346)
		(stroke
			(width 0.2)
			(type default)
		)
		(layer "In6.Cu")
	)
	(gr_arc
		(start 180.819552 -23.596346)
		(mid 180.436012 -23.212806)
		(end 180.052472 -23.596346)
		(stroke
			(width 0.2)
			(type default)
		)
		(layer "In6.Cu")
	)
	(gr_line
		(start 180.862986 -21.994368)
		(end 181.675786 -21.994368)
		(stroke
			(width 0.2)
			(type default)
		)
		(layer "In6.Cu")
	)
	(gr_arc
		(start 180.862986 -21.689568)
		(mid 180.827065 -21.704447)
		(end 180.812186 -21.740368)
		(stroke
			(width 0.2)
			(type default)
		)
		(layer "In6.Cu")
	)
	(gr_line
		(start 180.86324 -21.42744)
		(end 181.67604 -21.42744)
		(stroke
			(width 0.2)
			(type default)
		)
		(layer "In6.Cu")
	)
	(gr_arc
		(start 180.86324 -21.12264)
		(mid 180.827319 -21.137519)
		(end 180.81244 -21.17344)
		(stroke
			(width 0.2)
			(type default)
		)
		(layer "In6.Cu")
	)
	(gr_arc
		(start 181.238652 -11.199876)
		(mid 181.799865 -11.76147)
		(end 182.361332 -11.20013)
		(stroke
			(width 0.2)
			(type default)
		)
		(layer "In6.Cu")
	)
	(gr_line
		(start 181.238652 -9.800082)
		(end 181.238652 -11.199876)
		(stroke
			(width 0.2)
			(type default)
		)
		(layer "In6.Cu")
	)
	(gr_arc
		(start 181.238652 -3.999738)
		(mid 181.799865 -4.561332)
		(end 182.361332 -3.999992)
		(stroke
			(width 0.2)
			(type default)
		)
		(layer "In6.Cu")
	)
	(gr_line
		(start 181.238652 -2.600198)
		(end 181.238652 -3.999738)
		(stroke
			(width 0.2)
			(type default)
		)
		(layer "In6.Cu")
	)
	(gr_arc
		(start 181.675786 -21.994368)
		(mid 181.711707 -21.979489)
		(end 181.726586 -21.943568)
		(stroke
			(width 0.2)
			(type default)
		)
		(layer "In6.Cu")
	)
	(gr_line
		(start 181.675786 -21.689568)
		(end 180.862986 -21.689568)
		(stroke
			(width 0.2)
			(type default)
		)
		(layer "In6.Cu")
	)
	(gr_arc
		(start 181.67604 -21.42744)
		(mid 181.711961 -21.412561)
		(end 181.72684 -21.37664)
		(stroke
			(width 0.2)
			(type default)
		)
		(layer "In6.Cu")
	)
	(gr_line
		(start 181.67604 -21.12264)
		(end 180.86324 -21.12264)
		(stroke
			(width 0.2)
			(type default)
		)
		(layer "In6.Cu")
	)
	(gr_line
		(start 181.726586 -21.943568)
		(end 181.726586 -21.740368)
		(stroke
			(width 0.2)
			(type default)
		)
		(layer "In6.Cu")
	)
	(gr_arc
		(start 181.726586 -21.740368)
		(mid 181.711707 -21.704447)
		(end 181.675786 -21.689568)
		(stroke
			(width 0.2)
			(type default)
		)
		(layer "In6.Cu")
	)
	(gr_line
		(start 181.72684 -21.37664)
		(end 181.72684 -21.17344)
		(stroke
			(width 0.2)
			(type default)
		)
		(layer "In6.Cu")
	)
	(gr_arc
		(start 181.72684 -21.17344)
		(mid 181.711961 -21.137519)
		(end 181.67604 -21.12264)
		(stroke
			(width 0.2)
			(type default)
		)
		(layer "In6.Cu")
	)
	(gr_line
		(start 182.361332 -11.20013)
		(end 182.361332 -9.800082)
		(stroke
			(width 0.2)
			(type default)
		)
		(layer "In6.Cu")
	)
	(gr_arc
		(start 182.361332 -9.800082)
		(mid 181.799992 -9.238742)
		(end 181.238652 -9.800082)
		(stroke
			(width 0.2)
			(type default)
		)
		(layer "In6.Cu")
	)
	(gr_line
		(start 182.361332 -3.999992)
		(end 182.361332 -2.600198)
		(stroke
			(width 0.2)
			(type default)
		)
		(layer "In6.Cu")
	)
	(gr_arc
		(start 182.361332 -2.600198)
		(mid 181.799992 -2.038858)
		(end 181.238652 -2.600198)
		(stroke
			(width 0.2)
			(type default)
		)
		(layer "In6.Cu")
	)
	(gr_arc
		(start 183.038496 -12.399772)
		(mid 183.599709 -12.961366)
		(end 184.161176 -12.400026)
		(stroke
			(width 0.2)
			(type default)
		)
		(layer "In6.Cu")
	)
	(gr_line
		(start 183.038496 -10.999978)
		(end 183.038496 -12.399772)
		(stroke
			(width 0.2)
			(type default)
		)
		(layer "In6.Cu")
	)
	(gr_arc
		(start 183.038496 -5.199888)
		(mid 183.599709 -5.761482)
		(end 184.161176 -5.200142)
		(stroke
			(width 0.2)
			(type default)
		)
		(layer "In6.Cu")
	)
	(gr_line
		(start 183.038496 -3.800094)
		(end 183.038496 -5.199888)
		(stroke
			(width 0.2)
			(type default)
		)
		(layer "In6.Cu")
	)
	(gr_line
		(start 184.161176 -12.400026)
		(end 184.161176 -10.999978)
		(stroke
			(width 0.2)
			(type default)
		)
		(layer "In6.Cu")
	)
	(gr_arc
		(start 184.161176 -10.999978)
		(mid 183.599836 -10.438638)
		(end 183.038496 -10.999978)
		(stroke
			(width 0.2)
			(type default)
		)
		(layer "In6.Cu")
	)
	(gr_line
		(start 184.161176 -5.200142)
		(end 184.161176 -3.800094)
		(stroke
			(width 0.2)
			(type default)
		)
		(layer "In6.Cu")
	)
	(gr_arc
		(start 184.161176 -3.800094)
		(mid 183.599836 -3.238754)
		(end 183.038496 -3.800094)
		(stroke
			(width 0.2)
			(type default)
		)
		(layer "In6.Cu")
	)
	(gr_arc
		(start 184.838594 -11.199876)
		(mid 185.399807 -11.76147)
		(end 185.961274 -11.20013)
		(stroke
			(width 0.2)
			(type default)
		)
		(layer "In6.Cu")
	)
	(gr_line
		(start 184.838594 -9.800082)
		(end 184.838594 -11.199876)
		(stroke
			(width 0.2)
			(type default)
		)
		(layer "In6.Cu")
	)
	(gr_arc
		(start 184.838594 -3.999738)
		(mid 185.399807 -4.561332)
		(end 185.961274 -3.999992)
		(stroke
			(width 0.2)
			(type default)
		)
		(layer "In6.Cu")
	)
	(gr_line
		(start 184.838594 -2.600198)
		(end 184.838594 -3.999738)
		(stroke
			(width 0.2)
			(type default)
		)
		(layer "In6.Cu")
	)
	(gr_line
		(start 185.961274 -11.20013)
		(end 185.961274 -9.800082)
		(stroke
			(width 0.2)
			(type default)
		)
		(layer "In6.Cu")
	)
	(gr_arc
		(start 185.961274 -9.800082)
		(mid 185.399934 -9.238742)
		(end 184.838594 -9.800082)
		(stroke
			(width 0.2)
			(type default)
		)
		(layer "In6.Cu")
	)
	(gr_line
		(start 185.961274 -3.999992)
		(end 185.961274 -2.600198)
		(stroke
			(width 0.2)
			(type default)
		)
		(layer "In6.Cu")
	)
	(gr_arc
		(start 185.961274 -2.600198)
		(mid 185.399934 -2.038858)
		(end 184.838594 -2.600198)
		(stroke
			(width 0.2)
			(type default)
		)
		(layer "In6.Cu")
	)
	(gr_arc
		(start 186.638438 -12.399772)
		(mid 187.199651 -12.961366)
		(end 187.761118 -12.400026)
		(stroke
			(width 0.2)
			(type default)
		)
		(layer "In6.Cu")
	)
	(gr_line
		(start 186.638438 -10.999978)
		(end 186.638438 -12.399772)
		(stroke
			(width 0.2)
			(type default)
		)
		(layer "In6.Cu")
	)
	(gr_arc
		(start 186.638438 -5.199888)
		(mid 187.199651 -5.761482)
		(end 187.761118 -5.200142)
		(stroke
			(width 0.2)
			(type default)
		)
		(layer "In6.Cu")
	)
	(gr_line
		(start 186.638438 -3.800094)
		(end 186.638438 -5.199888)
		(stroke
			(width 0.2)
			(type default)
		)
		(layer "In6.Cu")
	)
	(gr_line
		(start 187.761118 -12.400026)
		(end 187.761118 -10.999978)
		(stroke
			(width 0.2)
			(type default)
		)
		(layer "In6.Cu")
	)
	(gr_arc
		(start 187.761118 -10.999978)
		(mid 187.199778 -10.438638)
		(end 186.638438 -10.999978)
		(stroke
			(width 0.2)
			(type default)
		)
		(layer "In6.Cu")
	)
	(gr_line
		(start 187.761118 -5.200142)
		(end 187.761118 -3.800094)
		(stroke
			(width 0.2)
			(type default)
		)
		(layer "In6.Cu")
	)
	(gr_arc
		(start 187.761118 -3.800094)
		(mid 187.199778 -3.238754)
		(end 186.638438 -3.800094)
		(stroke
			(width 0.2)
			(type default)
		)
		(layer "In6.Cu")
	)
	(gr_arc
		(start 188.438536 -11.199876)
		(mid 188.999749 -11.76147)
		(end 189.561216 -11.20013)
		(stroke
			(width 0.2)
			(type default)
		)
		(layer "In6.Cu")
	)
	(gr_line
		(start 188.438536 -9.800082)
		(end 188.438536 -11.199876)
		(stroke
			(width 0.2)
			(type default)
		)
		(layer "In6.Cu")
	)
	(gr_arc
		(start 188.438536 -3.999738)
		(mid 188.999749 -4.561332)
		(end 189.561216 -3.999992)
		(stroke
			(width 0.2)
			(type default)
		)
		(layer "In6.Cu")
	)
	(gr_line
		(start 188.438536 -2.600198)
		(end 188.438536 -3.999738)
		(stroke
			(width 0.2)
			(type default)
		)
		(layer "In6.Cu")
	)
	(gr_line
		(start 189.561216 -11.20013)
		(end 189.561216 -9.800082)
		(stroke
			(width 0.2)
			(type default)
		)
		(layer "In6.Cu")
	)
	(gr_arc
		(start 189.561216 -9.800082)
		(mid 188.999876 -9.238742)
		(end 188.438536 -9.800082)
		(stroke
			(width 0.2)
			(type default)
		)
		(layer "In6.Cu")
	)
	(gr_line
		(start 189.561216 -3.999992)
		(end 189.561216 -2.600198)
		(stroke
			(width 0.2)
			(type default)
		)
		(layer "In6.Cu")
	)
	(gr_arc
		(start 189.561216 -2.600198)
		(mid 188.999876 -2.038858)
		(end 188.438536 -2.600198)
		(stroke
			(width 0.2)
			(type default)
		)
		(layer "In6.Cu")
	)
	(gr_arc
		(start 190.238634 -12.399772)
		(mid 190.799847 -12.961366)
		(end 191.361314 -12.400026)
		(stroke
			(width 0.2)
			(type default)
		)
		(layer "In6.Cu")
	)
	(gr_line
		(start 190.238634 -10.999978)
		(end 190.238634 -12.399772)
		(stroke
			(width 0.2)
			(type default)
		)
		(layer "In6.Cu")
	)
	(gr_arc
		(start 190.238634 -5.199888)
		(mid 190.799847 -5.761482)
		(end 191.361314 -5.200142)
		(stroke
			(width 0.2)
			(type default)
		)
		(layer "In6.Cu")
	)
	(gr_line
		(start 190.238634 -3.800094)
		(end 190.238634 -5.199888)
		(stroke
			(width 0.2)
			(type default)
		)
		(layer "In6.Cu")
	)
	(gr_line
		(start 191.361314 -12.400026)
		(end 191.361314 -10.999978)
		(stroke
			(width 0.2)
			(type default)
		)
		(layer "In6.Cu")
	)
	(gr_arc
		(start 191.361314 -10.999978)
		(mid 190.799974 -10.438638)
		(end 190.238634 -10.999978)
		(stroke
			(width 0.2)
			(type default)
		)
		(layer "In6.Cu")
	)
	(gr_line
		(start 191.361314 -5.200142)
		(end 191.361314 -3.800094)
		(stroke
			(width 0.2)
			(type default)
		)
		(layer "In6.Cu")
	)
	(gr_arc
		(start 191.361314 -3.800094)
		(mid 190.799974 -3.238754)
		(end 190.238634 -3.800094)
		(stroke
			(width 0.2)
			(type default)
		)
		(layer "In6.Cu")
	)
	(gr_arc
		(start 192.038478 -11.199876)
		(mid 192.599691 -11.76147)
		(end 193.161158 -11.20013)
		(stroke
			(width 0.2)
			(type default)
		)
		(layer "In6.Cu")
	)
	(gr_line
		(start 192.038478 -9.800082)
		(end 192.038478 -11.199876)
		(stroke
			(width 0.2)
			(type default)
		)
		(layer "In6.Cu")
	)
	(gr_arc
		(start 192.038478 -3.999738)
		(mid 192.599691 -4.561332)
		(end 193.161158 -3.999992)
		(stroke
			(width 0.2)
			(type default)
		)
		(layer "In6.Cu")
	)
	(gr_line
		(start 192.038478 -2.600198)
		(end 192.038478 -3.999738)
		(stroke
			(width 0.2)
			(type default)
		)
		(layer "In6.Cu")
	)
	(gr_line
		(start 193.161158 -11.20013)
		(end 193.161158 -9.800082)
		(stroke
			(width 0.2)
			(type default)
		)
		(layer "In6.Cu")
	)
	(gr_arc
		(start 193.161158 -9.800082)
		(mid 192.599818 -9.238742)
		(end 192.038478 -9.800082)
		(stroke
			(width 0.2)
			(type default)
		)
		(layer "In6.Cu")
	)
	(gr_line
		(start 193.161158 -3.999992)
		(end 193.161158 -2.600198)
		(stroke
			(width 0.2)
			(type default)
		)
		(layer "In6.Cu")
	)
	(gr_arc
		(start 193.161158 -2.600198)
		(mid 192.599818 -2.038858)
		(end 192.038478 -2.600198)
		(stroke
			(width 0.2)
			(type default)
		)
		(layer "In6.Cu")
	)
	(gr_line
		(start 208.000092 -144.999964)
		(end 127.00254 -144.999964)
		(stroke
			(width 1.524)
			(type default)
		)
		(layer "In6.Cu")
	)
	(gr_arc
		(start 208.000092 -144.999964)
		(mid 209.414297 -144.41418)
		(end 210.000088 -142.999968)
		(stroke
			(width 1.524)
			(type default)
		)
		(layer "In6.Cu")
	)
	(gr_arc
		(start 210.000088 -1.999996)
		(mid 209.414301 -0.585791)
		(end 208.000092 0)
		(stroke
			(width 1.524)
			(type default)
		)
		(layer "In6.Cu")
	)
	(gr_line
		(start 210.000088 -1.999996)
		(end 210.000088 -142.999968)
		(stroke
			(width 1.524)
			(type default)
		)
		(layer "In6.Cu")
	)
	(gr_line
		(start 0 -142.999968)
		(end 0 -1.999996)
		(stroke
			(width 0.05)
			(type default)
		)
		(layer "Edge.Cuts")
	)
	(gr_arc
		(start 0 -142.999968)
		(mid 0.585785 -144.414179)
		(end 1.999996 -144.999964)
		(stroke
			(width 0.05)
			(type default)
		)
		(layer "Edge.Cuts")
	)
	(gr_arc
		(start 1.999996 0)
		(mid 0.585785 -0.585785)
		(end 0 -1.999996)
		(stroke
			(width 0.05)
			(type default)
		)
		(layer "Edge.Cuts")
	)
	(gr_line
		(start 1.999996 0)
		(end 208.000092 0)
		(stroke
			(width 0.05)
			(type default)
		)
		(layer "Edge.Cuts")
	)
	(gr_arc
		(start 7.649972 -131.430014)
		(mid 9.500108 -133.28015)
		(end 11.34999 -131.430014)
		(stroke
			(width 0.05)
			(type default)
		)
		(layer "Edge.Cuts")
	)
	(gr_arc
		(start 8.450072 -135.929878)
		(mid 9.500108 -136.979914)
		(end 10.54989 -135.929878)
		(stroke
			(width 0.05)
			(type default)
		)
		(layer "Edge.Cuts")
	)
	(gr_arc
		(start 8.7249 -126.929896)
		(mid 9.500108 -127.705104)
		(end 10.275062 -126.929896)
		(stroke
			(width 0.05)
			(type default)
		)
		(layer "Edge.Cuts")
	)
	(gr_arc
		(start 10.275062 -126.929896)
		(mid 9.500108 -126.154942)
		(end 8.7249 -126.929896)
		(stroke
			(width 0.05)
			(type default)
		)
		(layer "Edge.Cuts")
	)
	(gr_arc
		(start 10.54989 -135.929878)
		(mid 9.500108 -134.880096)
		(end 8.450072 -135.929878)
		(stroke
			(width 0.05)
			(type default)
		)
		(layer "Edge.Cuts")
	)
	(gr_arc
		(start 11.34999 -131.430014)
		(mid 9.500108 -129.580132)
		(end 7.649972 -131.430014)
		(stroke
			(width 0.05)
			(type default)
		)
		(layer "Edge.Cuts")
	)
	(gr_arc
		(start 28.204922 -9.91997)
		(mid 29.480002 -11.19505)
		(end 30.755082 -9.91997)
		(stroke
			(width 0.05)
			(type default)
		)
		(layer "Edge.Cuts")
	)
	(gr_arc
		(start 28.275026 -3.700018)
		(mid 29.480002 -4.904994)
		(end 30.684978 -3.700018)
		(stroke
			(width 0.05)
			(type default)
		)
		(layer "Edge.Cuts")
	)
	(gr_arc
		(start 30.684978 -3.700018)
		(mid 29.480002 -2.495042)
		(end 28.275026 -3.700018)
		(stroke
			(width 0.05)
			(type default)
		)
		(layer "Edge.Cuts")
	)
	(gr_arc
		(start 30.755082 -9.91997)
		(mid 29.480002 -8.64489)
		(end 28.204922 -9.91997)
		(stroke
			(width 0.05)
			(type default)
		)
		(layer "Edge.Cuts")
	)
	(gr_arc
		(start 73.250044 -134.999984)
		(mid 75.000104 -136.750044)
		(end 76.74991 -134.999984)
		(stroke
			(width 0.05)
			(type default)
		)
		(layer "Edge.Cuts")
	)
	(gr_arc
		(start 76.74991 -134.999984)
		(mid 75.000104 -133.250178)
		(end 73.250044 -134.999984)
		(stroke
			(width 0.05)
			(type default)
		)
		(layer "Edge.Cuts")
	)
	(gr_line
		(start 83.002374 -144.999964)
		(end 1.999996 -144.999964)
		(stroke
			(width 0.05)
			(type default)
		)
		(layer "Edge.Cuts")
	)
	(gr_arc
		(start 83.002374 -144.999964)
		(mid 84.41672 -144.414257)
		(end 85.002624 -142.999968)
		(stroke
			(width 0.05)
			(type default)
		)
		(layer "Edge.Cuts")
	)
	(gr_line
		(start 85.002624 -132.26288)
		(end 85.002624 -142.999968)
		(stroke
			(width 0.05)
			(type default)
		)
		(layer "Edge.Cuts")
	)
	(gr_arc
		(start 89.212674 -127.325628)
		(mid 86.197998 -129.018598)
		(end 85.002624 -132.26288)
		(stroke
			(width 0.05)
			(type default)
		)
		(layer "Edge.Cuts")
	)
	(gr_arc
		(start 93.49994 -39.67988)
		(mid 95.000064 -41.180004)
		(end 96.499934 -39.67988)
		(stroke
			(width 0.05)
			(type default)
		)
		(layer "Edge.Cuts")
	)
	(gr_arc
		(start 96.499934 -39.67988)
		(mid 95.000064 -38.18001)
		(end 93.49994 -39.67988)
		(stroke
			(width 0.05)
			(type default)
		)
		(layer "Edge.Cuts")
	)
	(gr_line
		(start 97.499932 -126.000002)
		(end 89.212674 -127.325628)
		(stroke
			(width 0.05)
			(type default)
		)
		(layer "Edge.Cuts")
	)
	(gr_line
		(start 112.499902 -126.000002)
		(end 97.499932 -126.000002)
		(stroke
			(width 0.05)
			(type default)
		)
		(layer "Edge.Cuts")
	)
	(gr_line
		(start 120.79224 -127.32639)
		(end 112.499902 -126.000002)
		(stroke
			(width 0.05)
			(type default)
		)
		(layer "Edge.Cuts")
	)
	(gr_line
		(start 125.002544 -142.999968)
		(end 125.002544 -132.263642)
		(stroke
			(width 0.05)
			(type default)
		)
		(layer "Edge.Cuts")
	)
	(gr_arc
		(start 125.002544 -142.999968)
		(mid 125.58832 -144.414185)
		(end 127.00254 -144.999964)
		(stroke
			(width 0.05)
			(type default)
		)
		(layer "Edge.Cuts")
	)
	(gr_arc
		(start 125.002544 -132.263642)
		(mid 123.807045 -129.019301)
		(end 120.79224 -127.32639)
		(stroke
			(width 0.05)
			(type default)
		)
		(layer "Edge.Cuts")
	)
	(gr_arc
		(start 133.249924 -134.999984)
		(mid 134.999984 -136.750044)
		(end 136.750044 -134.999984)
		(stroke
			(width 0.05)
			(type default)
		)
		(layer "Edge.Cuts")
	)
	(gr_arc
		(start 133.500114 -94.309946)
		(mid 135.000238 -95.81007)
		(end 136.500108 -94.309946)
		(stroke
			(width 0.05)
			(type default)
		)
		(layer "Edge.Cuts")
	)
	(gr_arc
		(start 136.500108 -94.309946)
		(mid 135.000238 -92.810076)
		(end 133.500114 -94.309946)
		(stroke
			(width 0.05)
			(type default)
		)
		(layer "Edge.Cuts")
	)
	(gr_arc
		(start 136.750044 -134.999984)
		(mid 134.999984 -133.249924)
		(end 133.249924 -134.999984)
		(stroke
			(width 0.05)
			(type default)
		)
		(layer "Edge.Cuts")
	)
	(gr_arc
		(start 149.999954 -29.500068)
		(mid 151.500078 -31.000192)
		(end 152.999948 -29.500068)
		(stroke
			(width 0.05)
			(type default)
		)
		(layer "Edge.Cuts")
	)
	(gr_arc
		(start 152.999948 -29.500068)
		(mid 151.500078 -28.000198)
		(end 149.999954 -29.500068)
		(stroke
			(width 0.05)
			(type default)
		)
		(layer "Edge.Cuts")
	)
	(gr_arc
		(start 197.000114 -50.500026)
		(mid 198.500238 -52.00015)
		(end 200.000108 -50.500026)
		(stroke
			(width 0.05)
			(type default)
		)
		(layer "Edge.Cuts")
	)
	(gr_arc
		(start 198.650098 -131.430014)
		(mid 200.500234 -133.28015)
		(end 202.350116 -131.430014)
		(stroke
			(width 0.05)
			(type default)
		)
		(layer "Edge.Cuts")
	)
	(gr_arc
		(start 199.449944 -135.929878)
		(mid 200.49998 -136.979914)
		(end 201.550016 -135.929878)
		(stroke
			(width 0.05)
			(type default)
		)
		(layer "Edge.Cuts")
	)
	(gr_arc
		(start 199.725026 -126.929896)
		(mid 200.49998 -127.70485)
		(end 201.274934 -126.929896)
		(stroke
			(width 0.05)
			(type default)
		)
		(layer "Edge.Cuts")
	)
	(gr_arc
		(start 200.000108 -50.500026)
		(mid 198.500238 -49.000156)
		(end 197.000114 -50.500026)
		(stroke
			(width 0.05)
			(type default)
		)
		(layer "Edge.Cuts")
	)
	(gr_arc
		(start 201.274934 -126.929896)
		(mid 200.49998 -126.154942)
		(end 199.725026 -126.929896)
		(stroke
			(width 0.05)
			(type default)
		)
		(layer "Edge.Cuts")
	)
	(gr_arc
		(start 201.550016 -135.929878)
		(mid 200.49998 -134.879842)
		(end 199.449944 -135.929878)
		(stroke
			(width 0.05)
			(type default)
		)
		(layer "Edge.Cuts")
	)
	(gr_arc
		(start 202.350116 -131.430014)
		(mid 200.500234 -129.580132)
		(end 198.650098 -131.430014)
		(stroke
			(width 0.05)
			(type default)
		)
		(layer "Edge.Cuts")
	)
	(gr_line
		(start 208.000092 -144.999964)
		(end 127.00254 -144.999964)
		(stroke
			(width 0.05)
			(type default)
		)
		(layer "Edge.Cuts")
	)
	(gr_arc
		(start 208.000092 -144.999964)
		(mid 209.414297 -144.41418)
		(end 210.000088 -142.999968)
		(stroke
			(width 0.05)
			(type default)
		)
		(layer "Edge.Cuts")
	)
	(gr_arc
		(start 210.000088 -1.999996)
		(mid 209.414301 -0.585791)
		(end 208.000092 0)
		(stroke
			(width 0.05)
			(type default)
		)
		(layer "Edge.Cuts")
	)
	(gr_line
		(start 210.000088 -1.999996)
		(end 210.000088 -142.999968)
		(stroke
			(width 0.05)
			(type default)
		)
		(layer "Edge.Cuts")
	)
	(via
		(at 203.327 -59.1185)
		(size 0.6096)
		(drill 0.3048)
		(layers "F.Cu" "B.Cu")
		(net "IOC_BYTE_N")
	)
	(segment
		(start 204.216 -61.849)
		(end 204.037946 -62.027054)
		(width 0.127)
		(layer "B.Cu")
		(net "IOC_BYTE_N")
	)
	(segment
		(start 204.216 -60.0075)
		(end 204.216 -61.849)
		(width 0.127)
		(layer "B.Cu")
		(net "IOC_BYTE_N")
	)
	(segment
		(start 204.037946 -62.027054)
		(end 203.22032 -62.027054)
		(width 0.127)
		(layer "B.Cu")
		(net "IOC_BYTE_N")
	)
	(segment
		(start 203.327 -59.1185)
		(end 202.311 -59.1185)
		(width 0.127)
		(layer "B.Cu")
		(net "IOC_BYTE_N")
	)
	(segment
		(start 201.168 -59.1185)
		(end 202.311 -59.1185)
		(width 0.127)
		(layer "B.Cu")
		(net "IOC_BYTE_N")
	)
	(segment
		(start 203.327 -59.1185)
		(end 204.216 -60.0075)
		(width 0.127)
		(layer "B.Cu")
		(net "IOC_BYTE_N")
	)
	(via
		(at 75.184 -72.898)
		(size 0.6096)
		(drill 0.3048)
		(layers "F.Cu" "B.Cu")
		(net "EXP_BYTE_N")
	)
	(segment
		(start 73.025 -72.7075)
		(end 74.9935 -72.7075)
		(width 0.127)
		(layer "B.Cu")
		(net "EXP_BYTE_N")
	)
	(segment
		(start 75.184 -72.898)
		(end 75.184 -74.71918)
		(width 0.127)
		(layer "B.Cu")
		(net "EXP_BYTE_N")
	)
	(segment
		(start 74.9935 -72.7075)
		(end 75.184 -72.898)
		(width 0.127)
		(layer "B.Cu")
		(net "EXP_BYTE_N")
	)
	(segment
		(start 75.184 -74.71918)
		(end 75.26782 -74.803)
		(width 0.127)
		(layer "B.Cu")
		(net "EXP_BYTE_N")
	)
	(segment
		(start 71.882 -72.7075)
		(end 73.025 -72.7075)
		(width 0.127)
		(layer "B.Cu")
		(net "EXP_BYTE_N")
	)
	(segment
		(start 75.26782 -74.803)
		(end 75.26782 -75.6031)
		(width 0.127)
		(layer "B.Cu")
		(net "EXP_BYTE_N")
	)
	(segment
		(start 169.934382 -88.142572)
		(end 169.934382 -89.090754)
		(width 0.508)
		(layer "F.Cu")
		(net "VT235_VX_R")
	)
	(segment
		(start 169.934382 -89.090754)
		(end 169.574718 -89.450418)
		(width 0.508)
		(layer "F.Cu")
		(net "VT235_VX_R")
	)
	(segment
		(start 83.80095 -106.429048)
		(end 83.954874 -106.275124)
		(width 0.127)
		(layer "F.Cu")
		(net "SCC_FULL_PWR_EN_U48")
	)
	(segment
		(start 83.954874 -105.775506)
		(end 83.954874 -104.803194)
		(width 0.127)
		(layer "F.Cu")
		(net "SCC_FULL_PWR_EN_U48")
	)
	(segment
		(start 83.954874 -106.275124)
		(end 83.954874 -105.775506)
		(width 0.127)
		(layer "F.Cu")
		(net "SCC_FULL_PWR_EN_U48")
	)
	(segment
		(start 83.80095 -109.006894)
		(end 83.80095 -106.429048)
		(width 0.127)
		(layer "F.Cu")
		(net "SCC_FULL_PWR_EN_U48")
	)
	(via
		(at 83.954874 -105.775506)
		(size 0.6604)
		(drill 0.3302)
		(layers "F.Cu" "B.Cu")
		(net "SCC_FULL_PWR_EN_U48")
	)
	(segment
		(start 82.825082 -105.756964)
		(end 82.825082 -106.315256)
		(width 0.127)
		(layer "F.Cu")
		(net "SCC_FULL_PWR_BUF_EN_U48")
	)
	(segment
		(start 82.825082 -106.315256)
		(end 83.15071 -106.640884)
		(width 0.127)
		(layer "F.Cu")
		(net "SCC_FULL_PWR_BUF_EN_U48")
	)
	(segment
		(start 82.825082 -104.804464)
		(end 82.825082 -105.756964)
		(width 0.127)
		(layer "F.Cu")
		(net "SCC_FULL_PWR_BUF_EN_U48")
	)
	(segment
		(start 83.15071 -106.640884)
		(end 83.15071 -107.355894)
		(width 0.127)
		(layer "F.Cu")
		(net "SCC_FULL_PWR_BUF_EN_U48")
	)
	(via
		(at 82.825082 -105.756964)
		(size 0.6604)
		(drill 0.3302)
		(layers "F.Cu" "B.Cu")
		(net "SCC_FULL_PWR_BUF_EN_U48")
	)
	(segment
		(start 172.326808 -51.726846)
		(end 172.326808 -52.804568)
		(width 0.127)
		(layer "F.Cu")
		(net "PG_CORE")
	)
	(segment
		(start 171.96689 -54.663594)
		(end 171.517056 -55.113428)
		(width 0.127)
		(layer "F.Cu")
		(net "PG_CORE")
	)
	(segment
		(start 171.96689 -53.164486)
		(end 171.96689 -54.663594)
		(width 0.127)
		(layer "F.Cu")
		(net "PG_CORE")
	)
	(segment
		(start 172.326808 -52.804568)
		(end 171.96689 -53.164486)
		(width 0.127)
		(layer "F.Cu")
		(net "PG_CORE")
	)
	(segment
		(start 172.199808 -51.599846)
		(end 172.326808 -51.726846)
		(width 0.127)
		(layer "F.Cu")
		(net "PG_CORE")
	)
	(via
		(at 88.877394 -34.786316)
		(size 0.508)
		(drill 0.254)
		(layers "F.Cu" "B.Cu")
		(net "SCC_RESET_N")
	)
	(via
		(at 159.203644 -7.931658)
		(size 0.508)
		(drill 0.254)
		(layers "F.Cu" "B.Cu")
		(net "SCC_RESET_N")
	)
	(via
		(at 160.985962 -7.048246)
		(size 0.6096)
		(drill 0.3048)
		(layers "F.Cu" "B.Cu")
		(net "SCC_RESET_N")
	)
	(via
		(at 83.749388 -24.021796)
		(size 0.508)
		(drill 0.254)
		(layers "F.Cu" "B.Cu")
		(net "SCC_RESET_N")
	)
	(segment
		(start 168.1988 -8.509)
		(end 168.0464 -8.6614)
		(width 0.127)
		(layer "B.Cu")
		(net "SCC_RESET_N")
	)
	(segment
		(start 160.531302 -7.502906)
		(end 159.632396 -7.502906)
		(width 0.127)
		(layer "B.Cu")
		(net "SCC_RESET_N")
	)
	(segment
		(start 167.170608 -6.5278)
		(end 168.1988 -7.555992)
		(width 0.127)
		(layer "B.Cu")
		(net "SCC_RESET_N")
	)
	(segment
		(start 164.488622 -6.5278)
		(end 167.170608 -6.5278)
		(width 0.127)
		(layer "B.Cu")
		(net "SCC_RESET_N")
	)
	(segment
		(start 159.632396 -7.502906)
		(end 159.203644 -7.931658)
		(width 0.127)
		(layer "B.Cu")
		(net "SCC_RESET_N")
	)
	(segment
		(start 160.985962 -7.048246)
		(end 160.531302 -7.502906)
		(width 0.127)
		(layer "B.Cu")
		(net "SCC_RESET_N")
	)
	(segment
		(start 160.985962 -7.035038)
		(end 160.985962 -7.048246)
		(width 0.127)
		(layer "B.Cu")
		(net "SCC_RESET_N")
	)
	(segment
		(start 163.75634 -5.795518)
		(end 164.488622 -6.5278)
		(width 0.127)
		(layer "B.Cu")
		(net "SCC_RESET_N")
	)
	(segment
		(start 163.75634 -5.795518)
		(end 162.225482 -5.795518)
		(width 0.127)
		(layer "B.Cu")
		(net "SCC_RESET_N")
	)
	(segment
		(start 162.225482 -5.795518)
		(end 160.985962 -7.035038)
		(width 0.127)
		(layer "B.Cu")
		(net "SCC_RESET_N")
	)
	(segment
		(start 168.1988 -7.555992)
		(end 168.1988 -8.509)
		(width 0.127)
		(layer "B.Cu")
		(net "SCC_RESET_N")
	)
	(segment
		(start 168.0464 -8.6614)
		(end 167.161464 -8.6614)
		(width 0.127)
		(layer "B.Cu")
		(net "SCC_RESET_N")
	)
	(segment
		(start 101.541072 -13.465302)
		(end 101.540818 -13.465048)
		(width 0.127)
		(layer "In2.Cu")
		(net "SCC_RESET_N")
	)
	(segment
		(start 88.883998 -34.79292)
		(end 121.547382 -34.79292)
		(width 0.127)
		(layer "In2.Cu")
		(net "SCC_RESET_N")
	)
	(segment
		(start 101.540818 -13.465048)
		(end 101.540818 -8.259572)
		(width 0.127)
		(layer "In2.Cu")
		(net "SCC_RESET_N")
	)
	(segment
		(start 83.749388 -24.021796)
		(end 84.257388 -23.513796)
		(width 0.127)
		(layer "In2.Cu")
		(net "SCC_RESET_N")
	)
	(segment
		(start 137.319258 -19.021044)
		(end 148.114258 -19.021044)
		(width 0.127)
		(layer "In2.Cu")
		(net "SCC_RESET_N")
	)
	(segment
		(start 84.257388 -23.513796)
		(end 91.913202 -23.513796)
		(width 0.127)
		(layer "In2.Cu")
		(net "SCC_RESET_N")
	)
	(segment
		(start 101.541072 -13.885926)
		(end 101.541072 -13.465302)
		(width 0.127)
		(layer "In2.Cu")
		(net "SCC_RESET_N")
	)
	(segment
		(start 121.547382 -34.79292)
		(end 137.319258 -19.021044)
		(width 0.127)
		(layer "In2.Cu")
		(net "SCC_RESET_N")
	)
	(segment
		(start 88.877394 -34.786316)
		(end 88.883998 -34.79292)
		(width 0.127)
		(layer "In2.Cu")
		(net "SCC_RESET_N")
	)
	(segment
		(start 91.913202 -23.513796)
		(end 101.541072 -13.885926)
		(width 0.127)
		(layer "In2.Cu")
		(net "SCC_RESET_N")
	)
	(segment
		(start 101.540818 -8.259572)
		(end 102.200202 -7.600188)
		(width 0.127)
		(layer "In2.Cu")
		(net "SCC_RESET_N")
	)
	(segment
		(start 148.114258 -19.021044)
		(end 159.203644 -7.931658)
		(width 0.127)
		(layer "In2.Cu")
		(net "SCC_RESET_N")
	)
	(segment
		(start 88.877394 -34.786316)
		(end 88.877394 -29.149802)
		(width 0.127)
		(layer "In5.Cu")
		(net "SCC_RESET_N")
	)
	(segment
		(start 88.877394 -29.149802)
		(end 83.749388 -24.021796)
		(width 0.127)
		(layer "In5.Cu")
		(net "SCC_RESET_N")
	)
	(segment
		(start 92.974668 -80.884522)
		(end 93.168978 -81.078832)
		(width 0.127)
		(layer "F.Cu")
		(net "SCC_RESET_LS_R_N")
	)
	(segment
		(start 92.3036 -80.2132)
		(end 92.3036 -80.213454)
		(width 0.127)
		(layer "F.Cu")
		(net "SCC_RESET_LS_R_N")
	)
	(segment
		(start 93.168978 -81.078832)
		(end 93.95206 -81.078832)
		(width 0.127)
		(layer "F.Cu")
		(net "SCC_RESET_LS_R_N")
	)
	(segment
		(start 92.3036 -80.213454)
		(end 92.974668 -80.884522)
		(width 0.127)
		(layer "F.Cu")
		(net "SCC_RESET_LS_R_N")
	)
	(segment
		(start 93.95206 -81.078832)
		(end 94.216728 -81.3435)
		(width 0.127)
		(layer "F.Cu")
		(net "SCC_RESET_LS_R_N")
	)
	(via
		(at 92.974668 -80.884522)
		(size 0.6604)
		(drill 0.3302)
		(layers "F.Cu" "B.Cu")
		(net "SCC_RESET_LS_R_N")
	)
	(via
		(at 92.3036 -80.2132)
		(size 0.508)
		(drill 0.254)
		(layers "F.Cu" "B.Cu")
		(net "SCC_RESET_LS_R_N")
	)
	(segment
		(start 92.97416 -80.88376)
		(end 92.97416 -81.52511)
		(width 0.127)
		(layer "B.Cu")
		(net "SCC_RESET_LS_R_N")
	)
	(segment
		(start 92.3036 -80.2132)
		(end 92.97416 -80.88376)
		(width 0.127)
		(layer "B.Cu")
		(net "SCC_RESET_LS_R_N")
	)
	(segment
		(start 94.216728 -82.2325)
		(end 94.216728 -83.439762)
		(width 0.127)
		(layer "F.Cu")
		(net "SCC_RESET_LS_N")
	)
	(segment
		(start 164.364162 -4.692904)
		(end 163.489894 -5.567172)
		(width 0.127)
		(layer "F.Cu")
		(net "SCC_RESET_LS_N")
	)
	(segment
		(start 93.5355 -82.2325)
		(end 93.06814 -82.69986)
		(width 0.127)
		(layer "F.Cu")
		(net "SCC_RESET_LS_N")
	)
	(segment
		(start 163.489894 -5.567172)
		(end 163.489894 -6.418072)
		(width 0.127)
		(layer "F.Cu")
		(net "SCC_RESET_LS_N")
	)
	(segment
		(start 94.216728 -82.2325)
		(end 93.5355 -82.2325)
		(width 0.127)
		(layer "F.Cu")
		(net "SCC_RESET_LS_N")
	)
	(segment
		(start 164.364162 -3.546856)
		(end 164.364162 -4.692904)
		(width 0.127)
		(layer "F.Cu")
		(net "SCC_RESET_LS_N")
	)
	(segment
		(start 91.94546 -82.69986)
		(end 91.5162 -82.2706)
		(width 0.127)
		(layer "F.Cu")
		(net "SCC_RESET_LS_N")
	)
	(segment
		(start 93.06814 -82.69986)
		(end 92.607384 -82.69986)
		(width 0.127)
		(layer "F.Cu")
		(net "SCC_RESET_LS_N")
	)
	(segment
		(start 92.607384 -82.69986)
		(end 91.94546 -82.69986)
		(width 0.127)
		(layer "F.Cu")
		(net "SCC_RESET_LS_N")
	)
	(via
		(at 164.364162 -3.546856)
		(size 0.508)
		(drill 0.254)
		(layers "F.Cu" "B.Cu")
		(net "SCC_RESET_LS_N")
	)
	(via
		(at 91.5162 -82.2706)
		(size 0.508)
		(drill 0.254)
		(layers "F.Cu" "B.Cu")
		(net "SCC_RESET_LS_N")
	)
	(via
		(at 92.607384 -82.69986)
		(size 0.6604)
		(drill 0.3302)
		(layers "F.Cu" "B.Cu")
		(net "SCC_RESET_LS_N")
	)
	(segment
		(start 96.516952 -82.2706)
		(end 91.5162 -82.2706)
		(width 0.127)
		(layer "In5.Cu")
		(net "SCC_RESET_LS_N")
	)
	(segment
		(start 150.873206 -58.12536)
		(end 150.873206 -64.647318)
		(width 0.127)
		(layer "In5.Cu")
		(net "SCC_RESET_LS_N")
	)
	(segment
		(start 109.836712 -78.606396)
		(end 109.606334 -78.836774)
		(width 0.127)
		(layer "In5.Cu")
		(net "SCC_RESET_LS_N")
	)
	(segment
		(start 111.004858 -75.438254)
		(end 110.5916 -75.851512)
		(width 0.127)
		(layer "In5.Cu")
		(net "SCC_RESET_LS_N")
	)
	(segment
		(start 155.900628 -6.48843)
		(end 155.900628 -31.293308)
		(width 0.127)
		(layer "In5.Cu")
		(net "SCC_RESET_LS_N")
	)
	(segment
		(start 113.22685 -74.606404)
		(end 112.395 -75.438254)
		(width 0.127)
		(layer "In5.Cu")
		(net "SCC_RESET_LS_N")
	)
	(segment
		(start 110.5916 -77.965554)
		(end 109.950758 -78.606396)
		(width 0.127)
		(layer "In5.Cu")
		(net "SCC_RESET_LS_N")
	)
	(segment
		(start 106.52379 -82.03311)
		(end 105.950512 -82.606388)
		(width 0.127)
		(layer "In5.Cu")
		(net "SCC_RESET_LS_N")
	)
	(segment
		(start 108.606336 -79.950818)
		(end 107.950762 -80.606392)
		(width 0.127)
		(layer "In5.Cu")
		(net "SCC_RESET_LS_N")
	)
	(segment
		(start 141.697964 -73.82256)
		(end 135.419338 -73.82256)
		(width 0.127)
		(layer "In5.Cu")
		(net "SCC_RESET_LS_N")
	)
	(segment
		(start 106.52379 -81.919064)
		(end 106.52379 -82.03311)
		(width 0.127)
		(layer "In5.Cu")
		(net "SCC_RESET_LS_N")
	)
	(segment
		(start 119.4816 -75.6031)
		(end 118.484904 -74.606404)
		(width 0.127)
		(layer "In5.Cu")
		(net "SCC_RESET_LS_N")
	)
	(segment
		(start 109.606334 -78.95082)
		(end 108.95076 -79.606394)
		(width 0.127)
		(layer "In5.Cu")
		(net "SCC_RESET_LS_N")
	)
	(segment
		(start 107.950762 -80.606392)
		(end 107.836716 -80.606392)
		(width 0.127)
		(layer "In5.Cu")
		(net "SCC_RESET_LS_N")
	)
	(segment
		(start 107.4674 -80.975708)
		(end 107.4674 -81.089754)
		(width 0.127)
		(layer "In5.Cu")
		(net "SCC_RESET_LS_N")
	)
	(segment
		(start 120.898158 -75.6031)
		(end 119.4816 -75.6031)
		(width 0.127)
		(layer "In5.Cu")
		(net "SCC_RESET_LS_N")
	)
	(segment
		(start 158.549594 -3.839464)
		(end 155.900628 -6.48843)
		(width 0.127)
		(layer "In5.Cu")
		(net "SCC_RESET_LS_N")
	)
	(segment
		(start 152.242774 -41.406064)
		(end 152.242774 -56.755792)
		(width 0.127)
		(layer "In5.Cu")
		(net "SCC_RESET_LS_N")
	)
	(segment
		(start 104.871774 -83.68538)
		(end 97.931732 -83.68538)
		(width 0.127)
		(layer "In5.Cu")
		(net "SCC_RESET_LS_N")
	)
	(segment
		(start 162.296094 -3.839464)
		(end 158.549594 -3.839464)
		(width 0.127)
		(layer "In5.Cu")
		(net "SCC_RESET_LS_N")
	)
	(segment
		(start 118.484904 -74.606404)
		(end 113.22685 -74.606404)
		(width 0.127)
		(layer "In5.Cu")
		(net "SCC_RESET_LS_N")
	)
	(segment
		(start 163.099496 -3.036062)
		(end 162.296094 -3.839464)
		(width 0.127)
		(layer "In5.Cu")
		(net "SCC_RESET_LS_N")
	)
	(segment
		(start 106.987594 -81.56956)
		(end 106.873294 -81.56956)
		(width 0.127)
		(layer "In5.Cu")
		(net "SCC_RESET_LS_N")
	)
	(segment
		(start 132.820156 -76.421742)
		(end 121.7168 -76.421742)
		(width 0.127)
		(layer "In5.Cu")
		(net "SCC_RESET_LS_N")
	)
	(segment
		(start 152.242774 -56.755792)
		(end 150.873206 -58.12536)
		(width 0.127)
		(layer "In5.Cu")
		(net "SCC_RESET_LS_N")
	)
	(segment
		(start 97.931732 -83.68538)
		(end 96.516952 -82.2706)
		(width 0.127)
		(layer "In5.Cu")
		(net "SCC_RESET_LS_N")
	)
	(segment
		(start 164.364162 -3.546856)
		(end 163.853368 -3.036062)
		(width 0.127)
		(layer "In5.Cu")
		(net "SCC_RESET_LS_N")
	)
	(segment
		(start 121.7168 -76.421742)
		(end 120.898158 -75.6031)
		(width 0.127)
		(layer "In5.Cu")
		(net "SCC_RESET_LS_N")
	)
	(segment
		(start 108.836714 -79.606394)
		(end 108.606336 -79.836772)
		(width 0.127)
		(layer "In5.Cu")
		(net "SCC_RESET_LS_N")
	)
	(segment
		(start 105.606342 -82.950812)
		(end 104.871774 -83.68538)
		(width 0.127)
		(layer "In5.Cu")
		(net "SCC_RESET_LS_N")
	)
	(segment
		(start 153.657808 -39.99103)
		(end 152.242774 -41.406064)
		(width 0.127)
		(layer "In5.Cu")
		(net "SCC_RESET_LS_N")
	)
	(segment
		(start 105.950512 -82.606388)
		(end 105.83672 -82.606388)
		(width 0.127)
		(layer "In5.Cu")
		(net "SCC_RESET_LS_N")
	)
	(segment
		(start 106.873294 -81.56956)
		(end 106.52379 -81.919064)
		(width 0.127)
		(layer "In5.Cu")
		(net "SCC_RESET_LS_N")
	)
	(segment
		(start 155.900628 -31.293308)
		(end 153.657808 -33.536128)
		(width 0.127)
		(layer "In5.Cu")
		(net "SCC_RESET_LS_N")
	)
	(segment
		(start 135.419338 -73.82256)
		(end 132.820156 -76.421742)
		(width 0.127)
		(layer "In5.Cu")
		(net "SCC_RESET_LS_N")
	)
	(segment
		(start 105.606342 -82.836766)
		(end 105.606342 -82.950812)
		(width 0.127)
		(layer "In5.Cu")
		(net "SCC_RESET_LS_N")
	)
	(segment
		(start 108.606336 -79.836772)
		(end 108.606336 -79.950818)
		(width 0.127)
		(layer "In5.Cu")
		(net "SCC_RESET_LS_N")
	)
	(segment
		(start 105.83672 -82.606388)
		(end 105.606342 -82.836766)
		(width 0.127)
		(layer "In5.Cu")
		(net "SCC_RESET_LS_N")
	)
	(segment
		(start 107.4674 -81.089754)
		(end 106.987594 -81.56956)
		(width 0.127)
		(layer "In5.Cu")
		(net "SCC_RESET_LS_N")
	)
	(segment
		(start 109.606334 -78.836774)
		(end 109.606334 -78.95082)
		(width 0.127)
		(layer "In5.Cu")
		(net "SCC_RESET_LS_N")
	)
	(segment
		(start 112.395 -75.438254)
		(end 111.004858 -75.438254)
		(width 0.127)
		(layer "In5.Cu")
		(net "SCC_RESET_LS_N")
	)
	(segment
		(start 150.873206 -64.647318)
		(end 141.697964 -73.82256)
		(width 0.127)
		(layer "In5.Cu")
		(net "SCC_RESET_LS_N")
	)
	(segment
		(start 108.95076 -79.606394)
		(end 108.836714 -79.606394)
		(width 0.127)
		(layer "In5.Cu")
		(net "SCC_RESET_LS_N")
	)
	(segment
		(start 107.836716 -80.606392)
		(end 107.4674 -80.975708)
		(width 0.127)
		(layer "In5.Cu")
		(net "SCC_RESET_LS_N")
	)
	(segment
		(start 163.853368 -3.036062)
		(end 163.099496 -3.036062)
		(width 0.127)
		(layer "In5.Cu")
		(net "SCC_RESET_LS_N")
	)
	(segment
		(start 153.657808 -33.536128)
		(end 153.657808 -39.99103)
		(width 0.127)
		(layer "In5.Cu")
		(net "SCC_RESET_LS_N")
	)
	(segment
		(start 110.5916 -75.851512)
		(end 110.5916 -77.965554)
		(width 0.127)
		(layer "In5.Cu")
		(net "SCC_RESET_LS_N")
	)
	(segment
		(start 109.950758 -78.606396)
		(end 109.836712 -78.606396)
		(width 0.127)
		(layer "In5.Cu")
		(net "SCC_RESET_LS_N")
	)
	(segment
		(start 163.7538 -11.223498)
		(end 163.889944 -11.359642)
		(width 0.127)
		(layer "F.Cu")
		(net "SCC_RESET_BUF_N")
	)
	(segment
		(start 163.889944 -11.359642)
		(end 163.889944 -12.056872)
		(width 0.127)
		(layer "F.Cu")
		(net "SCC_RESET_BUF_N")
	)
	(segment
		(start 162.665664 -8.028686)
		(end 163.7538 -9.116822)
		(width 0.127)
		(layer "F.Cu")
		(net "SCC_RESET_BUF_N")
	)
	(segment
		(start 163.7538 -9.116822)
		(end 163.7538 -11.223498)
		(width 0.127)
		(layer "F.Cu")
		(net "SCC_RESET_BUF_N")
	)
	(via
		(at 162.5346 -6.8834)
		(size 0.6096)
		(drill 0.3048)
		(layers "F.Cu" "B.Cu")
		(net "SCC_RESET_BUF_N")
	)
	(via
		(at 162.665664 -8.028686)
		(size 0.508)
		(drill 0.254)
		(layers "F.Cu" "B.Cu")
		(net "SCC_RESET_BUF_N")
	)
	(segment
		(start 162.665664 -7.558786)
		(end 162.665664 -8.028686)
		(width 0.127)
		(layer "B.Cu")
		(net "SCC_RESET_BUF_N")
	)
	(segment
		(start 165.510464 -7.271258)
		(end 165.322504 -7.083298)
		(width 0.127)
		(layer "B.Cu")
		(net "SCC_RESET_BUF_N")
	)
	(segment
		(start 162.5346 -6.8834)
		(end 162.5346 -7.427722)
		(width 0.127)
		(layer "B.Cu")
		(net "SCC_RESET_BUF_N")
	)
	(segment
		(start 164.15512 -7.083298)
		(end 163.75634 -6.684518)
		(width 0.127)
		(layer "B.Cu")
		(net "SCC_RESET_BUF_N")
	)
	(segment
		(start 162.5346 -7.427722)
		(end 162.665664 -7.558786)
		(width 0.127)
		(layer "B.Cu")
		(net "SCC_RESET_BUF_N")
	)
	(segment
		(start 163.75634 -6.684518)
		(end 162.733482 -6.684518)
		(width 0.127)
		(layer "B.Cu")
		(net "SCC_RESET_BUF_N")
	)
	(segment
		(start 165.322504 -7.083298)
		(end 164.15512 -7.083298)
		(width 0.127)
		(layer "B.Cu")
		(net "SCC_RESET_BUF_N")
	)
	(segment
		(start 165.510464 -8.01116)
		(end 165.510464 -7.271258)
		(width 0.127)
		(layer "B.Cu")
		(net "SCC_RESET_BUF_N")
	)
	(segment
		(start 162.733482 -6.684518)
		(end 162.5346 -6.8834)
		(width 0.127)
		(layer "B.Cu")
		(net "SCC_RESET_BUF_N")
	)
	(segment
		(start 10.52195 -66.52895)
		(end 10.5283 -66.5226)
		(width 0.127)
		(layer "F.Cu")
		(net "SCC_HSC_N")
	)
	(segment
		(start 10.5283 -66.5226)
		(end 10.5283 -65.145666)
		(width 0.127)
		(layer "F.Cu")
		(net "SCC_HSC_N")
	)
	(segment
		(start 9.0551 -66.52895)
		(end 10.52195 -66.52895)
		(width 0.127)
		(layer "F.Cu")
		(net "SCC_HSC_N")
	)
	(segment
		(start 9.517126 -63.923672)
		(end 9.517126 -63.57112)
		(width 0.127)
		(layer "F.Cu")
		(net "SCC_HSC_N")
	)
	(segment
		(start 10.5283 -65.145666)
		(end 10.5283 -64.934846)
		(width 0.127)
		(layer "F.Cu")
		(net "SCC_HSC_N")
	)
	(segment
		(start 10.5283 -64.934846)
		(end 9.517126 -63.923672)
		(width 0.127)
		(layer "F.Cu")
		(net "SCC_HSC_N")
	)
	(via
		(at 91.432126 -31.62554)
		(size 0.508)
		(drill 0.254)
		(layers "F.Cu" "B.Cu")
		(net "SCC_HSC_N")
	)
	(via
		(at 10.5283 -65.145666)
		(size 0.6604)
		(drill 0.3302)
		(layers "F.Cu" "B.Cu")
		(net "SCC_HSC_N")
	)
	(via
		(at 9.517126 -63.57112)
		(size 0.508)
		(drill 0.254)
		(layers "F.Cu" "B.Cu")
		(net "SCC_HSC_N")
	)
	(segment
		(start 148.0312 -7.544054)
		(end 148.999956 -6.575298)
		(width 0.254)
		(layer "In2.Cu")
		(net "SCC_HSC_N")
	)
	(segment
		(start 148.999956 -6.575298)
		(end 148.999956 -6.20014)
		(width 0.254)
		(layer "In2.Cu")
		(net "SCC_HSC_N")
	)
	(segment
		(start 145.98904 -16.383)
		(end 148.0312 -14.34084)
		(width 0.254)
		(layer "In2.Cu")
		(net "SCC_HSC_N")
	)
	(segment
		(start 148.0312 -14.34084)
		(end 148.0312 -7.544054)
		(width 0.254)
		(layer "In2.Cu")
		(net "SCC_HSC_N")
	)
	(segment
		(start 120.90146 -31.62554)
		(end 136.144 -16.383)
		(width 0.254)
		(layer "In2.Cu")
		(net "SCC_HSC_N")
	)
	(segment
		(start 91.432126 -31.62554)
		(end 120.90146 -31.62554)
		(width 0.254)
		(layer "In2.Cu")
		(net "SCC_HSC_N")
	)
	(segment
		(start 136.144 -16.383)
		(end 145.98904 -16.383)
		(width 0.254)
		(layer "In2.Cu")
		(net "SCC_HSC_N")
	)
	(segment
		(start 77.4192 -10.2362)
		(end 58.272172 -10.2362)
		(width 0.254)
		(layer "In5.Cu")
		(net "SCC_HSC_N")
	)
	(segment
		(start 20.018756 -62.46622)
		(end 10.622026 -62.46622)
		(width 0.254)
		(layer "In5.Cu")
		(net "SCC_HSC_N")
	)
	(segment
		(start 91.5416 -24.3586)
		(end 77.4192 -10.2362)
		(width 0.254)
		(layer "In5.Cu")
		(net "SCC_HSC_N")
	)
	(segment
		(start 91.5416 -31.516066)
		(end 91.5416 -24.3586)
		(width 0.254)
		(layer "In5.Cu")
		(net "SCC_HSC_N")
	)
	(segment
		(start 45.419264 -23.089108)
		(end 33.778698 -23.089108)
		(width 0.254)
		(layer "In5.Cu")
		(net "SCC_HSC_N")
	)
	(segment
		(start 58.272172 -10.2362)
		(end 45.419264 -23.089108)
		(width 0.254)
		(layer "In5.Cu")
		(net "SCC_HSC_N")
	)
	(segment
		(start 30.7086 -34.22904)
		(end 25.091136 -39.846504)
		(width 0.254)
		(layer "In5.Cu")
		(net "SCC_HSC_N")
	)
	(segment
		(start 91.432126 -31.62554)
		(end 91.5416 -31.516066)
		(width 0.254)
		(layer "In5.Cu")
		(net "SCC_HSC_N")
	)
	(segment
		(start 25.091136 -39.846504)
		(end 25.091136 -57.39384)
		(width 0.254)
		(layer "In5.Cu")
		(net "SCC_HSC_N")
	)
	(segment
		(start 30.7086 -26.159206)
		(end 30.7086 -34.22904)
		(width 0.254)
		(layer "In5.Cu")
		(net "SCC_HSC_N")
	)
	(segment
		(start 33.778698 -23.089108)
		(end 30.7086 -26.159206)
		(width 0.254)
		(layer "In5.Cu")
		(net "SCC_HSC_N")
	)
	(segment
		(start 25.091136 -57.39384)
		(end 20.018756 -62.46622)
		(width 0.254)
		(layer "In5.Cu")
		(net "SCC_HSC_N")
	)
	(segment
		(start 10.622026 -62.46622)
		(end 9.517126 -63.57112)
		(width 0.254)
		(layer "In5.Cu")
		(net "SCC_HSC_N")
	)
	(segment
		(start 108.49991 -74.500232)
		(end 108.000038 -75.000104)
		(width 0.127)
		(layer "F.Cu")
		(net "LED8")
	)
	(via
		(at 108.000038 -75.000104)
		(size 0.4572)
		(drill 0.2032)
		(layers "F.Cu" "B.Cu")
		(net "LED8")
	)
	(segment
		(start 107.498134 -74.4982)
		(end 108.000038 -75.000104)
		(width 0.127)
		(layer "B.Cu")
		(net "LED8")
	)
	(segment
		(start 94.398592 -85.095842)
		(end 94.398592 -84.324952)
		(width 0.127)
		(layer "B.Cu")
		(net "ICE_RESET_N")
	)
	(segment
		(start 94.398592 -86.63178)
		(end 94.398592 -85.095842)
		(width 0.127)
		(layer "B.Cu")
		(net "ICE_RESET_N")
	)
	(segment
		(start 94.398592 -84.324952)
		(end 94.27464 -84.201)
		(width 0.127)
		(layer "B.Cu")
		(net "ICE_RESET_N")
	)
	(segment
		(start 94.27464 -84.201)
		(end 94.27464 -83.57489)
		(width 0.127)
		(layer "B.Cu")
		(net "ICE_RESET_N")
	)
	(via
		(at 161.925 -89.789)
		(size 0.6604)
		(drill 0.3302)
		(layers "F.Cu" "B.Cu")
		(net "P12V_SYBY_VDD_U6")
	)
	(via
		(at 161.925 -92.0496)
		(size 0.508)
		(drill 0.254)
		(layers "F.Cu" "B.Cu")
		(net "P12V_SYBY_VDD_U6")
	)
	(via
		(at 161.925 -92.9386)
		(size 0.508)
		(drill 0.254)
		(layers "F.Cu" "B.Cu")
		(net "P12V_SYBY_VDD_U6")
	)
	(via
		(at 158.5976 -113.3094)
		(size 0.7112)
		(drill 0.4064)
		(layers "F.Cu" "B.Cu")
		(net "P12V_STBY_VIN_U11")
	)
	(via
		(at 159.8168 -113.3094)
		(size 0.7112)
		(drill 0.4064)
		(layers "F.Cu" "B.Cu")
		(net "P12V_STBY_VIN_U11")
	)
	(via
		(at 160.8074 -114.173)
		(size 0.6604)
		(drill 0.3302)
		(layers "F.Cu" "B.Cu")
		(net "P12V_STBY_VIN_U11")
	)
	(via
		(at 157.3784 -113.3094)
		(size 0.7112)
		(drill 0.4064)
		(layers "F.Cu" "B.Cu")
		(net "P12V_STBY_VIN_U11")
	)
	(via
		(at 63.043816 -94.566486)
		(size 0.6604)
		(drill 0.3302)
		(layers "F.Cu" "B.Cu")
		(net "P12V_STBY_VIN_U10")
	)
	(via
		(at 61.890656 -93.71965)
		(size 0.6604)
		(drill 0.3302)
		(layers "F.Cu" "B.Cu")
		(net "P12V_STBY_VIN_U10")
	)
	(via
		(at 61.8236 -96.17583)
		(size 0.6604)
		(drill 0.3302)
		(layers "F.Cu" "B.Cu")
		(net "P12V_STBY_VIN_U10")
	)
	(via
		(at 43.538394 -46.810168)
		(size 0.6604)
		(drill 0.3302)
		(layers "F.Cu" "B.Cu")
		(net "P12V_STBY_VIN_Q7")
	)
	(via
		(at 36.48837 -44.283376)
		(size 0.6604)
		(drill 0.3302)
		(layers "F.Cu" "B.Cu")
		(net "P12V_STBY_VIN_Q7")
	)
	(via
		(at 41.280842 -46.642274)
		(size 0.6604)
		(drill 0.3302)
		(layers "F.Cu" "B.Cu")
		(net "P12V_STBY_VIN_Q7")
	)
	(via
		(at 39.07917 -46.810168)
		(size 0.6604)
		(drill 0.3302)
		(layers "F.Cu" "B.Cu")
		(net "P12V_STBY_VIN_Q7")
	)
	(segment
		(start 157.242002 -116.849398)
		(end 155.966922 -116.849398)
		(width 0.254)
		(layer "F.Cu")
		(net "P12V_STBY_VDD_U11")
	)
	(segment
		(start 157.6324 -116.459)
		(end 157.242002 -116.849398)
		(width 0.254)
		(layer "F.Cu")
		(net "P12V_STBY_VDD_U11")
	)
	(via
		(at 157.6324 -116.459)
		(size 0.508)
		(drill 0.254)
		(layers "F.Cu" "B.Cu")
		(net "P12V_STBY_VDD_U11")
	)
	(via
		(at 160.9979 -115.04422)
		(size 0.6096)
		(drill 0.3048)
		(layers "F.Cu" "B.Cu")
		(net "P12V_STBY_VDD_U11")
	)
	(segment
		(start 161.2011 -114.84102)
		(end 160.9979 -115.04422)
		(width 0.254)
		(layer "B.Cu")
		(net "P12V_STBY_VDD_U11")
	)
	(segment
		(start 157.6324 -116.459)
		(end 159.04718 -115.04422)
		(width 0.254)
		(layer "B.Cu")
		(net "P12V_STBY_VDD_U11")
	)
	(segment
		(start 159.04718 -115.04422)
		(end 159.40278 -115.04422)
		(width 0.254)
		(layer "B.Cu")
		(net "P12V_STBY_VDD_U11")
	)
	(segment
		(start 159.40278 -115.04422)
		(end 160.9979 -115.04422)
		(width 0.254)
		(layer "B.Cu")
		(net "P12V_STBY_VDD_U11")
	)
	(segment
		(start 162.33648 -114.84102)
		(end 161.2011 -114.84102)
		(width 0.254)
		(layer "B.Cu")
		(net "P12V_STBY_VDD_U11")
	)
	(segment
		(start 64.974978 -97.231708)
		(end 64.974978 -98.050858)
		(width 0.254)
		(layer "F.Cu")
		(net "P12V_STBY_VDD_U10")
	)
	(segment
		(start 65.2526 -96.7486)
		(end 65.2526 -96.954086)
		(width 0.254)
		(layer "F.Cu")
		(net "P12V_STBY_VDD_U10")
	)
	(segment
		(start 65.2526 -96.954086)
		(end 64.974978 -97.231708)
		(width 0.254)
		(layer "F.Cu")
		(net "P12V_STBY_VDD_U10")
	)
	(via
		(at 65.2526 -96.7486)
		(size 0.508)
		(drill 0.254)
		(layers "F.Cu" "B.Cu")
		(net "P12V_STBY_VDD_U10")
	)
	(via
		(at 63.169292 -94.62389)
		(size 0.6096)
		(drill 0.3048)
		(layers "F.Cu" "B.Cu")
		(net "P12V_STBY_VDD_U10")
	)
	(segment
		(start 63.169292 -94.192598)
		(end 63.169292 -94.62389)
		(width 0.254)
		(layer "B.Cu")
		(net "P12V_STBY_VDD_U10")
	)
	(segment
		(start 63.444374 -95.4405)
		(end 63.169292 -95.165418)
		(width 0.254)
		(layer "B.Cu")
		(net "P12V_STBY_VDD_U10")
	)
	(segment
		(start 65.2526 -96.7486)
		(end 65.2526 -95.8723)
		(width 0.254)
		(layer "B.Cu")
		(net "P12V_STBY_VDD_U10")
	)
	(segment
		(start 65.2526 -95.8723)
		(end 64.8208 -95.4405)
		(width 0.254)
		(layer "B.Cu")
		(net "P12V_STBY_VDD_U10")
	)
	(segment
		(start 64.5922 -93.853)
		(end 63.50889 -93.853)
		(width 0.254)
		(layer "B.Cu")
		(net "P12V_STBY_VDD_U10")
	)
	(segment
		(start 63.169292 -95.165418)
		(end 63.169292 -94.62389)
		(width 0.254)
		(layer "B.Cu")
		(net "P12V_STBY_VDD_U10")
	)
	(segment
		(start 63.50889 -93.853)
		(end 63.169292 -94.192598)
		(width 0.254)
		(layer "B.Cu")
		(net "P12V_STBY_VDD_U10")
	)
	(segment
		(start 64.8208 -95.4405)
		(end 63.444374 -95.4405)
		(width 0.254)
		(layer "B.Cu")
		(net "P12V_STBY_VDD_U10")
	)
	(segment
		(start 178.13655 -106.83494)
		(end 175.88992 -106.83494)
		(width 0.127)
		(layer "F.Cu")
		(net "P12V_STBY_Q12_G")
	)
	(segment
		(start 178.93665 -107.63504)
		(end 178.13655 -106.83494)
		(width 0.127)
		(layer "F.Cu")
		(net "P12V_STBY_Q12_G")
	)
	(segment
		(start 180.28031 -107.63504)
		(end 178.93665 -107.63504)
		(width 0.127)
		(layer "F.Cu")
		(net "P12V_STBY_Q12_G")
	)
	(segment
		(start 183.98236 -113.64722)
		(end 183.98236 -112.62614)
		(width 0.127)
		(layer "F.Cu")
		(net "P12V_STBY_Q12_G")
	)
	(segment
		(start 183.98236 -111.154718)
		(end 183.98236 -112.62614)
		(width 0.127)
		(layer "F.Cu")
		(net "P12V_STBY_Q12_G")
	)
	(segment
		(start 181.85765 -109.21238)
		(end 182.55615 -109.91088)
		(width 0.127)
		(layer "F.Cu")
		(net "P12V_STBY_Q12_G")
	)
	(segment
		(start 175.88992 -106.83494)
		(end 175.48606 -106.43108)
		(width 0.127)
		(layer "F.Cu")
		(net "P12V_STBY_Q12_G")
	)
	(segment
		(start 182.55615 -109.91088)
		(end 182.738522 -109.91088)
		(width 0.127)
		(layer "F.Cu")
		(net "P12V_STBY_Q12_G")
	)
	(segment
		(start 182.738522 -109.91088)
		(end 183.98236 -111.154718)
		(width 0.127)
		(layer "F.Cu")
		(net "P12V_STBY_Q12_G")
	)
	(segment
		(start 181.85765 -109.21238)
		(end 180.28031 -107.63504)
		(width 0.127)
		(layer "F.Cu")
		(net "P12V_STBY_Q12_G")
	)
	(via
		(at 183.98236 -112.62614)
		(size 0.6604)
		(drill 0.3302)
		(layers "F.Cu" "B.Cu")
		(net "P12V_STBY_Q12_G")
	)
	(via
		(at 137.19556 -124.41682)
		(size 0.6096)
		(drill 0.3048)
		(layers "F.Cu" "B.Cu")
		(net "P12V_STBY_Q10_G")
	)
	(segment
		(start 139.71651 -124.14885)
		(end 139.5476 -124.31776)
		(width 0.127)
		(layer "B.Cu")
		(net "P12V_STBY_Q10_G")
	)
	(segment
		(start 136.730232 -124.41682)
		(end 135.528812 -123.2154)
		(width 0.127)
		(layer "B.Cu")
		(net "P12V_STBY_Q10_G")
	)
	(segment
		(start 135.528812 -123.2154)
		(end 134.4803 -123.2154)
		(width 0.127)
		(layer "B.Cu")
		(net "P12V_STBY_Q10_G")
	)
	(segment
		(start 143.0147 -124.14885)
		(end 139.71651 -124.14885)
		(width 0.127)
		(layer "B.Cu")
		(net "P12V_STBY_Q10_G")
	)
	(segment
		(start 137.59434 -124.31776)
		(end 139.5476 -124.31776)
		(width 0.127)
		(layer "B.Cu")
		(net "P12V_STBY_Q10_G")
	)
	(segment
		(start 137.19556 -124.41682)
		(end 136.730232 -124.41682)
		(width 0.127)
		(layer "B.Cu")
		(net "P12V_STBY_Q10_G")
	)
	(segment
		(start 137.49528 -124.41682)
		(end 137.59434 -124.31776)
		(width 0.127)
		(layer "B.Cu")
		(net "P12V_STBY_Q10_G")
	)
	(segment
		(start 137.19556 -124.41682)
		(end 137.49528 -124.41682)
		(width 0.127)
		(layer "B.Cu")
		(net "P12V_STBY_Q10_G")
	)
	(segment
		(start 177.8508 -96.9645)
		(end 177.8508 -97.7392)
		(width 0.254)
		(layer "F.Cu")
		(net "P0V975_SEN")
	)
	(via
		(at 177.8508 -97.7392)
		(size 0.508)
		(drill 0.254)
		(layers "F.Cu" "B.Cu")
		(net "P0V975_SEN")
	)
	(via
		(at 176.009046 -55.814468)
		(size 0.508)
		(drill 0.254)
		(layers "F.Cu" "B.Cu")
		(net "P0V975_SEN")
	)
	(via
		(at 175.204882 -54.62905)
		(size 0.6096)
		(drill 0.3048)
		(layers "F.Cu" "B.Cu")
		(net "P0V975_SEN")
	)
	(segment
		(start 174.8155 -54.239668)
		(end 175.204882 -54.62905)
		(width 0.254)
		(layer "B.Cu")
		(net "P0V975_SEN")
	)
	(segment
		(start 174.8155 -53.3908)
		(end 174.8155 -54.239668)
		(width 0.254)
		(layer "B.Cu")
		(net "P0V975_SEN")
	)
	(segment
		(start 175.204882 -54.62905)
		(end 176.009046 -55.433214)
		(width 0.254)
		(layer "B.Cu")
		(net "P0V975_SEN")
	)
	(segment
		(start 176.009046 -55.433214)
		(end 176.009046 -55.814468)
		(width 0.254)
		(layer "B.Cu")
		(net "P0V975_SEN")
	)
	(segment
		(start 177.274982 -70.141846)
		(end 190.632842 -83.499706)
		(width 0.254)
		(layer "In5.Cu")
		(net "P0V975_SEN")
	)
	(segment
		(start 176.009046 -55.814468)
		(end 176.287938 -56.09336)
		(width 0.254)
		(layer "In5.Cu")
		(net "P0V975_SEN")
	)
	(segment
		(start 177.274982 -59.289188)
		(end 177.274982 -70.141846)
		(width 0.254)
		(layer "In5.Cu")
		(net "P0V975_SEN")
	)
	(segment
		(start 182.411116 -97.9678)
		(end 181.361334 -96.918018)
		(width 0.254)
		(layer "In5.Cu")
		(net "P0V975_SEN")
	)
	(segment
		(start 190.632842 -96.412558)
		(end 189.0776 -97.9678)
		(width 0.254)
		(layer "In5.Cu")
		(net "P0V975_SEN")
	)
	(segment
		(start 189.0776 -97.9678)
		(end 182.411116 -97.9678)
		(width 0.254)
		(layer "In5.Cu")
		(net "P0V975_SEN")
	)
	(segment
		(start 178.671982 -96.918018)
		(end 177.8508 -97.7392)
		(width 0.254)
		(layer "In5.Cu")
		(net "P0V975_SEN")
	)
	(segment
		(start 176.287938 -56.09336)
		(end 176.287938 -58.302144)
		(width 0.254)
		(layer "In5.Cu")
		(net "P0V975_SEN")
	)
	(segment
		(start 176.287938 -58.302144)
		(end 177.274982 -59.289188)
		(width 0.254)
		(layer "In5.Cu")
		(net "P0V975_SEN")
	)
	(segment
		(start 190.632842 -83.499706)
		(end 190.632842 -96.412558)
		(width 0.254)
		(layer "In5.Cu")
		(net "P0V975_SEN")
	)
	(segment
		(start 181.361334 -96.918018)
		(end 178.671982 -96.918018)
		(width 0.254)
		(layer "In5.Cu")
		(net "P0V975_SEN")
	)
	(segment
		(start 177.8508 -99.3775)
		(end 177.8508 -98.6028)
		(width 0.254)
		(layer "F.Cu")
		(net "GND_SENSE")
	)
	(via
		(at 177.075846 -55.814468)
		(size 0.508)
		(drill 0.254)
		(layers "F.Cu" "B.Cu")
		(net "GND_SENSE")
	)
	(via
		(at 176.594262 -54.54269)
		(size 0.6096)
		(drill 0.3048)
		(layers "F.Cu" "B.Cu")
		(net "GND_SENSE")
	)
	(via
		(at 177.8508 -98.6028)
		(size 0.508)
		(drill 0.254)
		(layers "F.Cu" "B.Cu")
		(net "GND_SENSE")
	)
	(segment
		(start 175.8315 -53.779928)
		(end 175.8315 -53.3908)
		(width 0.254)
		(layer "B.Cu")
		(net "GND_SENSE")
	)
	(segment
		(start 177.075846 -55.814468)
		(end 177.075846 -55.024274)
		(width 0.254)
		(layer "B.Cu")
		(net "GND_SENSE")
	)
	(segment
		(start 176.594262 -54.54269)
		(end 175.8315 -53.779928)
		(width 0.254)
		(layer "B.Cu")
		(net "GND_SENSE")
	)
	(segment
		(start 177.075846 -55.024274)
		(end 176.594262 -54.54269)
		(width 0.254)
		(layer "B.Cu")
		(net "GND_SENSE")
	)
	(segment
		(start 177.075846 -55.814468)
		(end 176.846738 -56.043576)
		(width 0.254)
		(layer "In5.Cu")
		(net "GND_SENSE")
	)
	(segment
		(start 182.179468 -98.5266)
		(end 181.129686 -97.476818)
		(width 0.254)
		(layer "In5.Cu")
		(net "GND_SENSE")
	)
	(segment
		(start 178.976782 -97.476818)
		(end 177.8508 -98.6028)
		(width 0.254)
		(layer "In5.Cu")
		(net "GND_SENSE")
	)
	(segment
		(start 191.191642 -83.268058)
		(end 191.191642 -96.644206)
		(width 0.254)
		(layer "In5.Cu")
		(net "GND_SENSE")
	)
	(segment
		(start 177.859182 -59.053476)
		(end 177.859182 -69.935598)
		(width 0.254)
		(layer "In5.Cu")
		(net "GND_SENSE")
	)
	(segment
		(start 177.859182 -69.935598)
		(end 191.191642 -83.268058)
		(width 0.254)
		(layer "In5.Cu")
		(net "GND_SENSE")
	)
	(segment
		(start 176.846738 -56.043576)
		(end 176.846738 -58.041032)
		(width 0.254)
		(layer "In5.Cu")
		(net "GND_SENSE")
	)
	(segment
		(start 191.191642 -96.644206)
		(end 189.309248 -98.5266)
		(width 0.254)
		(layer "In5.Cu")
		(net "GND_SENSE")
	)
	(segment
		(start 181.129686 -97.476818)
		(end 178.976782 -97.476818)
		(width 0.254)
		(layer "In5.Cu")
		(net "GND_SENSE")
	)
	(segment
		(start 176.846738 -58.041032)
		(end 177.859182 -59.053476)
		(width 0.254)
		(layer "In5.Cu")
		(net "GND_SENSE")
	)
	(segment
		(start 189.309248 -98.5266)
		(end 182.179468 -98.5266)
		(width 0.254)
		(layer "In5.Cu")
		(net "GND_SENSE")
	)
	(segment
		(start 62.61862 -17.852644)
		(end 62.81547 -17.852644)
		(width 0.127)
		(layer "F.Cu")
		(net "SCC_STBY_PGOOD_U49")
	)
	(segment
		(start 64.219328 -20.706588)
		(end 65.361312 -20.706588)
		(width 0.127)
		(layer "F.Cu")
		(net "SCC_STBY_PGOOD_U49")
	)
	(segment
		(start 65.7225 -21.59)
		(end 65.7225 -22.86)
		(width 0.127)
		(layer "F.Cu")
		(net "SCC_STBY_PGOOD_U49")
	)
	(segment
		(start 63.810134 -20.297394)
		(end 64.219328 -20.706588)
		(width 0.127)
		(layer "F.Cu")
		(net "SCC_STBY_PGOOD_U49")
	)
	(segment
		(start 63.810134 -18.847308)
		(end 63.810134 -20.297394)
		(width 0.127)
		(layer "F.Cu")
		(net "SCC_STBY_PGOOD_U49")
	)
	(segment
		(start 65.7225 -21.067776)
		(end 65.7225 -21.59)
		(width 0.127)
		(layer "F.Cu")
		(net "SCC_STBY_PGOOD_U49")
	)
	(segment
		(start 62.81547 -17.852644)
		(end 63.810134 -18.847308)
		(width 0.127)
		(layer "F.Cu")
		(net "SCC_STBY_PGOOD_U49")
	)
	(segment
		(start 62.384686 -18.086578)
		(end 62.61862 -17.852644)
		(width 0.127)
		(layer "F.Cu")
		(net "SCC_STBY_PGOOD_U49")
	)
	(segment
		(start 65.361312 -20.706588)
		(end 65.7225 -21.067776)
		(width 0.127)
		(layer "F.Cu")
		(net "SCC_STBY_PGOOD_U49")
	)
	(segment
		(start 62.384686 -20.675346)
		(end 62.384686 -18.086578)
		(width 0.127)
		(layer "F.Cu")
		(net "SCC_STBY_PGOOD_U49")
	)
	(via
		(at 65.7225 -21.59)
		(size 0.6604)
		(drill 0.3302)
		(layers "F.Cu" "B.Cu")
		(net "SCC_STBY_PGOOD_U49")
	)
	(segment
		(start 74.16038 -19.879056)
		(end 75.25512 -20.973796)
		(width 0.127)
		(layer "F.Cu")
		(net "SYS_PWR_LED_N")
	)
	(segment
		(start 74.16038 -17.560798)
		(end 74.16038 -19.32686)
		(width 0.127)
		(layer "F.Cu")
		(net "SYS_PWR_LED_N")
	)
	(segment
		(start 74.16038 -19.32686)
		(end 74.16038 -19.879056)
		(width 0.127)
		(layer "F.Cu")
		(net "SYS_PWR_LED_N")
	)
	(segment
		(start 72.842374 -16.72971)
		(end 73.14438 -17.031716)
		(width 0.127)
		(layer "F.Cu")
		(net "SYS_PWR_LED_N")
	)
	(segment
		(start 73.14438 -17.031716)
		(end 73.631298 -17.031716)
		(width 0.127)
		(layer "F.Cu")
		(net "SYS_PWR_LED_N")
	)
	(segment
		(start 71.958708 -16.72971)
		(end 72.842374 -16.72971)
		(width 0.127)
		(layer "F.Cu")
		(net "SYS_PWR_LED_N")
	)
	(segment
		(start 73.631298 -17.031716)
		(end 74.16038 -17.560798)
		(width 0.127)
		(layer "F.Cu")
		(net "SYS_PWR_LED_N")
	)
	(via
		(at 75.25512 -20.973796)
		(size 0.508)
		(drill 0.254)
		(layers "F.Cu" "B.Cu")
		(net "SYS_PWR_LED_N")
	)
	(via
		(at 74.16038 -19.32686)
		(size 0.6604)
		(drill 0.3302)
		(layers "F.Cu" "B.Cu")
		(net "SYS_PWR_LED_N")
	)
	(segment
		(start 76.27112 -21.989796)
		(end 75.25512 -20.973796)
		(width 0.127)
		(layer "In2.Cu")
		(net "SYS_PWR_LED_N")
	)
	(segment
		(start 99.226878 -8.573262)
		(end 99.226878 -14.044422)
		(width 0.127)
		(layer "In2.Cu")
		(net "SYS_PWR_LED_N")
	)
	(segment
		(start 100.400104 -7.400036)
		(end 99.226878 -8.573262)
		(width 0.127)
		(layer "In2.Cu")
		(net "SYS_PWR_LED_N")
	)
	(segment
		(start 91.281504 -21.989796)
		(end 76.27112 -21.989796)
		(width 0.127)
		(layer "In2.Cu")
		(net "SYS_PWR_LED_N")
	)
	(segment
		(start 99.226878 -14.044422)
		(end 91.281504 -21.989796)
		(width 0.127)
		(layer "In2.Cu")
		(net "SYS_PWR_LED_N")
	)
	(segment
		(start 107.499912 -77.500226)
		(end 107.00004 -77.000354)
		(width 0.127)
		(layer "F.Cu")
		(net "SYS_PWR_LED_LS_N")
	)
	(segment
		(start 69.21754 -24.271224)
		(end 71.195692 -24.271224)
		(width 0.127)
		(layer "F.Cu")
		(net "SYS_PWR_LED_LS_N")
	)
	(segment
		(start 66.319908 -17.12849)
		(end 67.26936 -17.12849)
		(width 0.127)
		(layer "F.Cu")
		(net "SYS_PWR_LED_LS_N")
	)
	(segment
		(start 68.316348 -22.466808)
		(end 68.316348 -23.370032)
		(width 0.127)
		(layer "F.Cu")
		(net "SYS_PWR_LED_LS_N")
	)
	(segment
		(start 68.316348 -18.175478)
		(end 68.316348 -22.466808)
		(width 0.127)
		(layer "F.Cu")
		(net "SYS_PWR_LED_LS_N")
	)
	(segment
		(start 67.26936 -17.12849)
		(end 68.316348 -18.175478)
		(width 0.127)
		(layer "F.Cu")
		(net "SYS_PWR_LED_LS_N")
	)
	(segment
		(start 68.316348 -23.370032)
		(end 69.21754 -24.271224)
		(width 0.127)
		(layer "F.Cu")
		(net "SYS_PWR_LED_LS_N")
	)
	(via
		(at 103.068882 -86.186772)
		(size 0.508)
		(drill 0.254)
		(layers "F.Cu" "B.Cu")
		(net "SYS_PWR_LED_LS_N")
	)
	(via
		(at 68.316348 -22.466808)
		(size 0.6604)
		(drill 0.3302)
		(layers "F.Cu" "B.Cu")
		(net "SYS_PWR_LED_LS_N")
	)
	(via
		(at 107.00004 -77.000354)
		(size 0.4572)
		(drill 0.2032)
		(layers "F.Cu" "B.Cu")
		(net "SYS_PWR_LED_LS_N")
	)
	(via
		(at 71.195692 -24.271224)
		(size 0.508)
		(drill 0.254)
		(layers "F.Cu" "B.Cu")
		(net "SYS_PWR_LED_LS_N")
	)
	(segment
		(start 103.62438 -85.25002)
		(end 103.14178 -84.76742)
		(width 0.127)
		(layer "B.Cu")
		(net "SYS_PWR_LED_LS_N")
	)
	(segment
		(start 103.38181 -86.4997)
		(end 103.068882 -86.186772)
		(width 0.127)
		(layer "B.Cu")
		(net "SYS_PWR_LED_LS_N")
	)
	(segment
		(start 105.2322 -78.5114)
		(end 105.4608 -78.2828)
		(width 0.127)
		(layer "B.Cu")
		(net "SYS_PWR_LED_LS_N")
	)
	(segment
		(start 103.6066 -79.502)
		(end 104.1908 -79.502)
		(width 0.127)
		(layer "B.Cu")
		(net "SYS_PWR_LED_LS_N")
	)
	(segment
		(start 105.4608 -78.2828)
		(end 105.4608 -77.7748)
		(width 0.127)
		(layer "B.Cu")
		(net "SYS_PWR_LED_LS_N")
	)
	(segment
		(start 103.9114 -85.53704)
		(end 103.62438 -85.25002)
		(width 0.127)
		(layer "B.Cu")
		(net "SYS_PWR_LED_LS_N")
	)
	(segment
		(start 106.393996 -77.606398)
		(end 107.00004 -77.000354)
		(width 0.127)
		(layer "B.Cu")
		(net "SYS_PWR_LED_LS_N")
	)
	(segment
		(start 103.14178 -84.76742)
		(end 103.14178 -83.47964)
		(width 0.127)
		(layer "B.Cu")
		(net "SYS_PWR_LED_LS_N")
	)
	(segment
		(start 103.14178 -83.47964)
		(end 103.4542 -83.16722)
		(width 0.127)
		(layer "B.Cu")
		(net "SYS_PWR_LED_LS_N")
	)
	(segment
		(start 104.8258 -78.5114)
		(end 105.2322 -78.5114)
		(width 0.127)
		(layer "B.Cu")
		(net "SYS_PWR_LED_LS_N")
	)
	(segment
		(start 103.4542 -79.6544)
		(end 103.6066 -79.502)
		(width 0.127)
		(layer "B.Cu")
		(net "SYS_PWR_LED_LS_N")
	)
	(segment
		(start 105.629202 -77.606398)
		(end 106.393996 -77.606398)
		(width 0.127)
		(layer "B.Cu")
		(net "SYS_PWR_LED_LS_N")
	)
	(segment
		(start 104.5972 -78.74)
		(end 104.8258 -78.5114)
		(width 0.127)
		(layer "B.Cu")
		(net "SYS_PWR_LED_LS_N")
	)
	(segment
		(start 103.9114 -86.4997)
		(end 103.9114 -85.53704)
		(width 0.127)
		(layer "B.Cu")
		(net "SYS_PWR_LED_LS_N")
	)
	(segment
		(start 103.9114 -86.4997)
		(end 103.38181 -86.4997)
		(width 0.127)
		(layer "B.Cu")
		(net "SYS_PWR_LED_LS_N")
	)
	(segment
		(start 104.1908 -79.502)
		(end 104.5972 -79.0956)
		(width 0.127)
		(layer "B.Cu")
		(net "SYS_PWR_LED_LS_N")
	)
	(segment
		(start 105.4608 -77.7748)
		(end 105.629202 -77.606398)
		(width 0.127)
		(layer "B.Cu")
		(net "SYS_PWR_LED_LS_N")
	)
	(segment
		(start 103.4542 -83.16722)
		(end 103.4542 -79.6544)
		(width 0.127)
		(layer "B.Cu")
		(net "SYS_PWR_LED_LS_N")
	)
	(segment
		(start 104.5972 -79.0956)
		(end 104.5972 -78.74)
		(width 0.127)
		(layer "B.Cu")
		(net "SYS_PWR_LED_LS_N")
	)
	(segment
		(start 80.916018 -82.273902)
		(end 82.301842 -83.659726)
		(width 0.127)
		(layer "In5.Cu")
		(net "SYS_PWR_LED_LS_N")
	)
	(segment
		(start 72.616822 -30.703012)
		(end 74.282554 -30.703012)
		(width 0.127)
		(layer "In5.Cu")
		(net "SYS_PWR_LED_LS_N")
	)
	(segment
		(start 76.104242 -32.5247)
		(end 76.104242 -69.16166)
		(width 0.127)
		(layer "In5.Cu")
		(net "SYS_PWR_LED_LS_N")
	)
	(segment
		(start 70.348094 -28.434284)
		(end 72.616822 -30.703012)
		(width 0.127)
		(layer "In5.Cu")
		(net "SYS_PWR_LED_LS_N")
	)
	(segment
		(start 88.002618 -88.372442)
		(end 88.599772 -88.969596)
		(width 0.127)
		(layer "In5.Cu")
		(net "SYS_PWR_LED_LS_N")
	)
	(segment
		(start 80.916018 -81.156556)
		(end 80.916018 -82.273902)
		(width 0.127)
		(layer "In5.Cu")
		(net "SYS_PWR_LED_LS_N")
	)
	(segment
		(start 74.282554 -30.703012)
		(end 76.104242 -32.5247)
		(width 0.127)
		(layer "In5.Cu")
		(net "SYS_PWR_LED_LS_N")
	)
	(segment
		(start 76.104242 -69.16166)
		(end 79.25562 -72.313038)
		(width 0.127)
		(layer "In5.Cu")
		(net "SYS_PWR_LED_LS_N")
	)
	(segment
		(start 82.301842 -83.659726)
		(end 82.301842 -84.41436)
		(width 0.127)
		(layer "In5.Cu")
		(net "SYS_PWR_LED_LS_N")
	)
	(segment
		(start 79.25562 -72.313038)
		(end 79.25562 -79.496158)
		(width 0.127)
		(layer "In5.Cu")
		(net "SYS_PWR_LED_LS_N")
	)
	(segment
		(start 71.195692 -24.271224)
		(end 70.348094 -25.118822)
		(width 0.127)
		(layer "In5.Cu")
		(net "SYS_PWR_LED_LS_N")
	)
	(segment
		(start 86.259924 -88.372442)
		(end 88.002618 -88.372442)
		(width 0.127)
		(layer "In5.Cu")
		(net "SYS_PWR_LED_LS_N")
	)
	(segment
		(start 88.599772 -88.969596)
		(end 96.746822 -88.969596)
		(width 0.127)
		(layer "In5.Cu")
		(net "SYS_PWR_LED_LS_N")
	)
	(segment
		(start 101.898958 -87.356696)
		(end 103.068882 -86.186772)
		(width 0.127)
		(layer "In5.Cu")
		(net "SYS_PWR_LED_LS_N")
	)
	(segment
		(start 82.301842 -84.41436)
		(end 86.259924 -88.372442)
		(width 0.127)
		(layer "In5.Cu")
		(net "SYS_PWR_LED_LS_N")
	)
	(segment
		(start 70.348094 -25.118822)
		(end 70.348094 -28.434284)
		(width 0.127)
		(layer "In5.Cu")
		(net "SYS_PWR_LED_LS_N")
	)
	(segment
		(start 96.746822 -88.969596)
		(end 98.359722 -87.356696)
		(width 0.127)
		(layer "In5.Cu")
		(net "SYS_PWR_LED_LS_N")
	)
	(segment
		(start 79.25562 -79.496158)
		(end 80.916018 -81.156556)
		(width 0.127)
		(layer "In5.Cu")
		(net "SYS_PWR_LED_LS_N")
	)
	(segment
		(start 98.359722 -87.356696)
		(end 101.898958 -87.356696)
		(width 0.127)
		(layer "In5.Cu")
		(net "SYS_PWR_LED_LS_N")
	)
	(segment
		(start 201.04608 -83.058)
		(end 201.04608 -85.952076)
		(width 0.127)
		(layer "F.Cu")
		(net "SDB_CONN_PWR_3")
	)
	(segment
		(start 200.23328 -83.35772)
		(end 200.533 -83.058)
		(width 0.127)
		(layer "F.Cu")
		(net "SDB_CONN_PWR_3")
	)
	(segment
		(start 199.78624 -83.35772)
		(end 198.84136 -83.35772)
		(width 0.127)
		(layer "F.Cu")
		(net "SDB_CONN_PWR_3")
	)
	(segment
		(start 199.78624 -83.35772)
		(end 200.23328 -83.35772)
		(width 0.127)
		(layer "F.Cu")
		(net "SDB_CONN_PWR_3")
	)
	(segment
		(start 198.84136 -83.35772)
		(end 198.8312 -83.36788)
		(width 0.127)
		(layer "F.Cu")
		(net "SDB_CONN_PWR_3")
	)
	(segment
		(start 200.533 -83.058)
		(end 201.04608 -83.058)
		(width 0.127)
		(layer "F.Cu")
		(net "SDB_CONN_PWR_3")
	)
	(via
		(at 201.04608 -83.058)
		(size 0.6604)
		(drill 0.3302)
		(layers "F.Cu" "B.Cu")
		(net "SDB_CONN_PWR_3")
	)
	(segment
		(start 175.43526 -107.90428)
		(end 176.62144 -107.90428)
		(width 0.127)
		(layer "F.Cu")
		(net "Q22_D")
	)
	(segment
		(start 176.62652 -107.8992)
		(end 178.28006 -107.8992)
		(width 0.127)
		(layer "F.Cu")
		(net "Q22_D")
	)
	(segment
		(start 175.43526 -107.90428)
		(end 174.34306 -107.90428)
		(width 0.127)
		(layer "F.Cu")
		(net "Q22_D")
	)
	(segment
		(start 178.28006 -107.8992)
		(end 179.1208 -108.73994)
		(width 0.127)
		(layer "F.Cu")
		(net "Q22_D")
	)
	(segment
		(start 176.62144 -107.90428)
		(end 176.62652 -107.8992)
		(width 0.127)
		(layer "F.Cu")
		(net "Q22_D")
	)
	(via
		(at 175.43526 -107.90428)
		(size 0.6604)
		(drill 0.3302)
		(layers "F.Cu" "B.Cu")
		(net "Q22_D")
	)
	(segment
		(start 56.781446 -23.228554)
		(end 56.4515 -23.5585)
		(width 0.381)
		(layer "F.Cu")
		(net "P3V3_DPB")
	)
	(segment
		(start 54.966362 -16.95831)
		(end 55.937658 -16.95831)
		(width 0.508)
		(layer "F.Cu")
		(net "P3V3_DPB")
	)
	(segment
		(start 54.4449 -23.583392)
		(end 54.991508 -24.13)
		(width 0.508)
		(layer "F.Cu")
		(net "P3V3_DPB")
	)
	(segment
		(start 54.4449 -20.711922)
		(end 54.4449 -23.583392)
		(width 0.508)
		(layer "F.Cu")
		(net "P3V3_DPB")
	)
	(segment
		(start 54.4449 -20.711922)
		(end 54.4449 -17.479772)
		(width 0.508)
		(layer "F.Cu")
		(net "P3V3_DPB")
	)
	(segment
		(start 56.781446 -22.326346)
		(end 56.781446 -23.228554)
		(width 0.381)
		(layer "F.Cu")
		(net "P3V3_DPB")
	)
	(segment
		(start 54.991508 -24.13)
		(end 56.4515 -24.13)
		(width 0.508)
		(layer "F.Cu")
		(net "P3V3_DPB")
	)
	(segment
		(start 55.937658 -16.95831)
		(end 55.937658 -16.167608)
		(width 0.508)
		(layer "F.Cu")
		(net "P3V3_DPB")
	)
	(segment
		(start 54.4449 -17.479772)
		(end 54.966362 -16.95831)
		(width 0.508)
		(layer "F.Cu")
		(net "P3V3_DPB")
	)
	(segment
		(start 55.937658 -16.167608)
		(end 55.937912 -16.167354)
		(width 0.508)
		(layer "F.Cu")
		(net "P3V3_DPB")
	)
	(segment
		(start 56.4515 -23.5585)
		(end 56.4515 -24.13)
		(width 0.381)
		(layer "F.Cu")
		(net "P3V3_DPB")
	)
	(via
		(at 55.937912 -16.167354)
		(size 0.508)
		(drill 0.254)
		(layers "F.Cu" "B.Cu")
		(net "P3V3_DPB")
	)
	(via
		(at 54.4449 -20.711922)
		(size 0.6604)
		(drill 0.3302)
		(layers "F.Cu" "B.Cu")
		(net "P3V3_DPB")
	)
	(segment
		(start 59.542934 -12.021058)
		(end 80.381602 -12.021058)
		(width 0.508)
		(layer "In2.Cu")
		(net "P3V3_DPB")
	)
	(segment
		(start 86.07171 -14.2367)
		(end 86.631018 -13.677392)
		(width 0.127)
		(layer "In2.Cu")
		(net "P3V3_DPB")
	)
	(segment
		(start 86.631018 -13.677392)
		(end 86.631018 -7.369302)
		(width 0.127)
		(layer "In2.Cu")
		(net "P3V3_DPB")
	)
	(segment
		(start 80.381602 -12.021058)
		(end 82.597244 -14.2367)
		(width 0.508)
		(layer "In2.Cu")
		(net "P3V3_DPB")
	)
	(segment
		(start 55.937912 -15.62608)
		(end 59.542934 -12.021058)
		(width 0.508)
		(layer "In2.Cu")
		(net "P3V3_DPB")
	)
	(segment
		(start 82.597244 -14.2367)
		(end 85.440774 -14.2367)
		(width 0.508)
		(layer "In2.Cu")
		(net "P3V3_DPB")
	)
	(segment
		(start 85.440774 -14.2367)
		(end 86.07171 -14.2367)
		(width 0.127)
		(layer "In2.Cu")
		(net "P3V3_DPB")
	)
	(segment
		(start 86.631018 -7.369302)
		(end 87.80018 -6.20014)
		(width 0.127)
		(layer "In2.Cu")
		(net "P3V3_DPB")
	)
	(segment
		(start 55.937912 -16.167354)
		(end 55.937912 -15.62608)
		(width 0.508)
		(layer "In2.Cu")
		(net "P3V3_DPB")
	)
	(via
		(at 5.801106 -41.609518)
		(size 0.6604)
		(drill 0.3302)
		(layers "F.Cu" "B.Cu")
		(net "MB0_12V_CTRL_GATE1_R")
	)
	(segment
		(start 71.43369 -25.96769)
		(end 72.955658 -27.489658)
		(width 0.127)
		(layer "F.Cu")
		(net "ENCL_FAULT_LED_LS")
	)
	(segment
		(start 69.111876 -24.884126)
		(end 71.249794 -24.884126)
		(width 0.127)
		(layer "F.Cu")
		(net "ENCL_FAULT_LED_LS")
	)
	(segment
		(start 107.499912 -76.500228)
		(end 107.00004 -76.000356)
		(width 0.127)
		(layer "F.Cu")
		(net "ENCL_FAULT_LED_LS")
	)
	(segment
		(start 72.955658 -27.489658)
		(end 74.26579 -27.489658)
		(width 0.127)
		(layer "F.Cu")
		(net "ENCL_FAULT_LED_LS")
	)
	(segment
		(start 67.017138 -17.52854)
		(end 67.247008 -17.75841)
		(width 0.127)
		(layer "F.Cu")
		(net "ENCL_FAULT_LED_LS")
	)
	(segment
		(start 66.319908 -17.52854)
		(end 67.017138 -17.52854)
		(width 0.127)
		(layer "F.Cu")
		(net "ENCL_FAULT_LED_LS")
	)
	(segment
		(start 67.720972 -23.493222)
		(end 69.111876 -24.884126)
		(width 0.127)
		(layer "F.Cu")
		(net "ENCL_FAULT_LED_LS")
	)
	(segment
		(start 71.43369 -25.068022)
		(end 71.43369 -25.96769)
		(width 0.127)
		(layer "F.Cu")
		(net "ENCL_FAULT_LED_LS")
	)
	(segment
		(start 67.247008 -17.75841)
		(end 67.247008 -17.824704)
		(width 0.127)
		(layer "F.Cu")
		(net "ENCL_FAULT_LED_LS")
	)
	(segment
		(start 71.249794 -24.884126)
		(end 71.43369 -25.068022)
		(width 0.127)
		(layer "F.Cu")
		(net "ENCL_FAULT_LED_LS")
	)
	(segment
		(start 67.720972 -18.298668)
		(end 67.720972 -23.493222)
		(width 0.127)
		(layer "F.Cu")
		(net "ENCL_FAULT_LED_LS")
	)
	(segment
		(start 67.247008 -17.824704)
		(end 67.720972 -18.298668)
		(width 0.127)
		(layer "F.Cu")
		(net "ENCL_FAULT_LED_LS")
	)
	(via
		(at 99.683062 -84.23529)
		(size 0.6096)
		(drill 0.3048)
		(layers "F.Cu" "B.Cu")
		(net "ENCL_FAULT_LED_LS")
	)
	(via
		(at 107.00004 -76.000356)
		(size 0.4572)
		(drill 0.2032)
		(layers "F.Cu" "B.Cu")
		(net "ENCL_FAULT_LED_LS")
	)
	(via
		(at 74.26579 -27.489658)
		(size 0.508)
		(drill 0.254)
		(layers "F.Cu" "B.Cu")
		(net "ENCL_FAULT_LED_LS")
	)
	(via
		(at 99.1997 -83.01228)
		(size 0.508)
		(drill 0.254)
		(layers "F.Cu" "B.Cu")
		(net "ENCL_FAULT_LED_LS")
	)
	(segment
		(start 102.5398 -78.8924)
		(end 102.9208 -78.5114)
		(width 0.127)
		(layer "B.Cu")
		(net "ENCL_FAULT_LED_LS")
	)
	(segment
		(start 102.02672 -84.18322)
		(end 101.41966 -84.79028)
		(width 0.127)
		(layer "B.Cu")
		(net "ENCL_FAULT_LED_LS")
	)
	(segment
		(start 101.41966 -84.79028)
		(end 100.238052 -84.79028)
		(width 0.127)
		(layer "B.Cu")
		(net "ENCL_FAULT_LED_LS")
	)
	(segment
		(start 100.238052 -84.79028)
		(end 99.683062 -84.23529)
		(width 0.127)
		(layer "B.Cu")
		(net "ENCL_FAULT_LED_LS")
	)
	(segment
		(start 106.393996 -76.6064)
		(end 107.00004 -76.000356)
		(width 0.127)
		(layer "B.Cu")
		(net "ENCL_FAULT_LED_LS")
	)
	(segment
		(start 104.267 -78.5114)
		(end 104.521 -78.2574)
		(width 0.127)
		(layer "B.Cu")
		(net "ENCL_FAULT_LED_LS")
	)
	(segment
		(start 102.02672 -84.18322)
		(end 102.5398 -83.67014)
		(width 0.127)
		(layer "B.Cu")
		(net "ENCL_FAULT_LED_LS")
	)
	(segment
		(start 104.7496 -76.6064)
		(end 106.393996 -76.6064)
		(width 0.127)
		(layer "B.Cu")
		(net "ENCL_FAULT_LED_LS")
	)
	(segment
		(start 99.1997 -83.01228)
		(end 99.1997 -83.751928)
		(width 0.127)
		(layer "B.Cu")
		(net "ENCL_FAULT_LED_LS")
	)
	(segment
		(start 102.9208 -78.5114)
		(end 104.267 -78.5114)
		(width 0.127)
		(layer "B.Cu")
		(net "ENCL_FAULT_LED_LS")
	)
	(segment
		(start 99.1997 -83.751928)
		(end 99.683062 -84.23529)
		(width 0.127)
		(layer "B.Cu")
		(net "ENCL_FAULT_LED_LS")
	)
	(segment
		(start 102.5398 -83.67014)
		(end 102.5398 -78.8924)
		(width 0.127)
		(layer "B.Cu")
		(net "ENCL_FAULT_LED_LS")
	)
	(segment
		(start 104.521 -78.2574)
		(end 104.521 -76.835)
		(width 0.127)
		(layer "B.Cu")
		(net "ENCL_FAULT_LED_LS")
	)
	(segment
		(start 104.521 -76.835)
		(end 104.7496 -76.6064)
		(width 0.127)
		(layer "B.Cu")
		(net "ENCL_FAULT_LED_LS")
	)
	(segment
		(start 76.441046 -29.664914)
		(end 77.560678 -29.664914)
		(width 0.127)
		(layer "In5.Cu")
		(net "ENCL_FAULT_LED_LS")
	)
	(segment
		(start 74.26579 -27.489658)
		(end 76.441046 -29.664914)
		(width 0.127)
		(layer "In5.Cu")
		(net "ENCL_FAULT_LED_LS")
	)
	(segment
		(start 85.783928 -72.029828)
		(end 85.783928 -80.019144)
		(width 0.127)
		(layer "In5.Cu")
		(net "ENCL_FAULT_LED_LS")
	)
	(segment
		(start 99.11334 -82.92592)
		(end 99.1997 -83.01228)
		(width 0.127)
		(layer "In5.Cu")
		(net "ENCL_FAULT_LED_LS")
	)
	(segment
		(start 77.560678 -29.664914)
		(end 77.871066 -29.975302)
		(width 0.127)
		(layer "In5.Cu")
		(net "ENCL_FAULT_LED_LS")
	)
	(segment
		(start 80.697578 -62.353952)
		(end 80.697578 -66.943478)
		(width 0.127)
		(layer "In5.Cu")
		(net "ENCL_FAULT_LED_LS")
	)
	(segment
		(start 79.3242 -40.8178)
		(end 79.3242 -60.980574)
		(width 0.127)
		(layer "In5.Cu")
		(net "ENCL_FAULT_LED_LS")
	)
	(segment
		(start 85.783928 -80.019144)
		(end 87.019384 -81.2546)
		(width 0.127)
		(layer "In5.Cu")
		(net "ENCL_FAULT_LED_LS")
	)
	(segment
		(start 79.3242 -60.980574)
		(end 80.697578 -62.353952)
		(width 0.127)
		(layer "In5.Cu")
		(net "ENCL_FAULT_LED_LS")
	)
	(segment
		(start 78.37297 -39.86657)
		(end 79.3242 -40.8178)
		(width 0.127)
		(layer "In5.Cu")
		(net "ENCL_FAULT_LED_LS")
	)
	(segment
		(start 87.019384 -81.2546)
		(end 96.97212 -81.2546)
		(width 0.127)
		(layer "In5.Cu")
		(net "ENCL_FAULT_LED_LS")
	)
	(segment
		(start 96.97212 -81.2546)
		(end 98.64344 -82.92592)
		(width 0.127)
		(layer "In5.Cu")
		(net "ENCL_FAULT_LED_LS")
	)
	(segment
		(start 80.697578 -66.943478)
		(end 85.783928 -72.029828)
		(width 0.127)
		(layer "In5.Cu")
		(net "ENCL_FAULT_LED_LS")
	)
	(segment
		(start 77.871066 -29.975302)
		(end 77.871066 -31.200598)
		(width 0.127)
		(layer "In5.Cu")
		(net "ENCL_FAULT_LED_LS")
	)
	(segment
		(start 77.871066 -31.200598)
		(end 78.37297 -31.702502)
		(width 0.127)
		(layer "In5.Cu")
		(net "ENCL_FAULT_LED_LS")
	)
	(segment
		(start 98.64344 -82.92592)
		(end 99.11334 -82.92592)
		(width 0.127)
		(layer "In5.Cu")
		(net "ENCL_FAULT_LED_LS")
	)
	(segment
		(start 78.37297 -31.702502)
		(end 78.37297 -39.86657)
		(width 0.127)
		(layer "In5.Cu")
		(net "ENCL_FAULT_LED_LS")
	)
	(segment
		(start 72.806814 -17.12849)
		(end 73.607422 -17.929098)
		(width 0.127)
		(layer "F.Cu")
		(net "ENCL_FAULT_LED")
	)
	(segment
		(start 73.607422 -17.929098)
		(end 73.607422 -21.818854)
		(width 0.127)
		(layer "F.Cu")
		(net "ENCL_FAULT_LED")
	)
	(segment
		(start 73.607422 -21.818854)
		(end 73.607422 -22.437598)
		(width 0.127)
		(layer "F.Cu")
		(net "ENCL_FAULT_LED")
	)
	(segment
		(start 73.607422 -22.437598)
		(end 74.17562 -23.005796)
		(width 0.127)
		(layer "F.Cu")
		(net "ENCL_FAULT_LED")
	)
	(segment
		(start 71.958708 -17.12849)
		(end 72.806814 -17.12849)
		(width 0.127)
		(layer "F.Cu")
		(net "ENCL_FAULT_LED")
	)
	(via
		(at 74.17562 -23.005796)
		(size 0.508)
		(drill 0.254)
		(layers "F.Cu" "B.Cu")
		(net "ENCL_FAULT_LED")
	)
	(via
		(at 73.607422 -21.818854)
		(size 0.6604)
		(drill 0.3302)
		(layers "F.Cu" "B.Cu")
		(net "ENCL_FAULT_LED")
	)
	(segment
		(start 91.702636 -23.005796)
		(end 101.032818 -13.675614)
		(width 0.127)
		(layer "In2.Cu")
		(net "ENCL_FAULT_LED")
	)
	(segment
		(start 101.032818 -7.367524)
		(end 102.200202 -6.20014)
		(width 0.127)
		(layer "In2.Cu")
		(net "ENCL_FAULT_LED")
	)
	(segment
		(start 101.032818 -13.675614)
		(end 101.032818 -7.367524)
		(width 0.127)
		(layer "In2.Cu")
		(net "ENCL_FAULT_LED")
	)
	(segment
		(start 74.17562 -23.005796)
		(end 91.702636 -23.005796)
		(width 0.127)
		(layer "In2.Cu")
		(net "ENCL_FAULT_LED")
	)
	(segment
		(start 11.8745 -98.425)
		(end 11.8745 -98.09099)
		(width 0.127)
		(layer "F.Cu")
		(net "U120_EN")
	)
	(segment
		(start 11.8745 -98.425)
		(end 11.8745 -99.6315)
		(width 0.127)
		(layer "F.Cu")
		(net "U120_EN")
	)
	(segment
		(start 9.525 -97.5233)
		(end 9.903206 -97.5233)
		(width 0.127)
		(layer "F.Cu")
		(net "U120_EN")
	)
	(segment
		(start 11.8745 -98.09099)
		(end 11.25601 -97.4725)
		(width 0.127)
		(layer "F.Cu")
		(net "U120_EN")
	)
	(segment
		(start 11.57224 -99.93376)
		(end 11.0109 -99.93376)
		(width 0.127)
		(layer "F.Cu")
		(net "U120_EN")
	)
	(segment
		(start 9.954006 -97.4725)
		(end 10.687304 -97.4725)
		(width 0.127)
		(layer "F.Cu")
		(net "U120_EN")
	)
	(segment
		(start 9.903206 -97.5233)
		(end 9.954006 -97.4725)
		(width 0.127)
		(layer "F.Cu")
		(net "U120_EN")
	)
	(segment
		(start 11.8745 -99.6315)
		(end 11.57224 -99.93376)
		(width 0.127)
		(layer "F.Cu")
		(net "U120_EN")
	)
	(segment
		(start 11.25601 -97.4725)
		(end 10.687304 -97.4725)
		(width 0.127)
		(layer "F.Cu")
		(net "U120_EN")
	)
	(via
		(at 10.687304 -97.4725)
		(size 0.6604)
		(drill 0.3302)
		(layers "F.Cu" "B.Cu")
		(net "U120_EN")
	)
	(segment
		(start 70.4215 -81.6864)
		(end 70.4215 -80.6958)
		(width 0.127)
		(layer "F.Cu")
		(net "U122_VCC")
	)
	(segment
		(start 70.4215 -80.6958)
		(end 70.4215 -80.3275)
		(width 0.127)
		(layer "F.Cu")
		(net "U122_VCC")
	)
	(segment
		(start 70.4215 -80.3275)
		(end 70.962012 -79.786988)
		(width 0.127)
		(layer "F.Cu")
		(net "U122_VCC")
	)
	(segment
		(start 70.962012 -79.786988)
		(end 70.962012 -78.965806)
		(width 0.127)
		(layer "F.Cu")
		(net "U122_VCC")
	)
	(via
		(at 70.4215 -80.6958)
		(size 0.6604)
		(drill 0.3302)
		(layers "F.Cu" "B.Cu")
		(net "U122_VCC")
	)
	(segment
		(start 74.9173 -80.6196)
		(end 74.9173 -80.5307)
		(width 0.127)
		(layer "F.Cu")
		(net "U118_VCC")
	)
	(segment
		(start 74.9173 -81.7118)
		(end 74.9173 -80.6196)
		(width 0.127)
		(layer "F.Cu")
		(net "U118_VCC")
	)
	(segment
		(start 74.264012 -79.877412)
		(end 74.264012 -78.965806)
		(width 0.127)
		(layer "F.Cu")
		(net "U118_VCC")
	)
	(segment
		(start 74.9173 -80.5307)
		(end 74.264012 -79.877412)
		(width 0.127)
		(layer "F.Cu")
		(net "U118_VCC")
	)
	(via
		(at 74.9173 -80.6196)
		(size 0.6604)
		(drill 0.3302)
		(layers "F.Cu" "B.Cu")
		(net "U118_VCC")
	)
	(segment
		(start 63.627 -24.13)
		(end 63.246 -24.13)
		(width 0.127)
		(layer "F.Cu")
		(net "SCC_FULL_PWR_EN_U49")
	)
	(segment
		(start 63.034926 -23.918926)
		(end 63.034926 -22.326346)
		(width 0.127)
		(layer "F.Cu")
		(net "SCC_FULL_PWR_EN_U49")
	)
	(segment
		(start 64.8335 -24.13)
		(end 63.627 -24.13)
		(width 0.127)
		(layer "F.Cu")
		(net "SCC_FULL_PWR_EN_U49")
	)
	(segment
		(start 64.8335 -22.86)
		(end 64.8335 -24.13)
		(width 0.127)
		(layer "F.Cu")
		(net "SCC_FULL_PWR_EN_U49")
	)
	(segment
		(start 63.246 -24.13)
		(end 63.034926 -23.918926)
		(width 0.127)
		(layer "F.Cu")
		(net "SCC_FULL_PWR_EN_U49")
	)
	(via
		(at 63.627 -24.13)
		(size 0.6604)
		(drill 0.3302)
		(layers "F.Cu" "B.Cu")
		(net "SCC_FULL_PWR_EN_U49")
	)
	(via
		(at 173.912784 -60.063126)
		(size 0.6096)
		(drill 0.3048)
		(layers "F.Cu" "B.Cu")
		(net "SCC_FULL_PGOOD_SENSE")
	)
	(segment
		(start 173.04766 -60.063126)
		(end 172.8089 -60.301886)
		(width 0.127)
		(layer "B.Cu")
		(net "SCC_FULL_PGOOD_SENSE")
	)
	(segment
		(start 175.26 -60.063126)
		(end 173.912784 -60.063126)
		(width 0.127)
		(layer "B.Cu")
		(net "SCC_FULL_PGOOD_SENSE")
	)
	(segment
		(start 172.8089 -61.244734)
		(end 172.399706 -61.653928)
		(width 0.127)
		(layer "B.Cu")
		(net "SCC_FULL_PGOOD_SENSE")
	)
	(segment
		(start 172.399706 -61.653928)
		(end 172.399706 -62.251336)
		(width 0.127)
		(layer "B.Cu")
		(net "SCC_FULL_PGOOD_SENSE")
	)
	(segment
		(start 172.8089 -60.301886)
		(end 172.8089 -61.244734)
		(width 0.127)
		(layer "B.Cu")
		(net "SCC_FULL_PGOOD_SENSE")
	)
	(segment
		(start 173.912784 -60.063126)
		(end 173.04766 -60.063126)
		(width 0.127)
		(layer "B.Cu")
		(net "SCC_FULL_PGOOD_SENSE")
	)
	(segment
		(start 163.091114 -13.73632)
		(end 162.110166 -14.717268)
		(width 0.127)
		(layer "F.Cu")
		(net "DRIVE_INSERT_ALERT_N")
	)
	(segment
		(start 161.783522 -14.717268)
		(end 160.87979 -15.621)
		(width 0.127)
		(layer "F.Cu")
		(net "DRIVE_INSERT_ALERT_N")
	)
	(segment
		(start 162.110166 -14.717268)
		(end 161.783522 -14.717268)
		(width 0.127)
		(layer "F.Cu")
		(net "DRIVE_INSERT_ALERT_N")
	)
	(segment
		(start 160.87979 -15.621)
		(end 159.893 -15.621)
		(width 0.127)
		(layer "F.Cu")
		(net "DRIVE_INSERT_ALERT_N")
	)
	(segment
		(start 163.091114 -12.056872)
		(end 163.091114 -13.73632)
		(width 0.127)
		(layer "F.Cu")
		(net "DRIVE_INSERT_ALERT_N")
	)
	(via
		(at 159.893 -15.621)
		(size 0.508)
		(drill 0.254)
		(layers "F.Cu" "B.Cu")
		(net "DRIVE_INSERT_ALERT_N")
	)
	(via
		(at 161.783522 -14.717268)
		(size 0.6604)
		(drill 0.3302)
		(layers "F.Cu" "B.Cu")
		(net "DRIVE_INSERT_ALERT_N")
	)
	(via
		(at 95.22841 -44.816268)
		(size 0.508)
		(drill 0.254)
		(layers "F.Cu" "B.Cu")
		(net "DRIVE_INSERT_ALERT_N")
	)
	(via
		(at 85.273388 -24.021796)
		(size 0.508)
		(drill 0.254)
		(layers "F.Cu" "B.Cu")
		(net "DRIVE_INSERT_ALERT_N")
	)
	(segment
		(start 95.22841 -44.816268)
		(end 95.270066 -44.857924)
		(width 0.127)
		(layer "In2.Cu")
		(net "DRIVE_INSERT_ALERT_N")
	)
	(segment
		(start 102.832662 -13.312902)
		(end 102.832662 -8.56742)
		(width 0.127)
		(layer "In2.Cu")
		(net "DRIVE_INSERT_ALERT_N")
	)
	(segment
		(start 92.123768 -24.021796)
		(end 102.832662 -13.312902)
		(width 0.127)
		(layer "In2.Cu")
		(net "DRIVE_INSERT_ALERT_N")
	)
	(segment
		(start 102.31247 -44.857924)
		(end 108.675424 -38.49497)
		(width 0.127)
		(layer "In2.Cu")
		(net "DRIVE_INSERT_ALERT_N")
	)
	(segment
		(start 150.42388 -22.33168)
		(end 157.13456 -15.621)
		(width 0.127)
		(layer "In2.Cu")
		(net "DRIVE_INSERT_ALERT_N")
	)
	(segment
		(start 157.13456 -15.621)
		(end 159.893 -15.621)
		(width 0.127)
		(layer "In2.Cu")
		(net "DRIVE_INSERT_ALERT_N")
	)
	(segment
		(start 85.273388 -24.021796)
		(end 92.123768 -24.021796)
		(width 0.127)
		(layer "In2.Cu")
		(net "DRIVE_INSERT_ALERT_N")
	)
	(segment
		(start 95.270066 -44.857924)
		(end 102.31247 -44.857924)
		(width 0.127)
		(layer "In2.Cu")
		(net "DRIVE_INSERT_ALERT_N")
	)
	(segment
		(start 122.38355 -38.49497)
		(end 138.54684 -22.33168)
		(width 0.127)
		(layer "In2.Cu")
		(net "DRIVE_INSERT_ALERT_N")
	)
	(segment
		(start 108.675424 -38.49497)
		(end 122.38355 -38.49497)
		(width 0.127)
		(layer "In2.Cu")
		(net "DRIVE_INSERT_ALERT_N")
	)
	(segment
		(start 138.54684 -22.33168)
		(end 150.42388 -22.33168)
		(width 0.127)
		(layer "In2.Cu")
		(net "DRIVE_INSERT_ALERT_N")
	)
	(segment
		(start 102.832662 -8.56742)
		(end 104.000046 -7.400036)
		(width 0.127)
		(layer "In2.Cu")
		(net "DRIVE_INSERT_ALERT_N")
	)
	(segment
		(start 90.861642 -41.739058)
		(end 93.465142 -44.342558)
		(width 0.127)
		(layer "In5.Cu")
		(net "DRIVE_INSERT_ALERT_N")
	)
	(segment
		(start 89.893394 -28.641802)
		(end 89.893394 -34.527236)
		(width 0.127)
		(layer "In5.Cu")
		(net "DRIVE_INSERT_ALERT_N")
	)
	(segment
		(start 90.861642 -35.495484)
		(end 90.861642 -41.739058)
		(width 0.127)
		(layer "In5.Cu")
		(net "DRIVE_INSERT_ALERT_N")
	)
	(segment
		(start 93.465142 -44.342558)
		(end 94.7547 -44.342558)
		(width 0.127)
		(layer "In5.Cu")
		(net "DRIVE_INSERT_ALERT_N")
	)
	(segment
		(start 89.893394 -34.527236)
		(end 90.861642 -35.495484)
		(width 0.127)
		(layer "In5.Cu")
		(net "DRIVE_INSERT_ALERT_N")
	)
	(segment
		(start 94.7547 -44.342558)
		(end 95.22841 -44.816268)
		(width 0.127)
		(layer "In5.Cu")
		(net "DRIVE_INSERT_ALERT_N")
	)
	(segment
		(start 85.273388 -24.021796)
		(end 89.893394 -28.641802)
		(width 0.127)
		(layer "In5.Cu")
		(net "DRIVE_INSERT_ALERT_N")
	)
	(segment
		(start 162.078162 -3.3274)
		(end 162.078162 -4.2672)
		(width 0.127)
		(layer "F.Cu")
		(net "DRIVE_INSERT_ALERT_LS_N")
	)
	(segment
		(start 162.691064 -6.418072)
		(end 162.691064 -5.345938)
		(width 0.127)
		(layer "F.Cu")
		(net "DRIVE_INSERT_ALERT_LS_N")
	)
	(segment
		(start 116.500148 -73.500234)
		(end 117.00002 -74.000106)
		(width 0.127)
		(layer "F.Cu")
		(net "DRIVE_INSERT_ALERT_LS_N")
	)
	(segment
		(start 162.078162 -4.733036)
		(end 162.078162 -4.2672)
		(width 0.127)
		(layer "F.Cu")
		(net "DRIVE_INSERT_ALERT_LS_N")
	)
	(segment
		(start 162.691064 -5.345938)
		(end 162.078162 -4.733036)
		(width 0.127)
		(layer "F.Cu")
		(net "DRIVE_INSERT_ALERT_LS_N")
	)
	(via
		(at 162.078162 -4.2672)
		(size 0.6604)
		(drill 0.3302)
		(layers "F.Cu" "B.Cu")
		(net "DRIVE_INSERT_ALERT_LS_N")
	)
	(via
		(at 162.078162 -3.3274)
		(size 0.508)
		(drill 0.254)
		(layers "F.Cu" "B.Cu")
		(net "DRIVE_INSERT_ALERT_LS_N")
	)
	(via
		(at 117.00002 -74.000106)
		(size 0.4572)
		(drill 0.2032)
		(layers "F.Cu" "B.Cu")
		(net "DRIVE_INSERT_ALERT_LS_N")
	)
	(via
		(at 124.333 -94.2848)
		(size 0.508)
		(drill 0.254)
		(layers "F.Cu" "B.Cu")
		(net "DRIVE_INSERT_ALERT_LS_N")
	)
	(segment
		(start 124.1806 -94.4372)
		(end 124.333 -94.2848)
		(width 0.127)
		(layer "B.Cu")
		(net "DRIVE_INSERT_ALERT_LS_N")
	)
	(segment
		(start 122.3645 -94.4372)
		(end 124.1806 -94.4372)
		(width 0.127)
		(layer "B.Cu")
		(net "DRIVE_INSERT_ALERT_LS_N")
	)
	(segment
		(start 123.049284 -79.606394)
		(end 121.505218 -78.062328)
		(width 0.127)
		(layer "In2.Cu")
		(net "DRIVE_INSERT_ALERT_LS_N")
	)
	(segment
		(start 125.952758 -85.509862)
		(end 123.393708 -82.950812)
		(width 0.127)
		(layer "In2.Cu")
		(net "DRIVE_INSERT_ALERT_LS_N")
	)
	(segment
		(start 123.393708 -79.836772)
		(end 123.16333 -79.606394)
		(width 0.127)
		(layer "In2.Cu")
		(net "DRIVE_INSERT_ALERT_LS_N")
	)
	(segment
		(start 123.393708 -82.950812)
		(end 123.393708 -79.836772)
		(width 0.127)
		(layer "In2.Cu")
		(net "DRIVE_INSERT_ALERT_LS_N")
	)
	(segment
		(start 125.952758 -89.319354)
		(end 125.952758 -85.509862)
		(width 0.127)
		(layer "In2.Cu")
		(net "DRIVE_INSERT_ALERT_LS_N")
	)
	(segment
		(start 124.8029 -91.8083)
		(end 124.8029 -90.469212)
		(width 0.127)
		(layer "In2.Cu")
		(net "DRIVE_INSERT_ALERT_LS_N")
	)
	(segment
		(start 121.505218 -76.948284)
		(end 121.163334 -76.6064)
		(width 0.127)
		(layer "In2.Cu")
		(net "DRIVE_INSERT_ALERT_LS_N")
	)
	(segment
		(start 124.333 -94.2848)
		(end 124.9299 -93.6879)
		(width 0.127)
		(layer "In2.Cu")
		(net "DRIVE_INSERT_ALERT_LS_N")
	)
	(segment
		(start 120.1674 -74.422)
		(end 119.2022 -74.422)
		(width 0.127)
		(layer "In2.Cu")
		(net "DRIVE_INSERT_ALERT_LS_N")
	)
	(segment
		(start 124.8029 -90.469212)
		(end 125.952758 -89.319354)
		(width 0.127)
		(layer "In2.Cu")
		(net "DRIVE_INSERT_ALERT_LS_N")
	)
	(segment
		(start 121.163334 -76.6064)
		(end 121.162318 -76.6064)
		(width 0.127)
		(layer "In2.Cu")
		(net "DRIVE_INSERT_ALERT_LS_N")
	)
	(segment
		(start 120.501918 -75.946)
		(end 120.501918 -74.756518)
		(width 0.127)
		(layer "In2.Cu")
		(net "DRIVE_INSERT_ALERT_LS_N")
	)
	(segment
		(start 121.162318 -76.6064)
		(end 120.501918 -75.946)
		(width 0.127)
		(layer "In2.Cu")
		(net "DRIVE_INSERT_ALERT_LS_N")
	)
	(segment
		(start 123.16333 -79.606394)
		(end 123.049284 -79.606394)
		(width 0.127)
		(layer "In2.Cu")
		(net "DRIVE_INSERT_ALERT_LS_N")
	)
	(segment
		(start 118.780306 -74.000106)
		(end 117.00002 -74.000106)
		(width 0.127)
		(layer "In2.Cu")
		(net "DRIVE_INSERT_ALERT_LS_N")
	)
	(segment
		(start 121.505218 -78.062328)
		(end 121.505218 -76.948284)
		(width 0.127)
		(layer "In2.Cu")
		(net "DRIVE_INSERT_ALERT_LS_N")
	)
	(segment
		(start 124.9299 -93.6879)
		(end 124.9299 -91.9353)
		(width 0.127)
		(layer "In2.Cu")
		(net "DRIVE_INSERT_ALERT_LS_N")
	)
	(segment
		(start 119.2022 -74.422)
		(end 118.780306 -74.000106)
		(width 0.127)
		(layer "In2.Cu")
		(net "DRIVE_INSERT_ALERT_LS_N")
	)
	(segment
		(start 120.501918 -74.756518)
		(end 120.1674 -74.422)
		(width 0.127)
		(layer "In2.Cu")
		(net "DRIVE_INSERT_ALERT_LS_N")
	)
	(segment
		(start 124.9299 -91.9353)
		(end 124.8029 -91.8083)
		(width 0.127)
		(layer "In2.Cu")
		(net "DRIVE_INSERT_ALERT_LS_N")
	)
	(segment
		(start 119.0498 -74.4601)
		(end 118.589806 -74.000106)
		(width 0.127)
		(layer "In5.Cu")
		(net "DRIVE_INSERT_ALERT_LS_N")
	)
	(segment
		(start 150.365206 -57.706514)
		(end 150.365206 -64.436752)
		(width 0.127)
		(layer "In5.Cu")
		(net "DRIVE_INSERT_ALERT_LS_N")
	)
	(segment
		(start 151.284178 -41.23436)
		(end 151.284178 -56.787542)
		(width 0.127)
		(layer "In5.Cu")
		(net "DRIVE_INSERT_ALERT_LS_N")
	)
	(segment
		(start 130.215386 -75.522328)
		(end 121.7041 -75.522328)
		(width 0.127)
		(layer "In5.Cu")
		(net "DRIVE_INSERT_ALERT_LS_N")
	)
	(segment
		(start 135.180832 -73.299574)
		(end 132.593334 -75.887072)
		(width 0.127)
		(layer "In5.Cu")
		(net "DRIVE_INSERT_ALERT_LS_N")
	)
	(segment
		(start 157.918658 -3.3274)
		(end 155.16733 -6.078728)
		(width 0.127)
		(layer "In5.Cu")
		(net "DRIVE_INSERT_ALERT_LS_N")
	)
	(segment
		(start 120.641872 -74.4601)
		(end 119.0498 -74.4601)
		(width 0.127)
		(layer "In5.Cu")
		(net "DRIVE_INSERT_ALERT_LS_N")
	)
	(segment
		(start 151.284178 -56.787542)
		(end 150.365206 -57.706514)
		(width 0.127)
		(layer "In5.Cu")
		(net "DRIVE_INSERT_ALERT_LS_N")
	)
	(segment
		(start 162.078162 -3.3274)
		(end 157.918658 -3.3274)
		(width 0.127)
		(layer "In5.Cu")
		(net "DRIVE_INSERT_ALERT_LS_N")
	)
	(segment
		(start 121.7041 -75.522328)
		(end 120.641872 -74.4601)
		(width 0.127)
		(layer "In5.Cu")
		(net "DRIVE_INSERT_ALERT_LS_N")
	)
	(segment
		(start 150.365206 -64.436752)
		(end 141.502384 -73.299574)
		(width 0.127)
		(layer "In5.Cu")
		(net "DRIVE_INSERT_ALERT_LS_N")
	)
	(segment
		(start 155.16733 -6.078728)
		(end 155.16733 -31.02864)
		(width 0.127)
		(layer "In5.Cu")
		(net "DRIVE_INSERT_ALERT_LS_N")
	)
	(segment
		(start 141.502384 -73.299574)
		(end 135.180832 -73.299574)
		(width 0.127)
		(layer "In5.Cu")
		(net "DRIVE_INSERT_ALERT_LS_N")
	)
	(segment
		(start 155.16733 -31.02864)
		(end 152.811734 -33.384236)
		(width 0.127)
		(layer "In5.Cu")
		(net "DRIVE_INSERT_ALERT_LS_N")
	)
	(segment
		(start 152.811734 -39.706804)
		(end 151.284178 -41.23436)
		(width 0.127)
		(layer "In5.Cu")
		(net "DRIVE_INSERT_ALERT_LS_N")
	)
	(segment
		(start 152.811734 -33.384236)
		(end 152.811734 -39.706804)
		(width 0.127)
		(layer "In5.Cu")
		(net "DRIVE_INSERT_ALERT_LS_N")
	)
	(segment
		(start 132.593334 -75.887072)
		(end 130.58013 -75.887072)
		(width 0.127)
		(layer "In5.Cu")
		(net "DRIVE_INSERT_ALERT_LS_N")
	)
	(segment
		(start 130.58013 -75.887072)
		(end 130.215386 -75.522328)
		(width 0.127)
		(layer "In5.Cu")
		(net "DRIVE_INSERT_ALERT_LS_N")
	)
	(segment
		(start 118.589806 -74.000106)
		(end 117.00002 -74.000106)
		(width 0.127)
		(layer "In5.Cu")
		(net "DRIVE_INSERT_ALERT_LS_N")
	)
	(segment
		(start 120.071896 -85.234018)
		(end 120.071896 -84.82076)
		(width 0.127)
		(layer "F.Cu")
		(net "EXP_GPIO15")
	)
	(segment
		(start 120.071896 -86.441788)
		(end 119.963184 -86.5505)
		(width 0.127)
		(layer "F.Cu")
		(net "EXP_GPIO15")
	)
	(segment
		(start 119.518176 -89.005156)
		(end 119.518176 -88.096598)
		(width 0.127)
		(layer "F.Cu")
		(net "EXP_GPIO15")
	)
	(segment
		(start 119.308626 -87.205058)
		(end 119.963184 -86.5505)
		(width 0.127)
		(layer "F.Cu")
		(net "EXP_GPIO15")
	)
	(segment
		(start 119.518176 -88.096598)
		(end 119.308626 -87.887048)
		(width 0.127)
		(layer "F.Cu")
		(net "EXP_GPIO15")
	)
	(segment
		(start 118.500144 -83.249008)
		(end 118.500144 -82.500216)
		(width 0.127)
		(layer "F.Cu")
		(net "EXP_GPIO15")
	)
	(segment
		(start 119.378984 -89.144348)
		(end 119.518176 -89.005156)
		(width 0.127)
		(layer "F.Cu")
		(net "EXP_GPIO15")
	)
	(segment
		(start 119.308626 -87.887048)
		(end 119.308626 -87.205058)
		(width 0.127)
		(layer "F.Cu")
		(net "EXP_GPIO15")
	)
	(segment
		(start 120.071896 -84.82076)
		(end 118.500144 -83.249008)
		(width 0.127)
		(layer "F.Cu")
		(net "EXP_GPIO15")
	)
	(segment
		(start 120.071896 -85.234018)
		(end 120.071896 -86.441788)
		(width 0.127)
		(layer "F.Cu")
		(net "EXP_GPIO15")
	)
	(via
		(at 120.071896 -85.234018)
		(size 0.6604)
		(drill 0.3302)
		(layers "F.Cu" "B.Cu")
		(net "EXP_GPIO15")
	)
	(segment
		(start 115.50015 -73.500234)
		(end 116.000022 -74.000106)
		(width 0.127)
		(layer "F.Cu")
		(net "EXP_GPIO14")
	)
	(via
		(at 115.499896 -76.499974)
		(size 0.6096)
		(drill 0.3048)
		(layers "F.Cu" "B.Cu")
		(net "EXP_GPIO14")
	)
	(via
		(at 116.000022 -74.000106)
		(size 0.4572)
		(drill 0.2032)
		(layers "F.Cu" "B.Cu")
		(net "EXP_GPIO14")
	)
	(segment
		(start 115.389914 -88.796114)
		(end 115.389914 -89.31656)
		(width 0.127)
		(layer "B.Cu")
		(net "EXP_GPIO14")
	)
	(segment
		(start 116.198904 -77.4192)
		(end 116.523008 -77.743304)
		(width 0.127)
		(layer "B.Cu")
		(net "EXP_GPIO14")
	)
	(segment
		(start 115.5954 -79.728822)
		(end 115.5954 -80.1878)
		(width 0.127)
		(layer "B.Cu")
		(net "EXP_GPIO14")
	)
	(segment
		(start 115.455446 -85.915754)
		(end 115.1636 -86.2076)
		(width 0.127)
		(layer "B.Cu")
		(net "EXP_GPIO14")
	)
	(segment
		(start 115.886992 -83.755992)
		(end 116.1161 -83.9851)
		(width 0.127)
		(layer "B.Cu")
		(net "EXP_GPIO14")
	)
	(segment
		(start 115.455446 -85.514688)
		(end 115.455446 -85.915754)
		(width 0.127)
		(layer "B.Cu")
		(net "EXP_GPIO14")
	)
	(segment
		(start 115.499896 -74.898504)
		(end 116.000022 -74.398378)
		(width 0.127)
		(layer "B.Cu")
		(net "EXP_GPIO14")
	)
	(segment
		(start 115.886992 -82.079592)
		(end 115.886992 -83.755992)
		(width 0.127)
		(layer "B.Cu")
		(net "EXP_GPIO14")
	)
	(segment
		(start 116.523008 -79.178912)
		(end 116.274342 -79.427578)
		(width 0.127)
		(layer "B.Cu")
		(net "EXP_GPIO14")
	)
	(segment
		(start 116.274342 -79.427578)
		(end 115.896644 -79.427578)
		(width 0.127)
		(layer "B.Cu")
		(net "EXP_GPIO14")
	)
	(segment
		(start 116.523008 -77.743304)
		(end 116.523008 -79.178912)
		(width 0.127)
		(layer "B.Cu")
		(net "EXP_GPIO14")
	)
	(segment
		(start 115.499896 -76.499974)
		(end 115.499896 -74.898504)
		(width 0.127)
		(layer "B.Cu")
		(net "EXP_GPIO14")
	)
	(segment
		(start 115.499896 -76.499974)
		(end 115.499896 -77.183488)
		(width 0.127)
		(layer "B.Cu")
		(net "EXP_GPIO14")
	)
	(segment
		(start 115.1636 -88.5698)
		(end 115.389914 -88.796114)
		(width 0.127)
		(layer "B.Cu")
		(net "EXP_GPIO14")
	)
	(segment
		(start 115.5954 -80.1878)
		(end 115.2271 -80.5561)
		(width 0.127)
		(layer "B.Cu")
		(net "EXP_GPIO14")
	)
	(segment
		(start 116.1161 -84.854034)
		(end 115.455446 -85.514688)
		(width 0.127)
		(layer "B.Cu")
		(net "EXP_GPIO14")
	)
	(segment
		(start 115.1636 -86.2076)
		(end 115.1636 -88.5698)
		(width 0.127)
		(layer "B.Cu")
		(net "EXP_GPIO14")
	)
	(segment
		(start 115.499896 -77.183488)
		(end 115.735608 -77.4192)
		(width 0.127)
		(layer "B.Cu")
		(net "EXP_GPIO14")
	)
	(segment
		(start 115.2271 -81.4197)
		(end 115.886992 -82.079592)
		(width 0.127)
		(layer "B.Cu")
		(net "EXP_GPIO14")
	)
	(segment
		(start 115.2271 -80.5561)
		(end 115.2271 -81.4197)
		(width 0.127)
		(layer "B.Cu")
		(net "EXP_GPIO14")
	)
	(segment
		(start 115.735608 -77.4192)
		(end 116.198904 -77.4192)
		(width 0.127)
		(layer "B.Cu")
		(net "EXP_GPIO14")
	)
	(segment
		(start 116.1161 -83.9851)
		(end 116.1161 -84.854034)
		(width 0.127)
		(layer "B.Cu")
		(net "EXP_GPIO14")
	)
	(segment
		(start 115.389914 -89.31656)
		(end 115.389914 -90.51417)
		(width 0.127)
		(layer "B.Cu")
		(net "EXP_GPIO14")
	)
	(segment
		(start 115.896644 -79.427578)
		(end 115.5954 -79.728822)
		(width 0.127)
		(layer "B.Cu")
		(net "EXP_GPIO14")
	)
	(segment
		(start 116.000022 -74.398378)
		(end 116.000022 -74.000106)
		(width 0.127)
		(layer "B.Cu")
		(net "EXP_GPIO14")
	)
	(segment
		(start 122.809 -85.945726)
		(end 122.809 -85.344)
		(width 0.127)
		(layer "F.Cu")
		(net "EXP_GPIO13")
	)
	(segment
		(start 122.969274 -88.333326)
		(end 122.969274 -86.106)
		(width 0.127)
		(layer "F.Cu")
		(net "EXP_GPIO13")
	)
	(segment
		(start 121.3231 -89.1032)
		(end 120.357138 -90.069162)
		(width 0.127)
		(layer "F.Cu")
		(net "EXP_GPIO13")
	)
	(segment
		(start 118.500144 -81.500218)
		(end 118.893844 -81.893918)
		(width 0.127)
		(layer "F.Cu")
		(net "EXP_GPIO13")
	)
	(segment
		(start 122.809 -84.963)
		(end 122.809 -85.344)
		(width 0.127)
		(layer "F.Cu")
		(net "EXP_GPIO13")
	)
	(segment
		(start 121.3231 -89.1032)
		(end 122.1994 -89.1032)
		(width 0.127)
		(layer "F.Cu")
		(net "EXP_GPIO13")
	)
	(segment
		(start 122.969274 -86.106)
		(end 122.809 -85.945726)
		(width 0.127)
		(layer "F.Cu")
		(net "EXP_GPIO13")
	)
	(segment
		(start 118.893844 -83.264248)
		(end 120.088406 -84.45881)
		(width 0.127)
		(layer "F.Cu")
		(net "EXP_GPIO13")
	)
	(segment
		(start 120.357138 -90.069162)
		(end 120.357138 -91.094052)
		(width 0.127)
		(layer "F.Cu")
		(net "EXP_GPIO13")
	)
	(segment
		(start 122.30481 -84.45881)
		(end 122.809 -84.963)
		(width 0.127)
		(layer "F.Cu")
		(net "EXP_GPIO13")
	)
	(segment
		(start 122.1994 -89.1032)
		(end 122.969274 -88.333326)
		(width 0.127)
		(layer "F.Cu")
		(net "EXP_GPIO13")
	)
	(segment
		(start 120.088406 -84.45881)
		(end 122.30481 -84.45881)
		(width 0.127)
		(layer "F.Cu")
		(net "EXP_GPIO13")
	)
	(segment
		(start 118.893844 -81.893918)
		(end 118.893844 -83.264248)
		(width 0.127)
		(layer "F.Cu")
		(net "EXP_GPIO13")
	)
	(via
		(at 122.809 -85.344)
		(size 0.6604)
		(drill 0.3302)
		(layers "F.Cu" "B.Cu")
		(net "EXP_GPIO13")
	)
	(segment
		(start 12.7635 -48.4378)
		(end 12.7635 -47.5488)
		(width 0.254)
		(layer "F.Cu")
		(net "MB0_HS_SENSE_P")
	)
	(segment
		(start 12.7635 -48.682402)
		(end 13.694664 -49.613566)
		(width 0.254)
		(layer "F.Cu")
		(net "MB0_HS_SENSE_P")
	)
	(segment
		(start 12.7635 -47.5488)
		(end 12.827 -47.4853)
		(width 0.254)
		(layer "F.Cu")
		(net "MB0_HS_SENSE_P")
	)
	(segment
		(start 12.7635 -48.4378)
		(end 12.7635 -48.682402)
		(width 0.254)
		(layer "F.Cu")
		(net "MB0_HS_SENSE_P")
	)
	(segment
		(start 13.694664 -49.613566)
		(end 13.694664 -50.7873)
		(width 0.254)
		(layer "F.Cu")
		(net "MB0_HS_SENSE_P")
	)
	(segment
		(start 13.194538 -49.903888)
		(end 13.194538 -50.7873)
		(width 0.254)
		(layer "F.Cu")
		(net "MB0_HS_SENSE_N")
	)
	(segment
		(start 11.8745 -47.5488)
		(end 11.811 -47.4853)
		(width 0.254)
		(layer "F.Cu")
		(net "MB0_HS_SENSE_N")
	)
	(segment
		(start 11.8745 -48.4378)
		(end 11.8745 -47.5488)
		(width 0.254)
		(layer "F.Cu")
		(net "MB0_HS_SENSE_N")
	)
	(segment
		(start 11.8745 -48.4378)
		(end 11.8745 -48.58385)
		(width 0.254)
		(layer "F.Cu")
		(net "MB0_HS_SENSE_N")
	)
	(segment
		(start 11.8745 -48.58385)
		(end 13.194538 -49.903888)
		(width 0.254)
		(layer "F.Cu")
		(net "MB0_HS_SENSE_N")
	)
	(segment
		(start 124.000006 -82.00009)
		(end 124.000006 -81.000092)
		(width 0.127)
		(layer "F.Cu")
		(net "EXP_RGMII_RXC")
	)
	(segment
		(start 124.000006 -81.000092)
		(end 123.500134 -80.50022)
		(width 0.127)
		(layer "F.Cu")
		(net "EXP_RGMII_RXC")
	)
	(via
		(at 126.0602 -96.24949)
		(size 0.508)
		(drill 0.254)
		(layers "F.Cu" "B.Cu")
		(net "EXP_RGMII_RXC")
	)
	(via
		(at 125.7427 -94.910148)
		(size 0.6096)
		(drill 0.3048)
		(layers "F.Cu" "B.Cu")
		(net "EXP_RGMII_RXC")
	)
	(via
		(at 124.000006 -82.00009)
		(size 0.4572)
		(drill 0.2032)
		(layers "F.Cu" "B.Cu")
		(net "EXP_RGMII_RXC")
	)
	(segment
		(start 125.7427 -95.93199)
		(end 126.0602 -96.24949)
		(width 0.127)
		(layer "B.Cu")
		(net "EXP_RGMII_RXC")
	)
	(segment
		(start 125.7427 -93.5609)
		(end 125.7427 -94.910148)
		(width 0.127)
		(layer "B.Cu")
		(net "EXP_RGMII_RXC")
	)
	(segment
		(start 125.7427 -94.910148)
		(end 125.7427 -95.93199)
		(width 0.127)
		(layer "B.Cu")
		(net "EXP_RGMII_RXC")
	)
	(segment
		(start 124.000006 -82.00009)
		(end 124.000006 -82.557366)
		(width 0.127)
		(layer "In2.Cu")
		(net "EXP_RGMII_RXC")
	)
	(segment
		(start 125.984 -84.9884)
		(end 126.7206 -85.725)
		(width 0.127)
		(layer "In2.Cu")
		(net "EXP_RGMII_RXC")
	)
	(segment
		(start 125.984 -84.54136)
		(end 125.984 -84.9884)
		(width 0.127)
		(layer "In2.Cu")
		(net "EXP_RGMII_RXC")
	)
	(segment
		(start 126.7206 -85.725)
		(end 126.7206 -87.6808)
		(width 0.127)
		(layer "In2.Cu")
		(net "EXP_RGMII_RXC")
	)
	(segment
		(start 126.212854 -92.670884)
		(end 126.3142 -92.77223)
		(width 0.127)
		(layer "In2.Cu")
		(net "EXP_RGMII_RXC")
	)
	(segment
		(start 127 -89.2302)
		(end 126.1999 -90.0303)
		(width 0.127)
		(layer "In2.Cu")
		(net "EXP_RGMII_RXC")
	)
	(segment
		(start 126.7206 -87.6808)
		(end 127 -87.9602)
		(width 0.127)
		(layer "In2.Cu")
		(net "EXP_RGMII_RXC")
	)
	(segment
		(start 124.000006 -82.557366)
		(end 125.984 -84.54136)
		(width 0.127)
		(layer "In2.Cu")
		(net "EXP_RGMII_RXC")
	)
	(segment
		(start 126.212854 -91.446858)
		(end 126.212854 -92.670884)
		(width 0.127)
		(layer "In2.Cu")
		(net "EXP_RGMII_RXC")
	)
	(segment
		(start 126.3142 -95.99549)
		(end 126.0602 -96.24949)
		(width 0.127)
		(layer "In2.Cu")
		(net "EXP_RGMII_RXC")
	)
	(segment
		(start 126.1999 -91.433904)
		(end 126.212854 -91.446858)
		(width 0.127)
		(layer "In2.Cu")
		(net "EXP_RGMII_RXC")
	)
	(segment
		(start 126.3142 -92.77223)
		(end 126.3142 -95.99549)
		(width 0.127)
		(layer "In2.Cu")
		(net "EXP_RGMII_RXC")
	)
	(segment
		(start 127 -87.9602)
		(end 127 -89.2302)
		(width 0.127)
		(layer "In2.Cu")
		(net "EXP_RGMII_RXC")
	)
	(segment
		(start 126.1999 -90.0303)
		(end 126.1999 -91.433904)
		(width 0.127)
		(layer "In2.Cu")
		(net "EXP_RGMII_RXC")
	)
	(via
		(at 167.6019 -10.803636)
		(size 0.6096)
		(drill 0.3048)
		(layers "F.Cu" "B.Cu")
		(net "U50_OE")
	)
	(segment
		(start 167.161464 -9.31164)
		(end 167.161464 -9.783064)
		(width 0.127)
		(layer "B.Cu")
		(net "U50_OE")
	)
	(segment
		(start 167.161464 -9.783064)
		(end 167.6019 -10.2235)
		(width 0.127)
		(layer "B.Cu")
		(net "U50_OE")
	)
	(segment
		(start 167.6019 -10.2235)
		(end 167.6019 -10.803636)
		(width 0.127)
		(layer "B.Cu")
		(net "U50_OE")
	)
	(segment
		(start 167.600122 -11.872722)
		(end 167.6019 -11.8745)
		(width 0.127)
		(layer "B.Cu")
		(net "U50_OE")
	)
	(segment
		(start 166.636954 -11.872722)
		(end 167.600122 -11.872722)
		(width 0.127)
		(layer "B.Cu")
		(net "U50_OE")
	)
	(segment
		(start 167.6019 -10.803636)
		(end 167.6019 -11.8745)
		(width 0.127)
		(layer "B.Cu")
		(net "U50_OE")
	)
	(segment
		(start 60.67552 -17.859248)
		(end 61.641228 -17.859248)
		(width 0.127)
		(layer "F.Cu")
		(net "U49_OE")
	)
	(segment
		(start 61.734446 -20.675346)
		(end 61.734446 -20.04822)
		(width 0.127)
		(layer "F.Cu")
		(net "U49_OE")
	)
	(segment
		(start 61.654182 -18.904712)
		(end 61.654182 -17.846294)
		(width 0.127)
		(layer "F.Cu")
		(net "U49_OE")
	)
	(segment
		(start 61.641228 -17.859248)
		(end 61.654182 -17.846294)
		(width 0.127)
		(layer "F.Cu")
		(net "U49_OE")
	)
	(segment
		(start 61.654182 -19.967956)
		(end 61.654182 -18.904712)
		(width 0.127)
		(layer "F.Cu")
		(net "U49_OE")
	)
	(segment
		(start 61.734446 -20.04822)
		(end 61.654182 -19.967956)
		(width 0.127)
		(layer "F.Cu")
		(net "U49_OE")
	)
	(via
		(at 61.654182 -18.904712)
		(size 0.6604)
		(drill 0.3302)
		(layers "F.Cu" "B.Cu")
		(net "U49_OE")
	)
	(segment
		(start 187.87872 -107.6706)
		(end 188.3664 -107.6706)
		(width 0.127)
		(layer "F.Cu")
		(net "P1V8_C_S")
	)
	(segment
		(start 188.76264 -109.17682)
		(end 188.84392 -109.2581)
		(width 0.127)
		(layer "F.Cu")
		(net "P1V8_C_S")
	)
	(segment
		(start 187.53328 -108.89742)
		(end 187.72378 -108.70692)
		(width 0.127)
		(layer "F.Cu")
		(net "P1V8_C_S")
	)
	(segment
		(start 187.53328 -108.99648)
		(end 187.53328 -108.89742)
		(width 0.127)
		(layer "F.Cu")
		(net "P1V8_C_S")
	)
	(segment
		(start 187.72378 -107.82554)
		(end 187.87872 -107.6706)
		(width 0.127)
		(layer "F.Cu")
		(net "P1V8_C_S")
	)
	(segment
		(start 188.84392 -109.2581)
		(end 188.84392 -109.76356)
		(width 0.127)
		(layer "F.Cu")
		(net "P1V8_C_S")
	)
	(segment
		(start 187.43041 -109.09935)
		(end 187.53328 -108.99648)
		(width 0.127)
		(layer "F.Cu")
		(net "P1V8_C_S")
	)
	(segment
		(start 187.43041 -110.19536)
		(end 187.43041 -109.09935)
		(width 0.127)
		(layer "F.Cu")
		(net "P1V8_C_S")
	)
	(segment
		(start 188.76264 -108.77296)
		(end 188.76264 -109.17682)
		(width 0.127)
		(layer "F.Cu")
		(net "P1V8_C_S")
	)
	(segment
		(start 188.76264 -108.06684)
		(end 188.76264 -108.77296)
		(width 0.127)
		(layer "F.Cu")
		(net "P1V8_C_S")
	)
	(segment
		(start 187.72378 -108.70692)
		(end 187.72378 -107.82554)
		(width 0.127)
		(layer "F.Cu")
		(net "P1V8_C_S")
	)
	(segment
		(start 188.3664 -107.6706)
		(end 188.76264 -108.06684)
		(width 0.127)
		(layer "F.Cu")
		(net "P1V8_C_S")
	)
	(via
		(at 187.87872 -107.6706)
		(size 0.508)
		(drill 0.254)
		(layers "F.Cu" "B.Cu")
		(net "P1V8_C_S")
	)
	(via
		(at 188.76264 -108.77296)
		(size 0.6604)
		(drill 0.3302)
		(layers "F.Cu" "B.Cu")
		(net "P1V8_C_S")
	)
	(segment
		(start 187.87872 -109.00156)
		(end 187.87872 -107.6706)
		(width 0.127)
		(layer "B.Cu")
		(net "P1V8_C_S")
	)
	(segment
		(start 142.86484 -117.36578)
		(end 142.86484 -116.22532)
		(width 0.127)
		(layer "F.Cu")
		(net "P1V5_C_S")
	)
	(via
		(at 142.86484 -116.22532)
		(size 0.508)
		(drill 0.254)
		(layers "F.Cu" "B.Cu")
		(net "P1V5_C_S")
	)
	(via
		(at 142.660878 -117.160294)
		(size 0.6096)
		(drill 0.3048)
		(layers "F.Cu" "B.Cu")
		(net "P1V5_C_S")
	)
	(segment
		(start 143.888206 -117.115844)
		(end 143.888206 -117.160294)
		(width 0.127)
		(layer "B.Cu")
		(net "P1V5_C_S")
	)
	(segment
		(start 141.6685 -118.1735)
		(end 142.02791 -118.53291)
		(width 0.127)
		(layer "B.Cu")
		(net "P1V5_C_S")
	)
	(segment
		(start 142.997682 -116.22532)
		(end 143.888206 -117.115844)
		(width 0.127)
		(layer "B.Cu")
		(net "P1V5_C_S")
	)
	(segment
		(start 141.6685 -117.16004)
		(end 141.6685 -118.1735)
		(width 0.127)
		(layer "B.Cu")
		(net "P1V5_C_S")
	)
	(segment
		(start 142.02791 -118.53291)
		(end 142.96517 -118.53291)
		(width 0.127)
		(layer "B.Cu")
		(net "P1V5_C_S")
	)
	(segment
		(start 142.660624 -117.16004)
		(end 141.6685 -117.16004)
		(width 0.127)
		(layer "B.Cu")
		(net "P1V5_C_S")
	)
	(segment
		(start 142.660878 -117.160294)
		(end 143.888206 -117.160294)
		(width 0.127)
		(layer "B.Cu")
		(net "P1V5_C_S")
	)
	(segment
		(start 142.86484 -116.22532)
		(end 142.997682 -116.22532)
		(width 0.127)
		(layer "B.Cu")
		(net "P1V5_C_S")
	)
	(segment
		(start 142.660878 -117.160294)
		(end 142.660624 -117.16004)
		(width 0.127)
		(layer "B.Cu")
		(net "P1V5_C_S")
	)
	(segment
		(start 41.8846 -31.3182)
		(end 42.1894 -31.623)
		(width 0.127)
		(layer "F.Cu")
		(net "P0V9_U8_PG")
	)
	(segment
		(start 43.610276 -31.977076)
		(end 43.610276 -32.650938)
		(width 0.127)
		(layer "F.Cu")
		(net "P0V9_U8_PG")
	)
	(segment
		(start 41.5417 -29.8958)
		(end 41.5417 -30.9753)
		(width 0.127)
		(layer "F.Cu")
		(net "P0V9_U8_PG")
	)
	(segment
		(start 41.5417 -30.9753)
		(end 41.8846 -31.3182)
		(width 0.127)
		(layer "F.Cu")
		(net "P0V9_U8_PG")
	)
	(segment
		(start 41.5417 -28.8036)
		(end 41.5417 -27.6987)
		(width 0.127)
		(layer "F.Cu")
		(net "P0V9_U8_PG")
	)
	(segment
		(start 43.2562 -31.623)
		(end 43.610276 -31.977076)
		(width 0.127)
		(layer "F.Cu")
		(net "P0V9_U8_PG")
	)
	(segment
		(start 42.1894 -31.623)
		(end 43.2562 -31.623)
		(width 0.127)
		(layer "F.Cu")
		(net "P0V9_U8_PG")
	)
	(segment
		(start 41.5417 -29.8958)
		(end 41.5417 -28.8036)
		(width 0.127)
		(layer "F.Cu")
		(net "P0V9_U8_PG")
	)
	(via
		(at 41.8846 -31.3182)
		(size 0.6604)
		(drill 0.3302)
		(layers "F.Cu" "B.Cu")
		(net "P0V9_U8_PG")
	)
	(segment
		(start 118.500144 -78.500224)
		(end 119.000016 -79.000096)
		(width 0.127)
		(layer "F.Cu")
		(net "EXP_GPIO12")
	)
	(via
		(at 119.000016 -79.000096)
		(size 0.4572)
		(drill 0.2032)
		(layers "F.Cu" "B.Cu")
		(net "EXP_GPIO12")
	)
	(segment
		(start 119.3038 -79.000096)
		(end 119.000016 -79.000096)
		(width 0.127)
		(layer "B.Cu")
		(net "EXP_GPIO12")
	)
	(segment
		(start 119.462296 -78.8416)
		(end 119.3038 -79.000096)
		(width 0.127)
		(layer "B.Cu")
		(net "EXP_GPIO12")
	)
	(segment
		(start 120.0404 -78.8416)
		(end 119.462296 -78.8416)
		(width 0.127)
		(layer "B.Cu")
		(net "EXP_GPIO12")
	)
	(segment
		(start 17.972278 -101.08057)
		(end 17.145 -101.08057)
		(width 0.127)
		(layer "F.Cu")
		(net "U119_EN")
	)
	(segment
		(start 17.145 -101.08057)
		(end 16.87957 -101.346)
		(width 0.127)
		(layer "F.Cu")
		(net "U119_EN")
	)
	(segment
		(start 15.45082 -101.44506)
		(end 16.33474 -101.44506)
		(width 0.127)
		(layer "F.Cu")
		(net "U119_EN")
	)
	(segment
		(start 16.33474 -101.44506)
		(end 16.4338 -101.346)
		(width 0.127)
		(layer "F.Cu")
		(net "U119_EN")
	)
	(segment
		(start 15.4559 -101.45014)
		(end 15.45082 -101.44506)
		(width 0.127)
		(layer "F.Cu")
		(net "U119_EN")
	)
	(segment
		(start 15.4559 -102.4001)
		(end 15.4559 -101.45014)
		(width 0.127)
		(layer "F.Cu")
		(net "U119_EN")
	)
	(segment
		(start 16.87957 -101.346)
		(end 16.4338 -101.346)
		(width 0.127)
		(layer "F.Cu")
		(net "U119_EN")
	)
	(via
		(at 16.4338 -101.346)
		(size 0.6604)
		(drill 0.3302)
		(layers "F.Cu" "B.Cu")
		(net "U119_EN")
	)
	(segment
		(start 72.262492 -79.806292)
		(end 72.262492 -78.965806)
		(width 0.127)
		(layer "F.Cu")
		(net "PCIE_COMP_TO_SCC_RST_R_0")
	)
	(segment
		(start 73.5076 -83.947)
		(end 73.152 -83.5914)
		(width 0.127)
		(layer "F.Cu")
		(net "PCIE_COMP_TO_SCC_RST_R_0")
	)
	(segment
		(start 72.4916 -80.0354)
		(end 72.262492 -79.806292)
		(width 0.127)
		(layer "F.Cu")
		(net "PCIE_COMP_TO_SCC_RST_R_0")
	)
	(segment
		(start 73.152 -80.791304)
		(end 72.967596 -80.6069)
		(width 0.127)
		(layer "F.Cu")
		(net "PCIE_COMP_TO_SCC_RST_R_0")
	)
	(segment
		(start 72.4916 -80.6069)
		(end 72.4916 -80.0354)
		(width 0.127)
		(layer "F.Cu")
		(net "PCIE_COMP_TO_SCC_RST_R_0")
	)
	(segment
		(start 73.152 -83.5914)
		(end 73.152 -80.791304)
		(width 0.127)
		(layer "F.Cu")
		(net "PCIE_COMP_TO_SCC_RST_R_0")
	)
	(segment
		(start 75.9714 -82.423)
		(end 75.9714 -80.3656)
		(width 0.127)
		(layer "F.Cu")
		(net "PCIE_COMP_TO_SCC_RST_R_0")
	)
	(segment
		(start 75.9714 -80.3656)
		(end 75.564492 -79.958692)
		(width 0.127)
		(layer "F.Cu")
		(net "PCIE_COMP_TO_SCC_RST_R_0")
	)
	(segment
		(start 72.967596 -80.6069)
		(end 72.4916 -80.6069)
		(width 0.127)
		(layer "F.Cu")
		(net "PCIE_COMP_TO_SCC_RST_R_0")
	)
	(segment
		(start 75.7428 -83.947)
		(end 73.5076 -83.947)
		(width 0.127)
		(layer "F.Cu")
		(net "PCIE_COMP_TO_SCC_RST_R_0")
	)
	(segment
		(start 75.9714 -83.7184)
		(end 75.7428 -83.947)
		(width 0.127)
		(layer "F.Cu")
		(net "PCIE_COMP_TO_SCC_RST_R_0")
	)
	(segment
		(start 75.564492 -79.958692)
		(end 75.564492 -78.965806)
		(width 0.127)
		(layer "F.Cu")
		(net "PCIE_COMP_TO_SCC_RST_R_0")
	)
	(segment
		(start 75.9714 -82.423)
		(end 75.9714 -83.7184)
		(width 0.127)
		(layer "F.Cu")
		(net "PCIE_COMP_TO_SCC_RST_R_0")
	)
	(via
		(at 75.9714 -82.423)
		(size 0.6604)
		(drill 0.3302)
		(layers "F.Cu" "B.Cu")
		(net "PCIE_COMP_TO_SCC_RST_R_0")
	)
	(segment
		(start 23.7998 -100.2411)
		(end 22.7584 -100.2411)
		(width 0.127)
		(layer "F.Cu")
		(net "SCC_STBY_PGOOD_R")
	)
	(segment
		(start 21.469604 -100.43033)
		(end 21.472144 -100.43287)
		(width 0.127)
		(layer "F.Cu")
		(net "SCC_STBY_PGOOD_R")
	)
	(segment
		(start 22.56663 -100.43287)
		(end 21.472144 -100.43287)
		(width 0.127)
		(layer "F.Cu")
		(net "SCC_STBY_PGOOD_R")
	)
	(segment
		(start 19.623278 -100.43033)
		(end 21.469604 -100.43033)
		(width 0.127)
		(layer "F.Cu")
		(net "SCC_STBY_PGOOD_R")
	)
	(segment
		(start 22.7584 -100.2411)
		(end 22.56663 -100.43287)
		(width 0.127)
		(layer "F.Cu")
		(net "SCC_STBY_PGOOD_R")
	)
	(via
		(at 21.472144 -100.43287)
		(size 0.6604)
		(drill 0.3302)
		(layers "F.Cu" "B.Cu")
		(net "SCC_STBY_PGOOD_R")
	)
	(segment
		(start 67.3735 -94.1578)
		(end 67.358514 -94.142814)
		(width 0.127)
		(layer "F.Cu")
		(net "SCC_STBY_PGOOD_BUF")
	)
	(segment
		(start 23.6601 -98.4504)
		(end 22.7584 -99.3521)
		(width 0.127)
		(layer "F.Cu")
		(net "SCC_STBY_PGOOD_BUF")
	)
	(segment
		(start 65.9892 -106.7689)
		(end 65.9765 -106.7562)
		(width 0.127)
		(layer "F.Cu")
		(net "SCC_STBY_PGOOD_BUF")
	)
	(segment
		(start 65.9765 -104.013)
		(end 65.475104 -103.511604)
		(width 0.127)
		(layer "F.Cu")
		(net "SCC_STBY_PGOOD_BUF")
	)
	(segment
		(start 20.854924 -99.78009)
		(end 21.472144 -99.16287)
		(width 0.127)
		(layer "F.Cu")
		(net "SCC_STBY_PGOOD_BUF")
	)
	(segment
		(start 22.04847 -99.16287)
		(end 21.472144 -99.16287)
		(width 0.127)
		(layer "F.Cu")
		(net "SCC_STBY_PGOOD_BUF")
	)
	(segment
		(start 27.325828 -99.381564)
		(end 26.394664 -98.4504)
		(width 0.127)
		(layer "F.Cu")
		(net "SCC_STBY_PGOOD_BUF")
	)
	(segment
		(start 67.358514 -92.788486)
		(end 67.691 -92.456)
		(width 0.127)
		(layer "F.Cu")
		(net "SCC_STBY_PGOOD_BUF")
	)
	(segment
		(start 67.358514 -94.142814)
		(end 67.358514 -92.788486)
		(width 0.127)
		(layer "F.Cu")
		(net "SCC_STBY_PGOOD_BUF")
	)
	(segment
		(start 65.9765 -104.6734)
		(end 65.9765 -106.7562)
		(width 0.127)
		(layer "F.Cu")
		(net "SCC_STBY_PGOOD_BUF")
	)
	(segment
		(start 65.9765 -104.6734)
		(end 65.9765 -104.013)
		(width 0.127)
		(layer "F.Cu")
		(net "SCC_STBY_PGOOD_BUF")
	)
	(segment
		(start 19.623278 -99.78009)
		(end 20.854924 -99.78009)
		(width 0.127)
		(layer "F.Cu")
		(net "SCC_STBY_PGOOD_BUF")
	)
	(segment
		(start 26.394664 -98.4504)
		(end 23.6601 -98.4504)
		(width 0.127)
		(layer "F.Cu")
		(net "SCC_STBY_PGOOD_BUF")
	)
	(segment
		(start 65.9892 -107.5436)
		(end 65.9892 -106.7689)
		(width 0.127)
		(layer "F.Cu")
		(net "SCC_STBY_PGOOD_BUF")
	)
	(segment
		(start 22.2377 -99.3521)
		(end 22.04847 -99.16287)
		(width 0.127)
		(layer "F.Cu")
		(net "SCC_STBY_PGOOD_BUF")
	)
	(segment
		(start 22.7584 -99.3521)
		(end 22.2377 -99.3521)
		(width 0.127)
		(layer "F.Cu")
		(net "SCC_STBY_PGOOD_BUF")
	)
	(segment
		(start 65.475104 -103.511604)
		(end 65.475104 -102.949502)
		(width 0.127)
		(layer "F.Cu")
		(net "SCC_STBY_PGOOD_BUF")
	)
	(via
		(at 27.325828 -99.381564)
		(size 0.508)
		(drill 0.254)
		(layers "F.Cu" "B.Cu")
		(net "SCC_STBY_PGOOD_BUF")
	)
	(via
		(at 65.9892 -107.5436)
		(size 0.508)
		(drill 0.254)
		(layers "F.Cu" "B.Cu")
		(net "SCC_STBY_PGOOD_BUF")
	)
	(via
		(at 21.472144 -99.16287)
		(size 0.6604)
		(drill 0.3302)
		(layers "F.Cu" "B.Cu")
		(net "SCC_STBY_PGOOD_BUF")
	)
	(via
		(at 67.691 -92.456)
		(size 0.508)
		(drill 0.254)
		(layers "F.Cu" "B.Cu")
		(net "SCC_STBY_PGOOD_BUF")
	)
	(segment
		(start 27.325828 -99.381564)
		(end 27.325828 -104.679496)
		(width 0.127)
		(layer "In5.Cu")
		(net "SCC_STBY_PGOOD_BUF")
	)
	(segment
		(start 65.9892 -114.1476)
		(end 65.9892 -107.5436)
		(width 0.127)
		(layer "In5.Cu")
		(net "SCC_STBY_PGOOD_BUF")
	)
	(segment
		(start 64.5922 -115.5446)
		(end 65.9892 -114.1476)
		(width 0.127)
		(layer "In5.Cu")
		(net "SCC_STBY_PGOOD_BUF")
	)
	(segment
		(start 65.9892 -104.815386)
		(end 67.691 -103.113586)
		(width 0.127)
		(layer "In5.Cu")
		(net "SCC_STBY_PGOOD_BUF")
	)
	(segment
		(start 38.190932 -115.5446)
		(end 64.5922 -115.5446)
		(width 0.127)
		(layer "In5.Cu")
		(net "SCC_STBY_PGOOD_BUF")
	)
	(segment
		(start 27.325828 -104.679496)
		(end 38.190932 -115.5446)
		(width 0.127)
		(layer "In5.Cu")
		(net "SCC_STBY_PGOOD_BUF")
	)
	(segment
		(start 65.9892 -107.5436)
		(end 65.9892 -104.815386)
		(width 0.127)
		(layer "In5.Cu")
		(net "SCC_STBY_PGOOD_BUF")
	)
	(segment
		(start 67.691 -103.113586)
		(end 67.691 -92.456)
		(width 0.127)
		(layer "In5.Cu")
		(net "SCC_STBY_PGOOD_BUF")
	)
	(segment
		(start 6.5278 -100.5713)
		(end 6.7437 -100.5713)
		(width 0.127)
		(layer "F.Cu")
		(net "SCC_FULL_PGOOD_BUF_R")
	)
	(segment
		(start 9.3599 -100.584)
		(end 8.001 -100.584)
		(width 0.127)
		(layer "F.Cu")
		(net "SCC_FULL_PGOOD_BUF_R")
	)
	(segment
		(start 7.0358 -100.8634)
		(end 7.7216 -100.8634)
		(width 0.127)
		(layer "F.Cu")
		(net "SCC_FULL_PGOOD_BUF_R")
	)
	(segment
		(start 8.001 -100.584)
		(end 7.7216 -100.8634)
		(width 0.127)
		(layer "F.Cu")
		(net "SCC_FULL_PGOOD_BUF_R")
	)
	(segment
		(start 6.7437 -100.5713)
		(end 7.0358 -100.8634)
		(width 0.127)
		(layer "F.Cu")
		(net "SCC_FULL_PGOOD_BUF_R")
	)
	(segment
		(start 6.5278 -99.5553)
		(end 6.5278 -100.5713)
		(width 0.127)
		(layer "F.Cu")
		(net "SCC_FULL_PGOOD_BUF_R")
	)
	(via
		(at 7.7216 -100.8634)
		(size 0.6604)
		(drill 0.3302)
		(layers "F.Cu" "B.Cu")
		(net "SCC_FULL_PGOOD_BUF_R")
	)
	(segment
		(start 7.1628 -97.2566)
		(end 7.65556 -96.76384)
		(width 0.127)
		(layer "F.Cu")
		(net "SCC_FULL_PGOOD_BUF")
	)
	(segment
		(start 15.5194 -97.9424)
		(end 27.188414 -97.9424)
		(width 0.127)
		(layer "F.Cu")
		(net "SCC_FULL_PGOOD_BUF")
	)
	(segment
		(start 27.188414 -97.9424)
		(end 28.610052 -99.364038)
		(width 0.127)
		(layer "F.Cu")
		(net "SCC_FULL_PGOOD_BUF")
	)
	(segment
		(start 7.65556 -96.76384)
		(end 14.34084 -96.76384)
		(width 0.127)
		(layer "F.Cu")
		(net "SCC_FULL_PGOOD_BUF")
	)
	(segment
		(start 6.5278 -97.8916)
		(end 7.1628 -97.2566)
		(width 0.127)
		(layer "F.Cu")
		(net "SCC_FULL_PGOOD_BUF")
	)
	(segment
		(start 6.5278 -98.6663)
		(end 6.5278 -97.8916)
		(width 0.127)
		(layer "F.Cu")
		(net "SCC_FULL_PGOOD_BUF")
	)
	(segment
		(start 14.34084 -96.76384)
		(end 15.5194 -97.9424)
		(width 0.127)
		(layer "F.Cu")
		(net "SCC_FULL_PGOOD_BUF")
	)
	(via
		(at 58.5216 -88.392)
		(size 0.508)
		(drill 0.254)
		(layers "F.Cu" "B.Cu")
		(net "SCC_FULL_PGOOD_BUF")
	)
	(via
		(at 7.1628 -97.2566)
		(size 0.6604)
		(drill 0.3302)
		(layers "F.Cu" "B.Cu")
		(net "SCC_FULL_PGOOD_BUF")
	)
	(via
		(at 28.610052 -99.364038)
		(size 0.508)
		(drill 0.254)
		(layers "F.Cu" "B.Cu")
		(net "SCC_FULL_PGOOD_BUF")
	)
	(segment
		(start 28.996386 -94.142814)
		(end 28.996386 -98.977704)
		(width 0.127)
		(layer "B.Cu")
		(net "SCC_FULL_PGOOD_BUF")
	)
	(segment
		(start 28.996386 -98.977704)
		(end 28.610052 -99.364038)
		(width 0.127)
		(layer "B.Cu")
		(net "SCC_FULL_PGOOD_BUF")
	)
	(segment
		(start 58.5216 -88.392)
		(end 34.7472 -88.392)
		(width 0.127)
		(layer "B.Cu")
		(net "SCC_FULL_PGOOD_BUF")
	)
	(segment
		(start 34.7472 -88.392)
		(end 28.996386 -94.142814)
		(width 0.127)
		(layer "B.Cu")
		(net "SCC_FULL_PGOOD_BUF")
	)
	(segment
		(start 60.055252 -79.43723)
		(end 57.818782 -81.6737)
		(width 0.127)
		(layer "In2.Cu")
		(net "SCC_FULL_PGOOD_BUF")
	)
	(segment
		(start 149.702266 -13.478002)
		(end 146.191224 -16.989044)
		(width 0.127)
		(layer "In2.Cu")
		(net "SCC_FULL_PGOOD_BUF")
	)
	(segment
		(start 62.135258 -79.43723)
		(end 60.055252 -79.43723)
		(width 0.127)
		(layer "In2.Cu")
		(net "SCC_FULL_PGOOD_BUF")
	)
	(segment
		(start 83.80476 -48.332644)
		(end 81.065878 -51.071526)
		(width 0.127)
		(layer "In2.Cu")
		(net "SCC_FULL_PGOOD_BUF")
	)
	(segment
		(start 146.191224 -16.989044)
		(end 136.393428 -16.989044)
		(width 0.127)
		(layer "In2.Cu")
		(net "SCC_FULL_PGOOD_BUF")
	)
	(segment
		(start 57.818782 -87.689182)
		(end 58.5216 -88.392)
		(width 0.127)
		(layer "In2.Cu")
		(net "SCC_FULL_PGOOD_BUF")
	)
	(segment
		(start 149.702266 -8.302498)
		(end 149.702266 -13.478002)
		(width 0.127)
		(layer "In2.Cu")
		(net "SCC_FULL_PGOOD_BUF")
	)
	(segment
		(start 74.734674 -67.571112)
		(end 74.001376 -67.571112)
		(width 0.127)
		(layer "In2.Cu")
		(net "SCC_FULL_PGOOD_BUF")
	)
	(segment
		(start 121.048272 -32.3342)
		(end 88.344502 -32.3342)
		(width 0.127)
		(layer "In2.Cu")
		(net "SCC_FULL_PGOOD_BUF")
	)
	(segment
		(start 83.80476 -36.873942)
		(end 83.80476 -48.332644)
		(width 0.127)
		(layer "In2.Cu")
		(net "SCC_FULL_PGOOD_BUF")
	)
	(segment
		(start 81.065878 -60.074556)
		(end 76.775056 -64.365378)
		(width 0.127)
		(layer "In2.Cu")
		(net "SCC_FULL_PGOOD_BUF")
	)
	(segment
		(start 76.775056 -64.365378)
		(end 76.775056 -65.53073)
		(width 0.127)
		(layer "In2.Cu")
		(net "SCC_FULL_PGOOD_BUF")
	)
	(segment
		(start 57.818782 -81.6737)
		(end 57.818782 -87.689182)
		(width 0.127)
		(layer "In2.Cu")
		(net "SCC_FULL_PGOOD_BUF")
	)
	(segment
		(start 88.344502 -32.3342)
		(end 83.80476 -36.873942)
		(width 0.127)
		(layer "In2.Cu")
		(net "SCC_FULL_PGOOD_BUF")
	)
	(segment
		(start 74.001376 -67.571112)
		(end 62.135258 -79.43723)
		(width 0.127)
		(layer "In2.Cu")
		(net "SCC_FULL_PGOOD_BUF")
	)
	(segment
		(start 148.999956 -7.600188)
		(end 149.702266 -8.302498)
		(width 0.127)
		(layer "In2.Cu")
		(net "SCC_FULL_PGOOD_BUF")
	)
	(segment
		(start 81.065878 -51.071526)
		(end 81.065878 -60.074556)
		(width 0.127)
		(layer "In2.Cu")
		(net "SCC_FULL_PGOOD_BUF")
	)
	(segment
		(start 76.775056 -65.53073)
		(end 74.734674 -67.571112)
		(width 0.127)
		(layer "In2.Cu")
		(net "SCC_FULL_PGOOD_BUF")
	)
	(segment
		(start 136.393428 -16.989044)
		(end 121.048272 -32.3342)
		(width 0.127)
		(layer "In2.Cu")
		(net "SCC_FULL_PGOOD_BUF")
	)
	(segment
		(start 167.99052 -102.108)
		(end 169.7101 -103.82758)
		(width 0.127)
		(layer "F.Cu")
		(net "P0V975_STAT")
	)
	(segment
		(start 166.31158 -100.23094)
		(end 167.12692 -99.4156)
		(width 0.127)
		(layer "F.Cu")
		(net "P0V975_STAT")
	)
	(segment
		(start 169.7101 -108.73994)
		(end 169.8371 -108.86694)
		(width 0.127)
		(layer "F.Cu")
		(net "P0V975_STAT")
	)
	(segment
		(start 167.7289 -99.4156)
		(end 168.0591 -99.0854)
		(width 0.127)
		(layer "F.Cu")
		(net "P0V975_STAT")
	)
	(segment
		(start 169.7101 -103.82758)
		(end 169.7101 -108.73994)
		(width 0.127)
		(layer "F.Cu")
		(net "P0V975_STAT")
	)
	(segment
		(start 168.0591 -99.0854)
		(end 168.0591 -98.651822)
		(width 0.127)
		(layer "F.Cu")
		(net "P0V975_STAT")
	)
	(segment
		(start 170.69816 -108.86694)
		(end 170.955716 -109.124496)
		(width 0.127)
		(layer "F.Cu")
		(net "P0V975_STAT")
	)
	(segment
		(start 167.99052 -100.86086)
		(end 167.99052 -102.108)
		(width 0.127)
		(layer "F.Cu")
		(net "P0V975_STAT")
	)
	(segment
		(start 167.12692 -99.4156)
		(end 167.7289 -99.4156)
		(width 0.127)
		(layer "F.Cu")
		(net "P0V975_STAT")
	)
	(segment
		(start 168.91 -97.800922)
		(end 168.91 -97.17151)
		(width 0.127)
		(layer "F.Cu")
		(net "P0V975_STAT")
	)
	(segment
		(start 167.3606 -100.23094)
		(end 167.99052 -100.86086)
		(width 0.127)
		(layer "F.Cu")
		(net "P0V975_STAT")
	)
	(segment
		(start 168.0591 -98.651822)
		(end 168.91 -97.800922)
		(width 0.127)
		(layer "F.Cu")
		(net "P0V975_STAT")
	)
	(segment
		(start 169.8371 -108.86694)
		(end 170.69816 -108.86694)
		(width 0.127)
		(layer "F.Cu")
		(net "P0V975_STAT")
	)
	(segment
		(start 166.31158 -100.23094)
		(end 167.34536 -100.23094)
		(width 0.127)
		(layer "F.Cu")
		(net "P0V975_STAT")
	)
	(segment
		(start 170.955716 -109.124496)
		(end 170.955716 -109.716824)
		(width 0.127)
		(layer "F.Cu")
		(net "P0V975_STAT")
	)
	(segment
		(start 167.34536 -100.23094)
		(end 167.3606 -100.23094)
		(width 0.127)
		(layer "F.Cu")
		(net "P0V975_STAT")
	)
	(via
		(at 168.0591 -99.0854)
		(size 0.6604)
		(drill 0.3302)
		(layers "F.Cu" "B.Cu")
		(net "P0V975_STAT")
	)
	(segment
		(start 13.3096 -62.768226)
		(end 13.3096 -67.5894)
		(width 0.127)
		(layer "F.Cu")
		(net "MB0_HS_ENABLE_R")
	)
	(segment
		(start 14.351 -59.582558)
		(end 14.361414 -59.572144)
		(width 0.127)
		(layer "F.Cu")
		(net "MB0_HS_ENABLE_R")
	)
	(segment
		(start 7.1501 -67.5132)
		(end 10.4521 -67.5132)
		(width 0.127)
		(layer "F.Cu")
		(net "MB0_HS_ENABLE_R")
	)
	(segment
		(start 10.4521 -67.5132)
		(end 10.5283 -67.5894)
		(width 0.127)
		(layer "F.Cu")
		(net "MB0_HS_ENABLE_R")
	)
	(segment
		(start 10.8204 -68.4784)
		(end 10.5283 -68.1863)
		(width 0.127)
		(layer "F.Cu")
		(net "MB0_HS_ENABLE_R")
	)
	(segment
		(start 10.5283 -68.1863)
		(end 10.5283 -67.5894)
		(width 0.127)
		(layer "F.Cu")
		(net "MB0_HS_ENABLE_R")
	)
	(segment
		(start 14.351 -60.9092)
		(end 14.351 -61.726826)
		(width 0.127)
		(layer "F.Cu")
		(net "MB0_HS_ENABLE_R")
	)
	(segment
		(start 12.4206 -68.4784)
		(end 10.8204 -68.4784)
		(width 0.127)
		(layer "F.Cu")
		(net "MB0_HS_ENABLE_R")
	)
	(segment
		(start 14.351 -60.9092)
		(end 14.351 -59.582558)
		(width 0.127)
		(layer "F.Cu")
		(net "MB0_HS_ENABLE_R")
	)
	(segment
		(start 14.351 -61.726826)
		(end 13.3096 -62.768226)
		(width 0.127)
		(layer "F.Cu")
		(net "MB0_HS_ENABLE_R")
	)
	(segment
		(start 13.3096 -67.5894)
		(end 12.4206 -68.4784)
		(width 0.127)
		(layer "F.Cu")
		(net "MB0_HS_ENABLE_R")
	)
	(via
		(at 14.351 -60.9092)
		(size 0.6604)
		(drill 0.3302)
		(layers "F.Cu" "B.Cu")
		(net "MB0_HS_ENABLE_R")
	)
	(segment
		(start 88.8365 -78.232)
		(end 88.8365 -79.274162)
		(width 0.127)
		(layer "F.Cu")
		(net "EXP_RESET_R_U23_N")
	)
	(segment
		(start 89.775538 -80.2132)
		(end 90.2208 -80.2132)
		(width 0.127)
		(layer "F.Cu")
		(net "EXP_RESET_R_U23_N")
	)
	(segment
		(start 89.240614 -79.678276)
		(end 89.775538 -80.2132)
		(width 0.127)
		(layer "F.Cu")
		(net "EXP_RESET_R_U23_N")
	)
	(segment
		(start 88.8365 -79.274162)
		(end 89.240614 -79.678276)
		(width 0.127)
		(layer "F.Cu")
		(net "EXP_RESET_R_U23_N")
	)
	(via
		(at 89.240614 -79.678276)
		(size 0.6604)
		(drill 0.3302)
		(layers "F.Cu" "B.Cu")
		(net "EXP_RESET_R_U23_N")
	)
	(via
		(at 90.2208 -80.2132)
		(size 0.508)
		(drill 0.254)
		(layers "F.Cu" "B.Cu")
		(net "EXP_RESET_R_U23_N")
	)
	(segment
		(start 91.0717 -80.78089)
		(end 91.0717 -81.2546)
		(width 0.127)
		(layer "B.Cu")
		(net "EXP_RESET_R_U23_N")
	)
	(segment
		(start 90.2208 -80.2132)
		(end 90.50401 -80.2132)
		(width 0.127)
		(layer "B.Cu")
		(net "EXP_RESET_R_U23_N")
	)
	(segment
		(start 90.50401 -80.2132)
		(end 91.0717 -80.78089)
		(width 0.127)
		(layer "B.Cu")
		(net "EXP_RESET_R_U23_N")
	)
	(segment
		(start 84.45119 -111.668814)
		(end 84.444332 -111.675672)
		(width 0.127)
		(layer "F.Cu")
		(net "U48_OE")
	)
	(segment
		(start 84.45119 -110.6805)
		(end 84.45119 -111.668814)
		(width 0.127)
		(layer "F.Cu")
		(net "U48_OE")
	)
	(segment
		(start 84.444332 -112.645952)
		(end 84.438744 -112.65154)
		(width 0.127)
		(layer "F.Cu")
		(net "U48_OE")
	)
	(segment
		(start 84.45119 -110.6805)
		(end 84.45119 -109.006894)
		(width 0.127)
		(layer "F.Cu")
		(net "U48_OE")
	)
	(segment
		(start 84.444332 -111.675672)
		(end 84.444332 -112.645952)
		(width 0.127)
		(layer "F.Cu")
		(net "U48_OE")
	)
	(via
		(at 84.45119 -110.6805)
		(size 0.6604)
		(drill 0.3302)
		(layers "F.Cu" "B.Cu")
		(net "U48_OE")
	)
	(segment
		(start 56.888634 -17.84731)
		(end 56.89473 -17.841214)
		(width 0.127)
		(layer "F.Cu")
		(net "U47_OE")
	)
	(segment
		(start 56.781446 -20.675346)
		(end 56.781446 -19.316446)
		(width 0.127)
		(layer "F.Cu")
		(net "U47_OE")
	)
	(segment
		(start 56.781446 -19.316446)
		(end 56.780176 -19.315176)
		(width 0.127)
		(layer "F.Cu")
		(net "U47_OE")
	)
	(segment
		(start 56.780176 -18.530824)
		(end 56.89473 -18.41627)
		(width 0.127)
		(layer "F.Cu")
		(net "U47_OE")
	)
	(segment
		(start 56.780176 -19.315176)
		(end 56.780176 -18.898362)
		(width 0.127)
		(layer "F.Cu")
		(net "U47_OE")
	)
	(segment
		(start 55.937658 -17.84731)
		(end 56.888634 -17.84731)
		(width 0.127)
		(layer "F.Cu")
		(net "U47_OE")
	)
	(segment
		(start 56.89473 -18.41627)
		(end 56.89473 -17.841214)
		(width 0.127)
		(layer "F.Cu")
		(net "U47_OE")
	)
	(segment
		(start 56.780176 -18.898362)
		(end 56.780176 -18.530824)
		(width 0.127)
		(layer "F.Cu")
		(net "U47_OE")
	)
	(via
		(at 56.780176 -18.898362)
		(size 0.6604)
		(drill 0.3302)
		(layers "F.Cu" "B.Cu")
		(net "U47_OE")
	)
	(segment
		(start 60.1345 -21.082)
		(end 60.1345 -18.034)
		(width 0.127)
		(layer "F.Cu")
		(net "SCC_STBY_PWR_BUF_EN")
	)
	(segment
		(start 59.374786 -16.447008)
		(end 59.374786 -17.269714)
		(width 0.127)
		(layer "F.Cu")
		(net "SCC_STBY_PWR_BUF_EN")
	)
	(segment
		(start 60.1345 -21.082)
		(end 60.1345 -22.0345)
		(width 0.127)
		(layer "F.Cu")
		(net "SCC_STBY_PWR_BUF_EN")
	)
	(segment
		(start 60.1345 -22.0345)
		(end 59.842654 -22.326346)
		(width 0.127)
		(layer "F.Cu")
		(net "SCC_STBY_PWR_BUF_EN")
	)
	(segment
		(start 16.590518 -61.552582)
		(end 23.846536 -61.552582)
		(width 0.127)
		(layer "F.Cu")
		(net "SCC_STBY_PWR_BUF_EN")
	)
	(segment
		(start 59.374786 -17.269714)
		(end 59.3725 -17.272)
		(width 0.127)
		(layer "F.Cu")
		(net "SCC_STBY_PWR_BUF_EN")
	)
	(segment
		(start 59.842654 -22.326346)
		(end 58.081926 -22.326346)
		(width 0.127)
		(layer "F.Cu")
		(net "SCC_STBY_PWR_BUF_EN")
	)
	(segment
		(start 60.1345 -18.034)
		(end 59.3725 -17.272)
		(width 0.127)
		(layer "F.Cu")
		(net "SCC_STBY_PWR_BUF_EN")
	)
	(via
		(at 23.846536 -61.552582)
		(size 0.508)
		(drill 0.254)
		(layers "F.Cu" "B.Cu")
		(net "SCC_STBY_PWR_BUF_EN")
	)
	(via
		(at 60.1345 -21.082)
		(size 0.6604)
		(drill 0.3302)
		(layers "F.Cu" "B.Cu")
		(net "SCC_STBY_PWR_BUF_EN")
	)
	(via
		(at 59.374786 -16.447008)
		(size 0.508)
		(drill 0.254)
		(layers "F.Cu" "B.Cu")
		(net "SCC_STBY_PWR_BUF_EN")
	)
	(segment
		(start 26.858468 -58.54065)
		(end 23.846536 -61.552582)
		(width 0.127)
		(layer "In5.Cu")
		(net "SCC_STBY_PWR_BUF_EN")
	)
	(segment
		(start 26.858468 -40.324532)
		(end 26.858468 -58.54065)
		(width 0.127)
		(layer "In5.Cu")
		(net "SCC_STBY_PWR_BUF_EN")
	)
	(segment
		(start 32.385 -34.798)
		(end 26.858468 -40.324532)
		(width 0.127)
		(layer "In5.Cu")
		(net "SCC_STBY_PWR_BUF_EN")
	)
	(segment
		(start 52.012342 -24.822658)
		(end 34.384742 -24.822658)
		(width 0.127)
		(layer "In5.Cu")
		(net "SCC_STBY_PWR_BUF_EN")
	)
	(segment
		(start 59.374786 -17.460214)
		(end 52.012342 -24.822658)
		(width 0.127)
		(layer "In5.Cu")
		(net "SCC_STBY_PWR_BUF_EN")
	)
	(segment
		(start 59.374786 -16.447008)
		(end 59.374786 -17.460214)
		(width 0.127)
		(layer "In5.Cu")
		(net "SCC_STBY_PWR_BUF_EN")
	)
	(segment
		(start 34.384742 -24.822658)
		(end 32.385 -26.8224)
		(width 0.127)
		(layer "In5.Cu")
		(net "SCC_STBY_PWR_BUF_EN")
	)
	(segment
		(start 32.385 -26.8224)
		(end 32.385 -34.798)
		(width 0.127)
		(layer "In5.Cu")
		(net "SCC_STBY_PWR_BUF_EN")
	)
	(segment
		(start 82.825082 -103.425244)
		(end 82.953352 -103.296974)
		(width 0.127)
		(layer "F.Cu")
		(net "SCC_FULL_PWR_BUF_EN")
	)
	(segment
		(start 82.160872 -102.881176)
		(end 82.155792 -102.886256)
		(width 0.127)
		(layer "F.Cu")
		(net "SCC_FULL_PWR_BUF_EN")
	)
	(segment
		(start 173.5455 -110.0582)
		(end 173.5455 -111.204502)
		(width 0.127)
		(layer "F.Cu")
		(net "SCC_FULL_PWR_BUF_EN")
	)
	(segment
		(start 82.953352 -103.296974)
		(end 82.953352 -102.881176)
		(width 0.127)
		(layer "F.Cu")
		(net "SCC_FULL_PWR_BUF_EN")
	)
	(segment
		(start 82.953352 -102.881176)
		(end 82.160872 -102.881176)
		(width 0.127)
		(layer "F.Cu")
		(net "SCC_FULL_PWR_BUF_EN")
	)
	(segment
		(start 82.825082 -103.915464)
		(end 82.825082 -103.425244)
		(width 0.127)
		(layer "F.Cu")
		(net "SCC_FULL_PWR_BUF_EN")
	)
	(via
		(at 85.123782 -104.73436)
		(size 0.6096)
		(drill 0.3048)
		(layers "F.Cu" "B.Cu")
		(net "SCC_FULL_PWR_BUF_EN")
	)
	(via
		(at 113.03 -107.188)
		(size 0.508)
		(drill 0.254)
		(layers "F.Cu" "B.Cu")
		(net "SCC_FULL_PWR_BUF_EN")
	)
	(via
		(at 82.155792 -102.886256)
		(size 0.508)
		(drill 0.254)
		(layers "F.Cu" "B.Cu")
		(net "SCC_FULL_PWR_BUF_EN")
	)
	(via
		(at 173.5455 -111.204502)
		(size 0.508)
		(drill 0.254)
		(layers "F.Cu" "B.Cu")
		(net "SCC_FULL_PWR_BUF_EN")
	)
	(segment
		(start 84.33816 -104.73436)
		(end 85.123782 -104.73436)
		(width 0.127)
		(layer "B.Cu")
		(net "SCC_FULL_PWR_BUF_EN")
	)
	(segment
		(start 109.515402 -98.852736)
		(end 99.902264 -98.852736)
		(width 0.127)
		(layer "B.Cu")
		(net "SCC_FULL_PWR_BUF_EN")
	)
	(segment
		(start 82.490056 -102.886256)
		(end 84.33816 -104.73436)
		(width 0.127)
		(layer "B.Cu")
		(net "SCC_FULL_PWR_BUF_EN")
	)
	(segment
		(start 113.03 -107.188)
		(end 113.03 -102.367334)
		(width 0.127)
		(layer "B.Cu")
		(net "SCC_FULL_PWR_BUF_EN")
	)
	(segment
		(start 99.902264 -98.852736)
		(end 94.02064 -104.73436)
		(width 0.127)
		(layer "B.Cu")
		(net "SCC_FULL_PWR_BUF_EN")
	)
	(segment
		(start 82.155792 -102.886256)
		(end 82.490056 -102.886256)
		(width 0.127)
		(layer "B.Cu")
		(net "SCC_FULL_PWR_BUF_EN")
	)
	(segment
		(start 94.02064 -104.73436)
		(end 85.123782 -104.73436)
		(width 0.127)
		(layer "B.Cu")
		(net "SCC_FULL_PWR_BUF_EN")
	)
	(segment
		(start 113.03 -102.367334)
		(end 109.515402 -98.852736)
		(width 0.127)
		(layer "B.Cu")
		(net "SCC_FULL_PWR_BUF_EN")
	)
	(segment
		(start 113.03 -107.188)
		(end 113.284 -106.934)
		(width 0.127)
		(layer "In5.Cu")
		(net "SCC_FULL_PWR_BUF_EN")
	)
	(segment
		(start 142.98422 -117.42166)
		(end 149.79396 -117.42166)
		(width 0.127)
		(layer "In5.Cu")
		(net "SCC_FULL_PWR_BUF_EN")
	)
	(segment
		(start 149.79396 -117.42166)
		(end 152.019 -119.6467)
		(width 0.127)
		(layer "In5.Cu")
		(net "SCC_FULL_PWR_BUF_EN")
	)
	(segment
		(start 169.69486 -112.65662)
		(end 170.50766 -112.65662)
		(width 0.127)
		(layer "In5.Cu")
		(net "SCC_FULL_PWR_BUF_EN")
	)
	(segment
		(start 171.959778 -111.204502)
		(end 173.5455 -111.204502)
		(width 0.127)
		(layer "In5.Cu")
		(net "SCC_FULL_PWR_BUF_EN")
	)
	(segment
		(start 152.019 -119.6467)
		(end 162.70478 -119.6467)
		(width 0.127)
		(layer "In5.Cu")
		(net "SCC_FULL_PWR_BUF_EN")
	)
	(segment
		(start 162.70478 -119.6467)
		(end 169.69486 -112.65662)
		(width 0.127)
		(layer "In5.Cu")
		(net "SCC_FULL_PWR_BUF_EN")
	)
	(segment
		(start 170.50766 -112.65662)
		(end 171.959778 -111.204502)
		(width 0.127)
		(layer "In5.Cu")
		(net "SCC_FULL_PWR_BUF_EN")
	)
	(segment
		(start 126.2126 -114.5032)
		(end 127.17018 -115.46078)
		(width 0.127)
		(layer "In5.Cu")
		(net "SCC_FULL_PWR_BUF_EN")
	)
	(segment
		(start 127.17018 -115.46078)
		(end 141.02334 -115.46078)
		(width 0.127)
		(layer "In5.Cu")
		(net "SCC_FULL_PWR_BUF_EN")
	)
	(segment
		(start 115.689126 -106.934)
		(end 123.258326 -114.5032)
		(width 0.127)
		(layer "In5.Cu")
		(net "SCC_FULL_PWR_BUF_EN")
	)
	(segment
		(start 141.02334 -115.46078)
		(end 142.98422 -117.42166)
		(width 0.127)
		(layer "In5.Cu")
		(net "SCC_FULL_PWR_BUF_EN")
	)
	(segment
		(start 123.258326 -114.5032)
		(end 126.2126 -114.5032)
		(width 0.127)
		(layer "In5.Cu")
		(net "SCC_FULL_PWR_BUF_EN")
	)
	(segment
		(start 113.284 -106.934)
		(end 115.689126 -106.934)
		(width 0.127)
		(layer "In5.Cu")
		(net "SCC_FULL_PWR_BUF_EN")
	)
	(segment
		(start 185.399934 -39.19982)
		(end 185.000138 -38.800024)
		(width 0.127)
		(layer "F.Cu")
		(net "IOC_RESET_N")
	)
	(segment
		(start 185.000138 -38.800024)
		(end 184.999884 -38.800024)
		(width 0.127)
		(layer "F.Cu")
		(net "IOC_RESET_N")
	)
	(segment
		(start 179.031646 -27.27579)
		(end 179.031646 -28.83154)
		(width 0.127)
		(layer "F.Cu")
		(net "IOC_RESET_N")
	)
	(segment
		(start 179.031646 -28.83154)
		(end 179.399946 -29.19984)
		(width 0.127)
		(layer "F.Cu")
		(net "IOC_RESET_N")
	)
	(via
		(at 179.031646 -27.27579)
		(size 0.508)
		(drill 0.254)
		(layers "F.Cu" "B.Cu")
		(net "IOC_RESET_N")
	)
	(via
		(at 183.068976 -23.476458)
		(size 0.508)
		(drill 0.254)
		(layers "F.Cu" "B.Cu")
		(net "IOC_RESET_N")
	)
	(via
		(at 185.399934 -39.19982)
		(size 0.508)
		(drill 0.254)
		(layers "F.Cu" "B.Cu")
		(net "IOC_RESET_N")
	)
	(via
		(at 178.995832 -66.204338)
		(size 0.508)
		(drill 0.254)
		(layers "F.Cu" "B.Cu")
		(net "IOC_RESET_N")
	)
	(via
		(at 177.9524 -65.160906)
		(size 0.6096)
		(drill 0.3048)
		(layers "F.Cu" "B.Cu")
		(net "IOC_RESET_N")
	)
	(segment
		(start 171.447206 -64.943736)
		(end 171.447206 -63.958216)
		(width 0.127)
		(layer "B.Cu")
		(net "IOC_RESET_N")
	)
	(segment
		(start 179.877974 -27.4193)
		(end 180.058568 -27.599894)
		(width 0.127)
		(layer "B.Cu")
		(net "IOC_RESET_N")
	)
	(segment
		(start 178.995832 -66.204338)
		(end 177.9524 -65.160906)
		(width 0.127)
		(layer "B.Cu")
		(net "IOC_RESET_N")
	)
	(segment
		(start 171.447206 -63.958216)
		(end 171.866052 -63.53937)
		(width 0.127)
		(layer "B.Cu")
		(net "IOC_RESET_N")
	)
	(segment
		(start 180.730906 -27.599894)
		(end 181.083712 -27.247088)
		(width 0.127)
		(layer "B.Cu")
		(net "IOC_RESET_N")
	)
	(segment
		(start 183.068976 -25.04186)
		(end 183.068976 -23.476458)
		(width 0.127)
		(layer "B.Cu")
		(net "IOC_RESET_N")
	)
	(segment
		(start 175.124872 -63.53937)
		(end 176.330864 -63.53937)
		(width 0.127)
		(layer "B.Cu")
		(net "IOC_RESET_N")
	)
	(segment
		(start 176.330864 -63.53937)
		(end 177.9524 -65.160906)
		(width 0.127)
		(layer "B.Cu")
		(net "IOC_RESET_N")
	)
	(segment
		(start 179.175156 -27.4193)
		(end 179.877974 -27.4193)
		(width 0.127)
		(layer "B.Cu")
		(net "IOC_RESET_N")
	)
	(segment
		(start 171.866052 -63.53937)
		(end 175.124872 -63.53937)
		(width 0.127)
		(layer "B.Cu")
		(net "IOC_RESET_N")
	)
	(segment
		(start 181.083712 -27.247088)
		(end 181.083712 -27.027124)
		(width 0.127)
		(layer "B.Cu")
		(net "IOC_RESET_N")
	)
	(segment
		(start 179.031646 -27.27579)
		(end 179.175156 -27.4193)
		(width 0.127)
		(layer "B.Cu")
		(net "IOC_RESET_N")
	)
	(segment
		(start 181.083712 -27.027124)
		(end 183.068976 -25.04186)
		(width 0.127)
		(layer "B.Cu")
		(net "IOC_RESET_N")
	)
	(segment
		(start 180.058568 -27.599894)
		(end 180.730906 -27.599894)
		(width 0.127)
		(layer "B.Cu")
		(net "IOC_RESET_N")
	)
	(segment
		(start 182.262018 -47.181516)
		(end 182.618888 -46.824646)
		(width 0.127)
		(layer "In2.Cu")
		(net "IOC_RESET_N")
	)
	(segment
		(start 182.5879 -43.51401)
		(end 184.088024 -43.51401)
		(width 0.127)
		(layer "In2.Cu")
		(net "IOC_RESET_N")
	)
	(segment
		(start 185.824368 -39.624254)
		(end 185.399934 -39.19982)
		(width 0.127)
		(layer "In2.Cu")
		(net "IOC_RESET_N")
	)
	(segment
		(start 194.926966 -36.5506)
		(end 192.2399 -36.5506)
		(width 0.127)
		(layer "In2.Cu")
		(net "IOC_RESET_N")
	)
	(segment
		(start 182.308754 -45.56887)
		(end 182.308754 -43.793156)
		(width 0.127)
		(layer "In2.Cu")
		(net "IOC_RESET_N")
	)
	(segment
		(start 175.401732 -56.877204)
		(end 175.401732 -52.289456)
		(width 0.127)
		(layer "In2.Cu")
		(net "IOC_RESET_N")
	)
	(segment
		(start 187.66155 -23.202392)
		(end 191.344804 -23.202392)
		(width 0.127)
		(layer "In2.Cu")
		(net "IOC_RESET_N")
	)
	(segment
		(start 182.618888 -45.879004)
		(end 182.308754 -45.56887)
		(width 0.127)
		(layer "In2.Cu")
		(net "IOC_RESET_N")
	)
	(segment
		(start 195.163948 -23.701502)
		(end 198.2343 -26.771854)
		(width 0.127)
		(layer "In2.Cu")
		(net "IOC_RESET_N")
	)
	(segment
		(start 185.824368 -41.777666)
		(end 185.824368 -39.624254)
		(width 0.127)
		(layer "In2.Cu")
		(net "IOC_RESET_N")
	)
	(segment
		(start 198.2343 -33.243266)
		(end 194.926966 -36.5506)
		(width 0.127)
		(layer "In2.Cu")
		(net "IOC_RESET_N")
	)
	(segment
		(start 191.843914 -23.701502)
		(end 195.163948 -23.701502)
		(width 0.127)
		(layer "In2.Cu")
		(net "IOC_RESET_N")
	)
	(segment
		(start 178.995832 -66.204338)
		(end 176.04994 -63.258446)
		(width 0.127)
		(layer "In2.Cu")
		(net "IOC_RESET_N")
	)
	(segment
		(start 182.308754 -43.793156)
		(end 182.5879 -43.51401)
		(width 0.127)
		(layer "In2.Cu")
		(net "IOC_RESET_N")
	)
	(segment
		(start 187.387484 -23.476458)
		(end 187.66155 -23.202392)
		(width 0.127)
		(layer "In2.Cu")
		(net "IOC_RESET_N")
	)
	(segment
		(start 176.04994 -57.525412)
		(end 175.401732 -56.877204)
		(width 0.127)
		(layer "In2.Cu")
		(net "IOC_RESET_N")
	)
	(segment
		(start 198.2343 -26.771854)
		(end 198.2343 -33.243266)
		(width 0.127)
		(layer "In2.Cu")
		(net "IOC_RESET_N")
	)
	(segment
		(start 191.344804 -23.202392)
		(end 191.843914 -23.701502)
		(width 0.127)
		(layer "In2.Cu")
		(net "IOC_RESET_N")
	)
	(segment
		(start 192.2399 -36.5506)
		(end 190.7032 -38.0873)
		(width 0.127)
		(layer "In2.Cu")
		(net "IOC_RESET_N")
	)
	(segment
		(start 182.262018 -49.246536)
		(end 182.262018 -47.181516)
		(width 0.127)
		(layer "In2.Cu")
		(net "IOC_RESET_N")
	)
	(segment
		(start 175.401732 -52.289456)
		(end 177.79492 -49.896268)
		(width 0.127)
		(layer "In2.Cu")
		(net "IOC_RESET_N")
	)
	(segment
		(start 183.068976 -23.476458)
		(end 187.387484 -23.476458)
		(width 0.127)
		(layer "In2.Cu")
		(net "IOC_RESET_N")
	)
	(segment
		(start 181.612286 -49.896268)
		(end 182.262018 -49.246536)
		(width 0.127)
		(layer "In2.Cu")
		(net "IOC_RESET_N")
	)
	(segment
		(start 190.7032 -38.0873)
		(end 188.6585 -38.0873)
		(width 0.127)
		(layer "In2.Cu")
		(net "IOC_RESET_N")
	)
	(segment
		(start 182.618888 -46.824646)
		(end 182.618888 -45.879004)
		(width 0.127)
		(layer "In2.Cu")
		(net "IOC_RESET_N")
	)
	(segment
		(start 185.567574 -39.03218)
		(end 185.399934 -39.19982)
		(width 0.127)
		(layer "In2.Cu")
		(net "IOC_RESET_N")
	)
	(segment
		(start 187.71362 -39.03218)
		(end 185.567574 -39.03218)
		(width 0.127)
		(layer "In2.Cu")
		(net "IOC_RESET_N")
	)
	(segment
		(start 188.6585 -38.0873)
		(end 187.71362 -39.03218)
		(width 0.127)
		(layer "In2.Cu")
		(net "IOC_RESET_N")
	)
	(segment
		(start 176.04994 -63.258446)
		(end 176.04994 -57.525412)
		(width 0.127)
		(layer "In2.Cu")
		(net "IOC_RESET_N")
	)
	(segment
		(start 177.79492 -49.896268)
		(end 181.612286 -49.896268)
		(width 0.127)
		(layer "In2.Cu")
		(net "IOC_RESET_N")
	)
	(segment
		(start 184.088024 -43.51401)
		(end 185.824368 -41.777666)
		(width 0.127)
		(layer "In2.Cu")
		(net "IOC_RESET_N")
	)
	(segment
		(start 91.764358 -79.414116)
		(end 91.764358 -79.685642)
		(width 0.127)
		(layer "F.Cu")
		(net "EXP_RESET_N")
	)
	(segment
		(start 90.582242 -78.232)
		(end 90.90533 -78.555088)
		(width 0.127)
		(layer "F.Cu")
		(net "EXP_RESET_N")
	)
	(segment
		(start 91.764358 -79.685642)
		(end 91.2368 -80.2132)
		(width 0.127)
		(layer "F.Cu")
		(net "EXP_RESET_N")
	)
	(segment
		(start 89.7255 -78.232)
		(end 90.582242 -78.232)
		(width 0.127)
		(layer "F.Cu")
		(net "EXP_RESET_N")
	)
	(segment
		(start 90.90533 -78.555088)
		(end 91.764358 -79.414116)
		(width 0.127)
		(layer "F.Cu")
		(net "EXP_RESET_N")
	)
	(segment
		(start 110.499906 -76.500228)
		(end 110.000034 -77.0001)
		(width 0.127)
		(layer "F.Cu")
		(net "EXP_RESET_N")
	)
	(via
		(at 91.2368 -80.2132)
		(size 0.508)
		(drill 0.254)
		(layers "F.Cu" "B.Cu")
		(net "EXP_RESET_N")
	)
	(via
		(at 110.000034 -77.0001)
		(size 0.4572)
		(drill 0.2032)
		(layers "F.Cu" "B.Cu")
		(net "EXP_RESET_N")
	)
	(via
		(at 90.90533 -78.555088)
		(size 0.6604)
		(drill 0.3302)
		(layers "F.Cu" "B.Cu")
		(net "EXP_RESET_N")
	)
	(segment
		(start 92.166948 -82.255614)
		(end 92.166948 -81.143348)
		(width 0.127)
		(layer "B.Cu")
		(net "EXP_RESET_N")
	)
	(segment
		(start 92.97416 -83.57489)
		(end 92.97416 -83.062826)
		(width 0.127)
		(layer "B.Cu")
		(net "EXP_RESET_N")
	)
	(segment
		(start 92.97416 -83.062826)
		(end 92.166948 -82.255614)
		(width 0.127)
		(layer "B.Cu")
		(net "EXP_RESET_N")
	)
	(segment
		(start 92.166948 -81.143348)
		(end 91.2368 -80.2132)
		(width 0.127)
		(layer "B.Cu")
		(net "EXP_RESET_N")
	)
	(segment
		(start 105.462324 -80.465676)
		(end 107.09148 -80.465676)
		(width 0.127)
		(layer "In5.Cu")
		(net "EXP_RESET_N")
	)
	(segment
		(start 96.5073 -79.7433)
		(end 98.157792 -81.393792)
		(width 0.127)
		(layer "In5.Cu")
		(net "EXP_RESET_N")
	)
	(segment
		(start 107.518454 -78.924658)
		(end 107.86237 -78.580742)
		(width 0.127)
		(layer "In5.Cu")
		(net "EXP_RESET_N")
	)
	(segment
		(start 98.157792 -81.393792)
		(end 104.534208 -81.393792)
		(width 0.127)
		(layer "In5.Cu")
		(net "EXP_RESET_N")
	)
	(segment
		(start 108.419392 -78.580742)
		(end 110.000034 -77.0001)
		(width 0.127)
		(layer "In5.Cu")
		(net "EXP_RESET_N")
	)
	(segment
		(start 107.86237 -78.580742)
		(end 108.419392 -78.580742)
		(width 0.127)
		(layer "In5.Cu")
		(net "EXP_RESET_N")
	)
	(segment
		(start 91.2368 -80.2132)
		(end 91.7067 -79.7433)
		(width 0.127)
		(layer "In5.Cu")
		(net "EXP_RESET_N")
	)
	(segment
		(start 91.7067 -79.7433)
		(end 96.5073 -79.7433)
		(width 0.127)
		(layer "In5.Cu")
		(net "EXP_RESET_N")
	)
	(segment
		(start 107.518454 -80.038702)
		(end 107.518454 -78.924658)
		(width 0.127)
		(layer "In5.Cu")
		(net "EXP_RESET_N")
	)
	(segment
		(start 107.09148 -80.465676)
		(end 107.518454 -80.038702)
		(width 0.127)
		(layer "In5.Cu")
		(net "EXP_RESET_N")
	)
	(segment
		(start 104.534208 -81.393792)
		(end 105.462324 -80.465676)
		(width 0.127)
		(layer "In5.Cu")
		(net "EXP_RESET_N")
	)
	(segment
		(start 66.159126 -6.533134)
		(end 80.239362 -6.533134)
		(width 0.127)
		(layer "F.Cu")
		(net "SCC_STBY_PGOOD")
	)
	(segment
		(start 81.106264 -7.400036)
		(end 86.000082 -7.400036)
		(width 0.127)
		(layer "F.Cu")
		(net "SCC_STBY_PGOOD")
	)
	(segment
		(start 62.61862 -16.963644)
		(end 62.61862 -10.07364)
		(width 0.127)
		(layer "F.Cu")
		(net "SCC_STBY_PGOOD")
	)
	(segment
		(start 80.239362 -6.533134)
		(end 81.106264 -7.400036)
		(width 0.127)
		(layer "F.Cu")
		(net "SCC_STBY_PGOOD")
	)
	(segment
		(start 62.61862 -10.07364)
		(end 63.534798 -9.157462)
		(width 0.127)
		(layer "F.Cu")
		(net "SCC_STBY_PGOOD")
	)
	(segment
		(start 25.047956 -99.3521)
		(end 26.080466 -99.3521)
		(width 0.127)
		(layer "F.Cu")
		(net "SCC_STBY_PGOOD")
	)
	(segment
		(start 23.7998 -99.3521)
		(end 25.047956 -99.3521)
		(width 0.127)
		(layer "F.Cu")
		(net "SCC_STBY_PGOOD")
	)
	(segment
		(start 63.534798 -9.157462)
		(end 66.159126 -6.533134)
		(width 0.127)
		(layer "F.Cu")
		(net "SCC_STBY_PGOOD")
	)
	(via
		(at 25.047956 -99.3521)
		(size 0.6604)
		(drill 0.3302)
		(layers "F.Cu" "B.Cu")
		(net "SCC_STBY_PGOOD")
	)
	(via
		(at 26.080466 -99.3521)
		(size 0.508)
		(drill 0.254)
		(layers "F.Cu" "B.Cu")
		(net "SCC_STBY_PGOOD")
	)
	(via
		(at 63.534798 -9.157462)
		(size 0.508)
		(drill 0.254)
		(layers "F.Cu" "B.Cu")
		(net "SCC_STBY_PGOOD")
	)
	(via
		(at 8.247126 -63.57112)
		(size 0.508)
		(drill 0.254)
		(layers "F.Cu" "B.Cu")
		(net "SCC_STBY_PGOOD")
	)
	(segment
		(start 25.045416 -98.31705)
		(end 25.045416 -96.481138)
		(width 0.127)
		(layer "B.Cu")
		(net "SCC_STBY_PGOOD")
	)
	(segment
		(start 15.689834 -94.488)
		(end 13.8938 -92.691966)
		(width 0.127)
		(layer "B.Cu")
		(net "SCC_STBY_PGOOD")
	)
	(segment
		(start 23.052278 -94.488)
		(end 15.689834 -94.488)
		(width 0.127)
		(layer "B.Cu")
		(net "SCC_STBY_PGOOD")
	)
	(segment
		(start 13.8938 -72.752966)
		(end 8.247126 -67.106292)
		(width 0.127)
		(layer "B.Cu")
		(net "SCC_STBY_PGOOD")
	)
	(segment
		(start 8.247126 -67.106292)
		(end 8.247126 -63.57112)
		(width 0.127)
		(layer "B.Cu")
		(net "SCC_STBY_PGOOD")
	)
	(segment
		(start 13.8938 -92.691966)
		(end 13.8938 -72.752966)
		(width 0.127)
		(layer "B.Cu")
		(net "SCC_STBY_PGOOD")
	)
	(segment
		(start 26.080466 -99.3521)
		(end 25.045416 -98.31705)
		(width 0.127)
		(layer "B.Cu")
		(net "SCC_STBY_PGOOD")
	)
	(segment
		(start 25.045416 -96.481138)
		(end 23.052278 -94.488)
		(width 0.127)
		(layer "B.Cu")
		(net "SCC_STBY_PGOOD")
	)
	(segment
		(start 30.1371 -33.992312)
		(end 24.497792 -39.63162)
		(width 0.127)
		(layer "In5.Cu")
		(net "SCC_STBY_PGOOD")
	)
	(segment
		(start 58.291984 -9.157462)
		(end 44.931838 -22.517608)
		(width 0.127)
		(layer "In5.Cu")
		(net "SCC_STBY_PGOOD")
	)
	(segment
		(start 30.1371 -25.922478)
		(end 30.1371 -33.992312)
		(width 0.127)
		(layer "In5.Cu")
		(net "SCC_STBY_PGOOD")
	)
	(segment
		(start 44.931838 -22.517608)
		(end 33.54197 -22.517608)
		(width 0.127)
		(layer "In5.Cu")
		(net "SCC_STBY_PGOOD")
	)
	(segment
		(start 24.497792 -39.63162)
		(end 24.497792 -56.926226)
		(width 0.127)
		(layer "In5.Cu")
		(net "SCC_STBY_PGOOD")
	)
	(segment
		(start 63.534798 -9.157462)
		(end 58.291984 -9.157462)
		(width 0.127)
		(layer "In5.Cu")
		(net "SCC_STBY_PGOOD")
	)
	(segment
		(start 63.534798 -9.157462)
		(end 81.340706 -9.157462)
		(width 0.127)
		(layer "In5.Cu")
		(net "SCC_STBY_PGOOD")
	)
	(segment
		(start 33.54197 -22.517608)
		(end 30.1371 -25.922478)
		(width 0.127)
		(layer "In5.Cu")
		(net "SCC_STBY_PGOOD")
	)
	(segment
		(start 81.340706 -9.157462)
		(end 83.098132 -7.400036)
		(width 0.127)
		(layer "In5.Cu")
		(net "SCC_STBY_PGOOD")
	)
	(segment
		(start 9.961372 -61.856874)
		(end 8.247126 -63.57112)
		(width 0.127)
		(layer "In5.Cu")
		(net "SCC_STBY_PGOOD")
	)
	(segment
		(start 83.098132 -7.400036)
		(end 86.000082 -7.400036)
		(width 0.127)
		(layer "In5.Cu")
		(net "SCC_STBY_PGOOD")
	)
	(segment
		(start 24.497792 -56.926226)
		(end 19.567144 -61.856874)
		(width 0.127)
		(layer "In5.Cu")
		(net "SCC_STBY_PGOOD")
	)
	(segment
		(start 19.567144 -61.856874)
		(end 9.961372 -61.856874)
		(width 0.127)
		(layer "In5.Cu")
		(net "SCC_STBY_PGOOD")
	)
	(via
		(at 174.475648 -68.199)
		(size 0.6096)
		(drill 0.3048)
		(layers "F.Cu" "B.Cu")
		(net "SYS_RST_Q8")
	)
	(segment
		(start 175.22698 -68.199)
		(end 175.372522 -68.053458)
		(width 0.127)
		(layer "B.Cu")
		(net "SYS_RST_Q8")
	)
	(segment
		(start 173.288706 -68.450206)
		(end 174.625 -69.7865)
		(width 0.127)
		(layer "B.Cu")
		(net "SYS_RST_Q8")
	)
	(segment
		(start 173.288706 -68.199)
		(end 173.288706 -68.450206)
		(width 0.127)
		(layer "B.Cu")
		(net "SYS_RST_Q8")
	)
	(segment
		(start 174.475648 -68.199)
		(end 175.22698 -68.199)
		(width 0.127)
		(layer "B.Cu")
		(net "SYS_RST_Q8")
	)
	(segment
		(start 174.475648 -68.199)
		(end 173.288706 -68.199)
		(width 0.127)
		(layer "B.Cu")
		(net "SYS_RST_Q8")
	)
	(segment
		(start 175.372522 -68.053458)
		(end 175.739298 -68.053458)
		(width 0.127)
		(layer "B.Cu")
		(net "SYS_RST_Q8")
	)
	(segment
		(start 173.928024 -64.3382)
		(end 171.052744 -61.46292)
		(width 0.127)
		(layer "F.Cu")
		(net "SCC_FULL_PGOOD_LS")
	)
	(segment
		(start 175.200056 -64.837056)
		(end 174.7012 -64.3382)
		(width 0.127)
		(layer "F.Cu")
		(net "SCC_FULL_PGOOD_LS")
	)
	(segment
		(start 170.305476 -106.424984)
		(end 170.33494 -106.39552)
		(width 0.127)
		(layer "F.Cu")
		(net "SCC_FULL_PGOOD_LS")
	)
	(segment
		(start 172.984668 -53.104034)
		(end 172.984668 -51.615086)
		(width 0.127)
		(layer "F.Cu")
		(net "SCC_FULL_PGOOD_LS")
	)
	(segment
		(start 172.999908 -53.119274)
		(end 172.984668 -53.104034)
		(width 0.127)
		(layer "F.Cu")
		(net "SCC_FULL_PGOOD_LS")
	)
	(segment
		(start 171.052744 -56.496712)
		(end 172.747432 -54.802024)
		(width 0.127)
		(layer "F.Cu")
		(net "SCC_FULL_PGOOD_LS")
	)
	(segment
		(start 170.33494 -106.39552)
		(end 171.1706 -106.39552)
		(width 0.127)
		(layer "F.Cu")
		(net "SCC_FULL_PGOOD_LS")
	)
	(segment
		(start 171.052744 -61.46292)
		(end 171.052744 -56.496712)
		(width 0.127)
		(layer "F.Cu")
		(net "SCC_FULL_PGOOD_LS")
	)
	(segment
		(start 172.747432 -54.802024)
		(end 172.747432 -54.591204)
		(width 0.127)
		(layer "F.Cu")
		(net "SCC_FULL_PGOOD_LS")
	)
	(segment
		(start 172.999908 -53.466746)
		(end 172.999908 -53.119274)
		(width 0.127)
		(layer "F.Cu")
		(net "SCC_FULL_PGOOD_LS")
	)
	(segment
		(start 172.984668 -51.615086)
		(end 172.999908 -51.599846)
		(width 0.127)
		(layer "F.Cu")
		(net "SCC_FULL_PGOOD_LS")
	)
	(segment
		(start 176.62525 -66.26225)
		(end 175.200056 -64.837056)
		(width 0.127)
		(layer "F.Cu")
		(net "SCC_FULL_PGOOD_LS")
	)
	(segment
		(start 172.9867 -54.004464)
		(end 172.984668 -54.002432)
		(width 0.127)
		(layer "F.Cu")
		(net "SCC_FULL_PGOOD_LS")
	)
	(segment
		(start 172.984668 -54.002432)
		(end 172.984668 -53.481986)
		(width 0.127)
		(layer "F.Cu")
		(net "SCC_FULL_PGOOD_LS")
	)
	(segment
		(start 172.984668 -53.481986)
		(end 172.999908 -53.466746)
		(width 0.127)
		(layer "F.Cu")
		(net "SCC_FULL_PGOOD_LS")
	)
	(segment
		(start 172.747432 -54.591204)
		(end 172.9867 -54.351936)
		(width 0.127)
		(layer "F.Cu")
		(net "SCC_FULL_PGOOD_LS")
	)
	(segment
		(start 172.9867 -54.351936)
		(end 172.9867 -54.004464)
		(width 0.127)
		(layer "F.Cu")
		(net "SCC_FULL_PGOOD_LS")
	)
	(segment
		(start 170.305476 -108.065824)
		(end 170.305476 -106.424984)
		(width 0.127)
		(layer "F.Cu")
		(net "SCC_FULL_PGOOD_LS")
	)
	(segment
		(start 174.7012 -64.3382)
		(end 173.928024 -64.3382)
		(width 0.127)
		(layer "F.Cu")
		(net "SCC_FULL_PGOOD_LS")
	)
	(via
		(at 176.62525 -66.26225)
		(size 0.508)
		(drill 0.254)
		(layers "F.Cu" "B.Cu")
		(net "SCC_FULL_PGOOD_LS")
	)
	(via
		(at 175.200056 -64.837056)
		(size 0.6604)
		(drill 0.3302)
		(layers "F.Cu" "B.Cu")
		(net "SCC_FULL_PGOOD_LS")
	)
	(via
		(at 171.1706 -106.39552)
		(size 0.508)
		(drill 0.254)
		(layers "F.Cu" "B.Cu")
		(net "SCC_FULL_PGOOD_LS")
	)
	(segment
		(start 177.479452 -107.166664)
		(end 171.941744 -107.166664)
		(width 0.127)
		(layer "In2.Cu")
		(net "SCC_FULL_PGOOD_LS")
	)
	(segment
		(start 189.694312 -105.489248)
		(end 188.99886 -106.1847)
		(width 0.127)
		(layer "In2.Cu")
		(net "SCC_FULL_PGOOD_LS")
	)
	(segment
		(start 189.694312 -79.331312)
		(end 189.694312 -105.489248)
		(width 0.127)
		(layer "In2.Cu")
		(net "SCC_FULL_PGOOD_LS")
	)
	(segment
		(start 171.941744 -107.166664)
		(end 171.1706 -106.39552)
		(width 0.127)
		(layer "In2.Cu")
		(net "SCC_FULL_PGOOD_LS")
	)
	(segment
		(start 176.62525 -66.26225)
		(end 189.694312 -79.331312)
		(width 0.127)
		(layer "In2.Cu")
		(net "SCC_FULL_PGOOD_LS")
	)
	(segment
		(start 178.461416 -106.1847)
		(end 177.479452 -107.166664)
		(width 0.127)
		(layer "In2.Cu")
		(net "SCC_FULL_PGOOD_LS")
	)
	(segment
		(start 188.99886 -106.1847)
		(end 178.461416 -106.1847)
		(width 0.127)
		(layer "In2.Cu")
		(net "SCC_FULL_PGOOD_LS")
	)
	(segment
		(start 192.54851 -71.921624)
		(end 192.808098 -71.662036)
		(width 0.127)
		(layer "F.Cu")
		(net "PCIE_RST_N")
	)
	(segment
		(start 192.8622 -73.05802)
		(end 192.54851 -72.74433)
		(width 0.127)
		(layer "F.Cu")
		(net "PCIE_RST_N")
	)
	(segment
		(start 192.54851 -72.74433)
		(end 192.54851 -71.921624)
		(width 0.127)
		(layer "F.Cu")
		(net "PCIE_RST_N")
	)
	(segment
		(start 192.808098 -71.662036)
		(end 193.633598 -71.662036)
		(width 0.127)
		(layer "F.Cu")
		(net "PCIE_RST_N")
	)
	(segment
		(start 193.876168 -73.05802)
		(end 192.8622 -73.05802)
		(width 0.127)
		(layer "F.Cu")
		(net "PCIE_RST_N")
	)
	(segment
		(start 178.599846 -29.99994)
		(end 178.20005 -29.600144)
		(width 0.127)
		(layer "F.Cu")
		(net "PCIE_RST_N")
	)
	(via
		(at 178.20005 -29.600144)
		(size 0.508)
		(drill 0.254)
		(layers "F.Cu" "B.Cu")
		(net "PCIE_RST_N")
	)
	(via
		(at 194.909186 -20.847304)
		(size 0.508)
		(drill 0.254)
		(layers "F.Cu" "B.Cu")
		(net "PCIE_RST_N")
	)
	(via
		(at 178.2826 -26.924)
		(size 0.6096)
		(drill 0.3048)
		(layers "F.Cu" "B.Cu")
		(net "PCIE_RST_N")
	)
	(via
		(at 193.876168 -73.05802)
		(size 0.508)
		(drill 0.254)
		(layers "F.Cu" "B.Cu")
		(net "PCIE_RST_N")
	)
	(segment
		(start 194.909186 -20.847304)
		(end 194.909186 -19.489166)
		(width 0.127)
		(layer "B.Cu")
		(net "PCIE_RST_N")
	)
	(segment
		(start 192.477898 -20.094702)
		(end 190.618364 -20.094702)
		(width 0.127)
		(layer "B.Cu")
		(net "PCIE_RST_N")
	)
	(segment
		(start 180.458364 -26.695908)
		(end 178.510692 -26.695908)
		(width 0.127)
		(layer "B.Cu")
		(net "PCIE_RST_N")
	)
	(segment
		(start 186.350656 -22.990556)
		(end 184.34558 -22.99335)
		(width 0.127)
		(layer "B.Cu")
		(net "PCIE_RST_N")
	)
	(segment
		(start 189.743588 -20.969478)
		(end 188.371734 -20.969478)
		(width 0.127)
		(layer "B.Cu")
		(net "PCIE_RST_N")
	)
	(segment
		(start 194.909186 -19.489166)
		(end 194.59575 -19.17573)
		(width 0.127)
		(layer "B.Cu")
		(net "PCIE_RST_N")
	)
	(segment
		(start 177.9778 -27.9908)
		(end 177.9778 -29.377894)
		(width 0.127)
		(layer "B.Cu")
		(net "PCIE_RST_N")
	)
	(segment
		(start 182.553356 -22.99335)
		(end 181.03215 -24.514556)
		(width 0.127)
		(layer "B.Cu")
		(net "PCIE_RST_N")
	)
	(segment
		(start 177.9778 -29.377894)
		(end 178.20005 -29.600144)
		(width 0.127)
		(layer "B.Cu")
		(net "PCIE_RST_N")
	)
	(segment
		(start 192.80886 -19.76374)
		(end 192.477898 -20.094702)
		(width 0.127)
		(layer "B.Cu")
		(net "PCIE_RST_N")
	)
	(segment
		(start 178.510692 -26.695908)
		(end 178.2826 -26.924)
		(width 0.127)
		(layer "B.Cu")
		(net "PCIE_RST_N")
	)
	(segment
		(start 181.03215 -26.122122)
		(end 180.458364 -26.695908)
		(width 0.127)
		(layer "B.Cu")
		(net "PCIE_RST_N")
	)
	(segment
		(start 194.59575 -19.17573)
		(end 193.40957 -19.17573)
		(width 0.127)
		(layer "B.Cu")
		(net "PCIE_RST_N")
	)
	(segment
		(start 178.120802 -27.085798)
		(end 178.120802 -27.847798)
		(width 0.127)
		(layer "B.Cu")
		(net "PCIE_RST_N")
	)
	(segment
		(start 190.618364 -20.094702)
		(end 189.743588 -20.969478)
		(width 0.127)
		(layer "B.Cu")
		(net "PCIE_RST_N")
	)
	(segment
		(start 193.40957 -19.17573)
		(end 192.82156 -19.76374)
		(width 0.127)
		(layer "B.Cu")
		(net "PCIE_RST_N")
	)
	(segment
		(start 181.03215 -24.514556)
		(end 181.03215 -26.122122)
		(width 0.127)
		(layer "B.Cu")
		(net "PCIE_RST_N")
	)
	(segment
		(start 184.34558 -22.99335)
		(end 182.553356 -22.99335)
		(width 0.127)
		(layer "B.Cu")
		(net "PCIE_RST_N")
	)
	(segment
		(start 188.371734 -20.969478)
		(end 186.350656 -22.990556)
		(width 0.127)
		(layer "B.Cu")
		(net "PCIE_RST_N")
	)
	(segment
		(start 178.120802 -27.847798)
		(end 177.9778 -27.9908)
		(width 0.127)
		(layer "B.Cu")
		(net "PCIE_RST_N")
	)
	(segment
		(start 178.2826 -26.924)
		(end 178.120802 -27.085798)
		(width 0.127)
		(layer "B.Cu")
		(net "PCIE_RST_N")
	)
	(segment
		(start 192.82156 -19.76374)
		(end 192.80886 -19.76374)
		(width 0.127)
		(layer "B.Cu")
		(net "PCIE_RST_N")
	)
	(segment
		(start 194.909186 -20.847304)
		(end 196.292216 -22.230334)
		(width 0.127)
		(layer "In5.Cu")
		(net "PCIE_RST_N")
	)
	(segment
		(start 203.5429 -35.209226)
		(end 202.885548 -35.866578)
		(width 0.127)
		(layer "In5.Cu")
		(net "PCIE_RST_N")
	)
	(segment
		(start 196.292216 -22.230334)
		(end 196.96049 -22.230334)
		(width 0.127)
		(layer "In5.Cu")
		(net "PCIE_RST_N")
	)
	(segment
		(start 194.439032 -73.620884)
		(end 193.876168 -73.05802)
		(width 0.127)
		(layer "In5.Cu")
		(net "PCIE_RST_N")
	)
	(segment
		(start 196.96049 -22.230334)
		(end 203.5429 -28.812744)
		(width 0.127)
		(layer "In5.Cu")
		(net "PCIE_RST_N")
	)
	(segment
		(start 203.5429 -28.812744)
		(end 203.5429 -35.209226)
		(width 0.127)
		(layer "In5.Cu")
		(net "PCIE_RST_N")
	)
	(segment
		(start 202.581256 -53.653944)
		(end 202.581256 -73.079356)
		(width 0.127)
		(layer "In5.Cu")
		(net "PCIE_RST_N")
	)
	(segment
		(start 202.039728 -73.620884)
		(end 194.439032 -73.620884)
		(width 0.127)
		(layer "In5.Cu")
		(net "PCIE_RST_N")
	)
	(segment
		(start 202.581256 -73.079356)
		(end 202.039728 -73.620884)
		(width 0.127)
		(layer "In5.Cu")
		(net "PCIE_RST_N")
	)
	(segment
		(start 202.885548 -35.866578)
		(end 202.885548 -53.349652)
		(width 0.127)
		(layer "In5.Cu")
		(net "PCIE_RST_N")
	)
	(segment
		(start 202.885548 -53.349652)
		(end 202.581256 -53.653944)
		(width 0.127)
		(layer "In5.Cu")
		(net "PCIE_RST_N")
	)
	(via
		(at 172.39488 -73.23582)
		(size 0.6096)
		(drill 0.3048)
		(layers "F.Cu" "B.Cu")
		(net "P3V3_STBY_Q15_R")
	)
	(segment
		(start 171.01312 -73.23582)
		(end 172.39488 -73.23582)
		(width 0.127)
		(layer "B.Cu")
		(net "P3V3_STBY_Q15_R")
	)
	(segment
		(start 170.9293 -71.7042)
		(end 170.942 -71.6915)
		(width 0.127)
		(layer "B.Cu")
		(net "P3V3_STBY_Q15_R")
	)
	(segment
		(start 170.9293 -73.152)
		(end 170.9293 -71.7042)
		(width 0.127)
		(layer "B.Cu")
		(net "P3V3_STBY_Q15_R")
	)
	(segment
		(start 170.9293 -73.152)
		(end 171.01312 -73.23582)
		(width 0.127)
		(layer "B.Cu")
		(net "P3V3_STBY_Q15_R")
	)
	(segment
		(start 173.64075 -72.98182)
		(end 173.64075 -71.6915)
		(width 0.127)
		(layer "B.Cu")
		(net "P3V3_STBY_Q15_R")
	)
	(segment
		(start 173.38675 -73.23582)
		(end 173.64075 -72.98182)
		(width 0.127)
		(layer "B.Cu")
		(net "P3V3_STBY_Q15_R")
	)
	(segment
		(start 172.39488 -73.23582)
		(end 173.38675 -73.23582)
		(width 0.127)
		(layer "B.Cu")
		(net "P3V3_STBY_Q15_R")
	)
	(segment
		(start 177.0888 -109.9312)
		(end 176.77892 -109.9312)
		(width 0.127)
		(layer "F.Cu")
		(net "P1V8_C_PG_LS")
	)
	(segment
		(start 172.200062 -49.9999)
		(end 172.199808 -49.9999)
		(width 0.127)
		(layer "F.Cu")
		(net "P1V8_C_PG_LS")
	)
	(segment
		(start 176.62652 -108.7882)
		(end 176.62652 -109.7788)
		(width 0.127)
		(layer "F.Cu")
		(net "P1V8_C_PG_LS")
	)
	(segment
		(start 172.599858 -50.399696)
		(end 172.200062 -49.9999)
		(width 0.127)
		(layer "F.Cu")
		(net "P1V8_C_PG_LS")
	)
	(segment
		(start 177.3174 -109.7026)
		(end 177.0888 -109.9312)
		(width 0.127)
		(layer "F.Cu")
		(net "P1V8_C_PG_LS")
	)
	(segment
		(start 176.62652 -109.7788)
		(end 176.77892 -109.9312)
		(width 0.127)
		(layer "F.Cu")
		(net "P1V8_C_PG_LS")
	)
	(segment
		(start 177.3174 -109.086396)
		(end 177.3174 -109.7026)
		(width 0.127)
		(layer "F.Cu")
		(net "P1V8_C_PG_LS")
	)
	(segment
		(start 178.01717 -108.386626)
		(end 177.3174 -109.086396)
		(width 0.127)
		(layer "F.Cu")
		(net "P1V8_C_PG_LS")
	)
	(via
		(at 178.01717 -108.386626)
		(size 0.508)
		(drill 0.254)
		(layers "F.Cu" "B.Cu")
		(net "P1V8_C_PG_LS")
	)
	(via
		(at 176.77892 -109.9312)
		(size 0.6604)
		(drill 0.3302)
		(layers "F.Cu" "B.Cu")
		(net "P1V8_C_PG_LS")
	)
	(via
		(at 172.599858 -50.399696)
		(size 0.508)
		(drill 0.254)
		(layers "F.Cu" "B.Cu")
		(net "P1V8_C_PG_LS")
	)
	(segment
		(start 178.01717 -108.386626)
		(end 179.51958 -108.386626)
		(width 0.127)
		(layer "In2.Cu")
		(net "P1V8_C_PG_LS")
	)
	(segment
		(start 190.2968 -79.186024)
		(end 173.980348 -62.869572)
		(width 0.127)
		(layer "In2.Cu")
		(net "P1V8_C_PG_LS")
	)
	(segment
		(start 173.980348 -62.869572)
		(end 173.980348 -56.775096)
		(width 0.127)
		(layer "In2.Cu")
		(net "P1V8_C_PG_LS")
	)
	(segment
		(start 181.213506 -106.6927)
		(end 189.209426 -106.6927)
		(width 0.127)
		(layer "In2.Cu")
		(net "P1V8_C_PG_LS")
	)
	(segment
		(start 173.980348 -56.775096)
		(end 171.9326 -54.727348)
		(width 0.127)
		(layer "In2.Cu")
		(net "P1V8_C_PG_LS")
	)
	(segment
		(start 179.51958 -108.386626)
		(end 181.213506 -106.6927)
		(width 0.127)
		(layer "In2.Cu")
		(net "P1V8_C_PG_LS")
	)
	(segment
		(start 189.209426 -106.6927)
		(end 190.2968 -105.605326)
		(width 0.127)
		(layer "In2.Cu")
		(net "P1V8_C_PG_LS")
	)
	(segment
		(start 171.9326 -54.727348)
		(end 171.9326 -52.832)
		(width 0.127)
		(layer "In2.Cu")
		(net "P1V8_C_PG_LS")
	)
	(segment
		(start 190.2968 -105.605326)
		(end 190.2968 -79.186024)
		(width 0.127)
		(layer "In2.Cu")
		(net "P1V8_C_PG_LS")
	)
	(segment
		(start 172.599858 -52.164742)
		(end 172.599858 -50.399696)
		(width 0.127)
		(layer "In2.Cu")
		(net "P1V8_C_PG_LS")
	)
	(segment
		(start 171.9326 -52.832)
		(end 172.599858 -52.164742)
		(width 0.127)
		(layer "In2.Cu")
		(net "P1V8_C_PG_LS")
	)
	(via
		(at 174.493428 -66.764916)
		(size 0.6096)
		(drill 0.3048)
		(layers "F.Cu" "B.Cu")
		(net "IOC_VREF_SET_LS")
	)
	(segment
		(start 174.493428 -66.764916)
		(end 173.288706 -66.764916)
		(width 0.127)
		(layer "B.Cu")
		(net "IOC_VREF_SET_LS")
	)
	(segment
		(start 173.288706 -66.764916)
		(end 173.288706 -65.7606)
		(width 0.127)
		(layer "B.Cu")
		(net "IOC_VREF_SET_LS")
	)
	(segment
		(start 175.739298 -67.164458)
		(end 175.451516 -67.164458)
		(width 0.127)
		(layer "B.Cu")
		(net "IOC_VREF_SET_LS")
	)
	(segment
		(start 175.451516 -67.164458)
		(end 175.051974 -66.764916)
		(width 0.127)
		(layer "B.Cu")
		(net "IOC_VREF_SET_LS")
	)
	(segment
		(start 173.352206 -65.6971)
		(end 173.352206 -64.943736)
		(width 0.127)
		(layer "B.Cu")
		(net "IOC_VREF_SET_LS")
	)
	(segment
		(start 173.288706 -65.7606)
		(end 173.352206 -65.6971)
		(width 0.127)
		(layer "B.Cu")
		(net "IOC_VREF_SET_LS")
	)
	(segment
		(start 175.051974 -66.764916)
		(end 174.493428 -66.764916)
		(width 0.127)
		(layer "B.Cu")
		(net "IOC_VREF_SET_LS")
	)
	(segment
		(start 8.74395 -45.584872)
		(end 8.557514 -45.584872)
		(width 0.127)
		(layer "F.Cu")
		(net "MB0_TEMP_E")
	)
	(segment
		(start 10.061448 -44.267374)
		(end 8.74395 -45.584872)
		(width 0.127)
		(layer "F.Cu")
		(net "MB0_TEMP_E")
	)
	(segment
		(start 8.23087 -45.911516)
		(end 8.557514 -45.584872)
		(width 0.127)
		(layer "F.Cu")
		(net "MB0_TEMP_E")
	)
	(segment
		(start 8.23087 -46.803818)
		(end 8.23087 -45.911516)
		(width 0.127)
		(layer "F.Cu")
		(net "MB0_TEMP_E")
	)
	(via
		(at 8.557514 -45.584872)
		(size 0.6604)
		(drill 0.3302)
		(layers "F.Cu" "B.Cu")
		(net "MB0_TEMP_E")
	)
	(segment
		(start 12.029948 -43.346624)
		(end 11.045698 -42.362374)
		(width 0.127)
		(layer "F.Cu")
		(net "MB0_TEMP_C")
	)
	(segment
		(start 11.363706 -44.267374)
		(end 9.858756 -45.772324)
		(width 0.127)
		(layer "F.Cu")
		(net "MB0_TEMP_C")
	)
	(segment
		(start 12.029948 -44.267374)
		(end 11.363706 -44.267374)
		(width 0.127)
		(layer "F.Cu")
		(net "MB0_TEMP_C")
	)
	(segment
		(start 9.24687 -46.803818)
		(end 9.24687 -46.38421)
		(width 0.127)
		(layer "F.Cu")
		(net "MB0_TEMP_C")
	)
	(segment
		(start 12.029948 -44.267374)
		(end 12.029948 -43.346624)
		(width 0.127)
		(layer "F.Cu")
		(net "MB0_TEMP_C")
	)
	(segment
		(start 9.24687 -46.38421)
		(end 9.858756 -45.772324)
		(width 0.127)
		(layer "F.Cu")
		(net "MB0_TEMP_C")
	)
	(via
		(at 9.858756 -45.772324)
		(size 0.6604)
		(drill 0.3302)
		(layers "F.Cu" "B.Cu")
		(net "MB0_TEMP_C")
	)
	(segment
		(start 83.954874 -103.471726)
		(end 83.842352 -103.359204)
		(width 0.127)
		(layer "F.Cu")
		(net "SCC_FULL_PWR_EN")
	)
	(segment
		(start 83.842352 -103.359204)
		(end 83.842352 -102.881176)
		(width 0.127)
		(layer "F.Cu")
		(net "SCC_FULL_PWR_EN")
	)
	(segment
		(start 84.783676 -102.881176)
		(end 85.74405 -102.881176)
		(width 0.127)
		(layer "F.Cu")
		(net "SCC_FULL_PWR_EN")
	)
	(segment
		(start 83.842352 -102.881176)
		(end 84.783676 -102.881176)
		(width 0.127)
		(layer "F.Cu")
		(net "SCC_FULL_PWR_EN")
	)
	(segment
		(start 65.7225 -24.13)
		(end 67.53352 -24.13)
		(width 0.127)
		(layer "F.Cu")
		(net "SCC_FULL_PWR_EN")
	)
	(segment
		(start 69.4055 -25.4635)
		(end 69.411342 -25.457658)
		(width 0.127)
		(layer "F.Cu")
		(net "SCC_FULL_PWR_EN")
	)
	(segment
		(start 69.411342 -25.457658)
		(end 70.96379 -25.457658)
		(width 0.127)
		(layer "F.Cu")
		(net "SCC_FULL_PWR_EN")
	)
	(segment
		(start 67.53352 -24.13)
		(end 68.86702 -25.4635)
		(width 0.127)
		(layer "F.Cu")
		(net "SCC_FULL_PWR_EN")
	)
	(segment
		(start 85.74405 -102.881176)
		(end 85.748368 -102.876858)
		(width 0.127)
		(layer "F.Cu")
		(net "SCC_FULL_PWR_EN")
	)
	(segment
		(start 83.954874 -103.914194)
		(end 83.954874 -103.471726)
		(width 0.127)
		(layer "F.Cu")
		(net "SCC_FULL_PWR_EN")
	)
	(segment
		(start 68.86702 -25.4635)
		(end 69.4055 -25.4635)
		(width 0.127)
		(layer "F.Cu")
		(net "SCC_FULL_PWR_EN")
	)
	(via
		(at 85.748368 -102.876858)
		(size 0.508)
		(drill 0.254)
		(layers "F.Cu" "B.Cu")
		(net "SCC_FULL_PWR_EN")
	)
	(via
		(at 70.96379 -25.457658)
		(size 0.508)
		(drill 0.254)
		(layers "F.Cu" "B.Cu")
		(net "SCC_FULL_PWR_EN")
	)
	(via
		(at 84.783676 -102.881176)
		(size 0.6604)
		(drill 0.3302)
		(layers "F.Cu" "B.Cu")
		(net "SCC_FULL_PWR_EN")
	)
	(segment
		(start 71.99249 -98.2472)
		(end 75.242674 -101.497384)
		(width 0.127)
		(layer "In2.Cu")
		(net "SCC_FULL_PWR_EN")
	)
	(segment
		(start 99.734878 -14.254988)
		(end 99.734878 -9.46531)
		(width 0.127)
		(layer "In2.Cu")
		(net "SCC_FULL_PWR_EN")
	)
	(segment
		(start 70.536816 -98.2472)
		(end 71.99249 -98.2472)
		(width 0.127)
		(layer "In2.Cu")
		(net "SCC_FULL_PWR_EN")
	)
	(segment
		(start 51.091592 -70.08876)
		(end 51.091592 -83.982814)
		(width 0.127)
		(layer "In2.Cu")
		(net "SCC_FULL_PWR_EN")
	)
	(segment
		(start 51.091592 -83.982814)
		(end 61.894466 -94.785688)
		(width 0.127)
		(layer "In2.Cu")
		(net "SCC_FULL_PWR_EN")
	)
	(segment
		(start 63.29807 -65.3796)
		(end 55.800752 -65.3796)
		(width 0.127)
		(layer "In2.Cu")
		(net "SCC_FULL_PWR_EN")
	)
	(segment
		(start 68.693538 -61.594746)
		(end 67.082924 -61.594746)
		(width 0.127)
		(layer "In2.Cu")
		(net "SCC_FULL_PWR_EN")
	)
	(segment
		(start 75.242674 -101.497384)
		(end 84.368894 -101.497384)
		(width 0.127)
		(layer "In2.Cu")
		(net "SCC_FULL_PWR_EN")
	)
	(segment
		(start 70.96379 -50.36439)
		(end 70.0024 -51.32578)
		(width 0.127)
		(layer "In2.Cu")
		(net "SCC_FULL_PWR_EN")
	)
	(segment
		(start 70.96379 -25.457658)
		(end 70.96379 -25.398222)
		(width 0.127)
		(layer "In2.Cu")
		(net "SCC_FULL_PWR_EN")
	)
	(segment
		(start 84.368894 -101.497384)
		(end 85.748368 -102.876858)
		(width 0.127)
		(layer "In2.Cu")
		(net "SCC_FULL_PWR_EN")
	)
	(segment
		(start 70.0024 -60.285884)
		(end 68.693538 -61.594746)
		(width 0.127)
		(layer "In2.Cu")
		(net "SCC_FULL_PWR_EN")
	)
	(segment
		(start 70.96379 -25.398222)
		(end 73.864216 -22.497796)
		(width 0.127)
		(layer "In2.Cu")
		(net "SCC_FULL_PWR_EN")
	)
	(segment
		(start 73.864216 -22.497796)
		(end 91.49207 -22.497796)
		(width 0.127)
		(layer "In2.Cu")
		(net "SCC_FULL_PWR_EN")
	)
	(segment
		(start 70.0024 -51.32578)
		(end 70.0024 -60.285884)
		(width 0.127)
		(layer "In2.Cu")
		(net "SCC_FULL_PWR_EN")
	)
	(segment
		(start 67.075304 -94.785688)
		(end 70.536816 -98.2472)
		(width 0.127)
		(layer "In2.Cu")
		(net "SCC_FULL_PWR_EN")
	)
	(segment
		(start 70.96379 -25.457658)
		(end 70.96379 -50.36439)
		(width 0.127)
		(layer "In2.Cu")
		(net "SCC_FULL_PWR_EN")
	)
	(segment
		(start 67.082924 -61.594746)
		(end 63.29807 -65.3796)
		(width 0.127)
		(layer "In2.Cu")
		(net "SCC_FULL_PWR_EN")
	)
	(segment
		(start 61.894466 -94.785688)
		(end 67.075304 -94.785688)
		(width 0.127)
		(layer "In2.Cu")
		(net "SCC_FULL_PWR_EN")
	)
	(segment
		(start 91.49207 -22.497796)
		(end 99.734878 -14.254988)
		(width 0.127)
		(layer "In2.Cu")
		(net "SCC_FULL_PWR_EN")
	)
	(segment
		(start 55.800752 -65.3796)
		(end 51.091592 -70.08876)
		(width 0.127)
		(layer "In2.Cu")
		(net "SCC_FULL_PWR_EN")
	)
	(segment
		(start 99.734878 -9.46531)
		(end 100.400104 -8.800084)
		(width 0.127)
		(layer "In2.Cu")
		(net "SCC_FULL_PWR_EN")
	)
	(segment
		(start 83.303364 -67.368166)
		(end 83.303364 -65.866264)
		(width 0.127)
		(layer "F.Cu")
		(net "LS_EN_U24")
	)
	(segment
		(start 82.2706 -63.8175)
		(end 82.2706 -64.8081)
		(width 0.127)
		(layer "F.Cu")
		(net "LS_EN_U24")
	)
	(segment
		(start 83.303364 -65.866264)
		(end 82.2833 -64.8462)
		(width 0.127)
		(layer "F.Cu")
		(net "LS_EN_U24")
	)
	(segment
		(start 87.5919 -70.021704)
		(end 85.956902 -70.021704)
		(width 0.127)
		(layer "F.Cu")
		(net "LS_EN_U24")
	)
	(segment
		(start 82.2833 -64.8462)
		(end 82.2833 -64.8208)
		(width 0.127)
		(layer "F.Cu")
		(net "LS_EN_U24")
	)
	(segment
		(start 85.956902 -70.021704)
		(end 83.303364 -67.368166)
		(width 0.127)
		(layer "F.Cu")
		(net "LS_EN_U24")
	)
	(segment
		(start 82.2706 -64.8081)
		(end 82.2833 -64.8208)
		(width 0.127)
		(layer "F.Cu")
		(net "LS_EN_U24")
	)
	(via
		(at 82.2833 -64.8208)
		(size 0.6604)
		(drill 0.3302)
		(layers "F.Cu" "B.Cu")
		(net "LS_EN_U24")
	)
	(segment
		(start 106.499914 -60.500006)
		(end 106.000042 -60.999878)
		(width 0.127)
		(layer "F.Cu")
		(net "LED47")
	)
	(segment
		(start 95.416116 -65.48882)
		(end 94.518226 -65.48882)
		(width 0.127)
		(layer "F.Cu")
		(net "LED47")
	)
	(segment
		(start 88.294972 -66.822574)
		(end 89.803224 -65.314322)
		(width 0.127)
		(layer "F.Cu")
		(net "LED47")
	)
	(segment
		(start 94.518226 -65.48882)
		(end 93.774006 -64.7446)
		(width 0.127)
		(layer "F.Cu")
		(net "LED47")
	)
	(segment
		(start 93.774006 -64.7446)
		(end 90.372946 -64.7446)
		(width 0.127)
		(layer "F.Cu")
		(net "LED47")
	)
	(segment
		(start 90.372946 -64.7446)
		(end 89.803224 -65.314322)
		(width 0.127)
		(layer "F.Cu")
		(net "LED47")
	)
	(segment
		(start 95.664782 -65.240154)
		(end 95.416116 -65.48882)
		(width 0.127)
		(layer "F.Cu")
		(net "LED47")
	)
	(segment
		(start 87.5919 -66.822574)
		(end 88.294972 -66.822574)
		(width 0.127)
		(layer "F.Cu")
		(net "LED47")
	)
	(via
		(at 106.000042 -60.999878)
		(size 0.4572)
		(drill 0.2032)
		(layers "F.Cu" "B.Cu")
		(net "LED47")
	)
	(via
		(at 95.664782 -65.240154)
		(size 0.508)
		(drill 0.254)
		(layers "F.Cu" "B.Cu")
		(net "LED47")
	)
	(segment
		(start 103.836724 -62.606428)
		(end 103.95077 -62.606428)
		(width 0.127)
		(layer "In2.Cu")
		(net "LED47")
	)
	(segment
		(start 104.580944 -60.862464)
		(end 104.864408 -60.579)
		(width 0.127)
		(layer "In2.Cu")
		(net "LED47")
	)
	(segment
		(start 103.606346 -62.836806)
		(end 103.836724 -62.606428)
		(width 0.127)
		(layer "In2.Cu")
		(net "LED47")
	)
	(segment
		(start 103.107998 -63.4492)
		(end 103.606346 -62.950852)
		(width 0.127)
		(layer "In2.Cu")
		(net "LED47")
	)
	(segment
		(start 105.579164 -60.579)
		(end 106.000042 -60.999878)
		(width 0.127)
		(layer "In2.Cu")
		(net "LED47")
	)
	(segment
		(start 103.606346 -62.950852)
		(end 103.606346 -62.836806)
		(width 0.127)
		(layer "In2.Cu")
		(net "LED47")
	)
	(segment
		(start 103.95077 -62.606428)
		(end 104.580944 -61.976254)
		(width 0.127)
		(layer "In2.Cu")
		(net "LED47")
	)
	(segment
		(start 95.664782 -65.240154)
		(end 97.455736 -63.4492)
		(width 0.127)
		(layer "In2.Cu")
		(net "LED47")
	)
	(segment
		(start 104.864408 -60.579)
		(end 105.579164 -60.579)
		(width 0.127)
		(layer "In2.Cu")
		(net "LED47")
	)
	(segment
		(start 104.580944 -61.976254)
		(end 104.580944 -60.862464)
		(width 0.127)
		(layer "In2.Cu")
		(net "LED47")
	)
	(segment
		(start 97.455736 -63.4492)
		(end 103.107998 -63.4492)
		(width 0.127)
		(layer "In2.Cu")
		(net "LED47")
	)
	(segment
		(start 93.4593 -65.521586)
		(end 92.808298 -65.521586)
		(width 0.127)
		(layer "F.Cu")
		(net "LED46")
	)
	(segment
		(start 90.942414 -65.521586)
		(end 89.789 -66.675)
		(width 0.127)
		(layer "F.Cu")
		(net "LED46")
	)
	(segment
		(start 89.241376 -67.222624)
		(end 89.789 -66.675)
		(width 0.127)
		(layer "F.Cu")
		(net "LED46")
	)
	(segment
		(start 93.62694 -65.353946)
		(end 93.4593 -65.521586)
		(width 0.127)
		(layer "F.Cu")
		(net "LED46")
	)
	(segment
		(start 107.499912 -62.500002)
		(end 107.00004 -62.00013)
		(width 0.127)
		(layer "F.Cu")
		(net "LED46")
	)
	(segment
		(start 87.5919 -67.222624)
		(end 89.241376 -67.222624)
		(width 0.127)
		(layer "F.Cu")
		(net "LED46")
	)
	(segment
		(start 92.808298 -65.521586)
		(end 90.942414 -65.521586)
		(width 0.127)
		(layer "F.Cu")
		(net "LED46")
	)
	(via
		(at 107.00004 -62.00013)
		(size 0.4572)
		(drill 0.2032)
		(layers "F.Cu" "B.Cu")
		(net "LED46")
	)
	(via
		(at 93.62694 -65.353946)
		(size 0.508)
		(drill 0.254)
		(layers "F.Cu" "B.Cu")
		(net "LED46")
	)
	(segment
		(start 96.776794 -68.5038)
		(end 105.053384 -68.5038)
		(width 0.127)
		(layer "In2.Cu")
		(net "LED46")
	)
	(segment
		(start 93.62694 -65.353946)
		(end 96.776794 -68.5038)
		(width 0.127)
		(layer "In2.Cu")
		(net "LED46")
	)
	(segment
		(start 105.606342 -67.950842)
		(end 105.606342 -62.836806)
		(width 0.127)
		(layer "In2.Cu")
		(net "LED46")
	)
	(segment
		(start 105.966514 -62.476634)
		(end 106.523536 -62.476634)
		(width 0.127)
		(layer "In2.Cu")
		(net "LED46")
	)
	(segment
		(start 106.523536 -62.476634)
		(end 107.00004 -62.00013)
		(width 0.127)
		(layer "In2.Cu")
		(net "LED46")
	)
	(segment
		(start 105.606342 -62.836806)
		(end 105.966514 -62.476634)
		(width 0.127)
		(layer "In2.Cu")
		(net "LED46")
	)
	(segment
		(start 105.053384 -68.5038)
		(end 105.606342 -67.950842)
		(width 0.127)
		(layer "In2.Cu")
		(net "LED46")
	)
	(segment
		(start 85.865716 -65.240408)
		(end 85.904324 -65.2018)
		(width 0.127)
		(layer "F.Cu")
		(net "LED45")
	)
	(segment
		(start 85.725 -65.381124)
		(end 85.725 -66.4972)
		(width 0.127)
		(layer "F.Cu")
		(net "LED45")
	)
	(segment
		(start 103.49992 -58.50001)
		(end 103.000048 -58.000138)
		(width 0.127)
		(layer "F.Cu")
		(net "LED45")
	)
	(segment
		(start 85.725 -66.4972)
		(end 86.850474 -67.622674)
		(width 0.127)
		(layer "F.Cu")
		(net "LED45")
	)
	(segment
		(start 85.865716 -65.240408)
		(end 85.725 -65.381124)
		(width 0.127)
		(layer "F.Cu")
		(net "LED45")
	)
	(segment
		(start 85.904324 -65.2018)
		(end 86.867492 -65.2018)
		(width 0.127)
		(layer "F.Cu")
		(net "LED45")
	)
	(segment
		(start 86.850474 -67.622674)
		(end 87.5919 -67.622674)
		(width 0.127)
		(layer "F.Cu")
		(net "LED45")
	)
	(via
		(at 103.000048 -58.000138)
		(size 0.4572)
		(drill 0.2032)
		(layers "F.Cu" "B.Cu")
		(net "LED45")
	)
	(via
		(at 85.865716 -65.240408)
		(size 0.6604)
		(drill 0.3302)
		(layers "F.Cu" "B.Cu")
		(net "LED45")
	)
	(via
		(at 86.867492 -65.2018)
		(size 0.508)
		(drill 0.254)
		(layers "F.Cu" "B.Cu")
		(net "LED45")
	)
	(segment
		(start 91.058492 -61.0108)
		(end 86.867492 -65.2018)
		(width 0.127)
		(layer "In2.Cu")
		(net "LED45")
	)
	(segment
		(start 99.208336 -61.0108)
		(end 91.058492 -61.0108)
		(width 0.127)
		(layer "In2.Cu")
		(net "LED45")
	)
	(segment
		(start 100.681536 -59.5376)
		(end 99.208336 -61.0108)
		(width 0.127)
		(layer "In2.Cu")
		(net "LED45")
	)
	(segment
		(start 101.97465 -58.468514)
		(end 101.473 -58.970164)
		(width 0.127)
		(layer "In2.Cu")
		(net "LED45")
	)
	(segment
		(start 103.000048 -58.000138)
		(end 102.531672 -58.468514)
		(width 0.127)
		(layer "In2.Cu")
		(net "LED45")
	)
	(segment
		(start 101.473 -58.970164)
		(end 101.473 -59.08421)
		(width 0.127)
		(layer "In2.Cu")
		(net "LED45")
	)
	(segment
		(start 101.01961 -59.5376)
		(end 100.681536 -59.5376)
		(width 0.127)
		(layer "In2.Cu")
		(net "LED45")
	)
	(segment
		(start 101.473 -59.08421)
		(end 101.01961 -59.5376)
		(width 0.127)
		(layer "In2.Cu")
		(net "LED45")
	)
	(segment
		(start 102.531672 -58.468514)
		(end 101.97465 -58.468514)
		(width 0.127)
		(layer "In2.Cu")
		(net "LED45")
	)
	(segment
		(start 90.956384 -66.616072)
		(end 90.956384 -67.234816)
		(width 0.127)
		(layer "F.Cu")
		(net "LED44")
	)
	(segment
		(start 90.956384 -67.234816)
		(end 90.551 -67.6402)
		(width 0.127)
		(layer "F.Cu")
		(net "LED44")
	)
	(segment
		(start 90.168476 -68.022724)
		(end 87.5919 -68.022724)
		(width 0.127)
		(layer "F.Cu")
		(net "LED44")
	)
	(segment
		(start 105.499916 -59.500008)
		(end 105.000044 -59.000136)
		(width 0.127)
		(layer "F.Cu")
		(net "LED44")
	)
	(segment
		(start 90.551 -67.6402)
		(end 90.168476 -68.022724)
		(width 0.127)
		(layer "F.Cu")
		(net "LED44")
	)
	(via
		(at 90.956384 -66.616072)
		(size 0.508)
		(drill 0.254)
		(layers "F.Cu" "B.Cu")
		(net "LED44")
	)
	(via
		(at 90.551 -67.6402)
		(size 0.6604)
		(drill 0.3302)
		(layers "F.Cu" "B.Cu")
		(net "LED44")
	)
	(via
		(at 105.000044 -59.000136)
		(size 0.4572)
		(drill 0.2032)
		(layers "F.Cu" "B.Cu")
		(net "LED44")
	)
	(segment
		(start 94.966028 -62.606428)
		(end 101.950774 -62.606428)
		(width 0.127)
		(layer "In2.Cu")
		(net "LED44")
	)
	(segment
		(start 103.505 -61.052202)
		(end 103.505 -59.938158)
		(width 0.127)
		(layer "In2.Cu")
		(net "LED44")
	)
	(segment
		(start 102.606348 -61.950854)
		(end 102.606348 -61.836808)
		(width 0.127)
		(layer "In2.Cu")
		(net "LED44")
	)
	(segment
		(start 102.606348 -61.836808)
		(end 102.836726 -61.60643)
		(width 0.127)
		(layer "In2.Cu")
		(net "LED44")
	)
	(segment
		(start 104.587548 -59.412632)
		(end 105.000044 -59.000136)
		(width 0.127)
		(layer "In2.Cu")
		(net "LED44")
	)
	(segment
		(start 101.950774 -62.606428)
		(end 102.606348 -61.950854)
		(width 0.127)
		(layer "In2.Cu")
		(net "LED44")
	)
	(segment
		(start 102.950772 -61.60643)
		(end 103.505 -61.052202)
		(width 0.127)
		(layer "In2.Cu")
		(net "LED44")
	)
	(segment
		(start 90.956384 -66.616072)
		(end 94.966028 -62.606428)
		(width 0.127)
		(layer "In2.Cu")
		(net "LED44")
	)
	(segment
		(start 102.836726 -61.60643)
		(end 102.950772 -61.60643)
		(width 0.127)
		(layer "In2.Cu")
		(net "LED44")
	)
	(segment
		(start 103.505 -59.938158)
		(end 104.030526 -59.412632)
		(width 0.127)
		(layer "In2.Cu")
		(net "LED44")
	)
	(segment
		(start 104.030526 -59.412632)
		(end 104.587548 -59.412632)
		(width 0.127)
		(layer "In2.Cu")
		(net "LED44")
	)
	(segment
		(start 85.725 -67.5767)
		(end 86.571074 -68.422774)
		(width 0.127)
		(layer "F.Cu")
		(net "LED43")
	)
	(segment
		(start 103.49992 -59.500008)
		(end 103.000048 -59.000136)
		(width 0.127)
		(layer "F.Cu")
		(net "LED43")
	)
	(segment
		(start 86.571074 -68.422774)
		(end 87.5919 -68.422774)
		(width 0.127)
		(layer "F.Cu")
		(net "LED43")
	)
	(via
		(at 85.725 -67.5767)
		(size 0.508)
		(drill 0.254)
		(layers "F.Cu" "B.Cu")
		(net "LED43")
	)
	(via
		(at 103.000048 -59.000136)
		(size 0.4572)
		(drill 0.2032)
		(layers "F.Cu" "B.Cu")
		(net "LED43")
	)
	(segment
		(start 85.725 -67.5767)
		(end 86.333584 -67.5767)
		(width 0.127)
		(layer "In2.Cu")
		(net "LED43")
	)
	(segment
		(start 100.41636 -62.0268)
		(end 100.83673 -61.60643)
		(width 0.127)
		(layer "In2.Cu")
		(net "LED43")
	)
	(segment
		(start 102.5398 -59.460384)
		(end 103.000048 -59.000136)
		(width 0.127)
		(layer "In2.Cu")
		(net "LED43")
	)
	(segment
		(start 91.883484 -62.0268)
		(end 100.41636 -62.0268)
		(width 0.127)
		(layer "In2.Cu")
		(net "LED43")
	)
	(segment
		(start 101.950774 -61.60643)
		(end 102.5398 -61.017404)
		(width 0.127)
		(layer "In2.Cu")
		(net "LED43")
	)
	(segment
		(start 102.5398 -61.017404)
		(end 102.5398 -59.460384)
		(width 0.127)
		(layer "In2.Cu")
		(net "LED43")
	)
	(segment
		(start 86.333584 -67.5767)
		(end 91.883484 -62.0268)
		(width 0.127)
		(layer "In2.Cu")
		(net "LED43")
	)
	(segment
		(start 100.83673 -61.60643)
		(end 101.950774 -61.60643)
		(width 0.127)
		(layer "In2.Cu")
		(net "LED43")
	)
	(segment
		(start 102.463854 -58.50001)
		(end 102.499922 -58.50001)
		(width 0.127)
		(layer "F.Cu")
		(net "LED42")
	)
	(segment
		(start 86.43112 -64.45631)
		(end 84.95157 -64.45631)
		(width 0.127)
		(layer "F.Cu")
		(net "LED42")
	)
	(segment
		(start 84.95157 -64.45631)
		(end 84.595716 -64.812164)
		(width 0.127)
		(layer "F.Cu")
		(net "LED42")
	)
	(segment
		(start 84.963 -66.39179)
		(end 84.595716 -66.024506)
		(width 0.127)
		(layer "F.Cu")
		(net "LED42")
	)
	(segment
		(start 84.595716 -66.024506)
		(end 84.595716 -65.240408)
		(width 0.127)
		(layer "F.Cu")
		(net "LED42")
	)
	(segment
		(start 102.038658 -58.074814)
		(end 102.463854 -58.50001)
		(width 0.127)
		(layer "F.Cu")
		(net "LED42")
	)
	(segment
		(start 86.220554 -68.821554)
		(end 84.963 -67.564)
		(width 0.127)
		(layer "F.Cu")
		(net "LED42")
	)
	(segment
		(start 84.963 -67.564)
		(end 84.963 -66.39179)
		(width 0.127)
		(layer "F.Cu")
		(net "LED42")
	)
	(segment
		(start 87.5919 -68.821554)
		(end 86.220554 -68.821554)
		(width 0.127)
		(layer "F.Cu")
		(net "LED42")
	)
	(segment
		(start 84.595716 -64.812164)
		(end 84.595716 -65.240408)
		(width 0.127)
		(layer "F.Cu")
		(net "LED42")
	)
	(via
		(at 102.038658 -58.074814)
		(size 0.4572)
		(drill 0.2032)
		(layers "F.Cu" "B.Cu")
		(net "LED42")
	)
	(via
		(at 84.595716 -65.240408)
		(size 0.6604)
		(drill 0.3302)
		(layers "F.Cu" "B.Cu")
		(net "LED42")
	)
	(via
		(at 86.43112 -64.45631)
		(size 0.508)
		(drill 0.254)
		(layers "F.Cu" "B.Cu")
		(net "LED42")
	)
	(segment
		(start 101.640386 -58.074814)
		(end 102.038658 -58.074814)
		(width 0.127)
		(layer "In2.Cu")
		(net "LED42")
	)
	(segment
		(start 101.108764 -58.606436)
		(end 101.640386 -58.074814)
		(width 0.127)
		(layer "In2.Cu")
		(net "LED42")
	)
	(segment
		(start 100.78593 -58.606436)
		(end 101.108764 -58.606436)
		(width 0.127)
		(layer "In2.Cu")
		(net "LED42")
	)
	(segment
		(start 86.43112 -64.45631)
		(end 90.38463 -60.5028)
		(width 0.127)
		(layer "In2.Cu")
		(net "LED42")
	)
	(segment
		(start 90.38463 -60.5028)
		(end 98.889566 -60.5028)
		(width 0.127)
		(layer "In2.Cu")
		(net "LED42")
	)
	(segment
		(start 98.889566 -60.5028)
		(end 100.78593 -58.606436)
		(width 0.127)
		(layer "In2.Cu")
		(net "LED42")
	)
	(segment
		(start 106.499914 -61.500004)
		(end 106.999786 -61.000132)
		(width 0.127)
		(layer "F.Cu")
		(net "LED41")
	)
	(segment
		(start 95.664782 -66.939668)
		(end 95.664782 -66.431922)
		(width 0.127)
		(layer "F.Cu")
		(net "LED41")
	)
	(segment
		(start 95.126302 -67.478148)
		(end 95.664782 -66.939668)
		(width 0.127)
		(layer "F.Cu")
		(net "LED41")
	)
	(segment
		(start 87.5919 -69.221604)
		(end 89.782396 -69.221604)
		(width 0.127)
		(layer "F.Cu")
		(net "LED41")
	)
	(segment
		(start 91.186 -67.818)
		(end 94.78645 -67.818)
		(width 0.127)
		(layer "F.Cu")
		(net "LED41")
	)
	(segment
		(start 94.78645 -67.818)
		(end 95.126302 -67.478148)
		(width 0.127)
		(layer "F.Cu")
		(net "LED41")
	)
	(segment
		(start 89.782396 -69.221604)
		(end 91.186 -67.818)
		(width 0.127)
		(layer "F.Cu")
		(net "LED41")
	)
	(via
		(at 95.126302 -67.478148)
		(size 0.6604)
		(drill 0.3302)
		(layers "F.Cu" "B.Cu")
		(net "LED41")
	)
	(via
		(at 106.999786 -61.000132)
		(size 0.4572)
		(drill 0.2032)
		(layers "F.Cu" "B.Cu")
		(net "LED41")
	)
	(via
		(at 95.664782 -66.431922)
		(size 0.508)
		(drill 0.254)
		(layers "F.Cu" "B.Cu")
		(net "LED41")
	)
	(segment
		(start 105.163366 -62.39383)
		(end 105.04932 -62.39383)
		(width 0.127)
		(layer "In2.Cu")
		(net "LED41")
	)
	(segment
		(start 105.837736 -61.508132)
		(end 105.499154 -61.846714)
		(width 0.127)
		(layer "In2.Cu")
		(net "LED41")
	)
	(segment
		(start 102.990396 -64.5668)
		(end 97.529904 -64.5668)
		(width 0.127)
		(layer "In2.Cu")
		(net "LED41")
	)
	(segment
		(start 105.499154 -61.846714)
		(end 105.499154 -62.058042)
		(width 0.127)
		(layer "In2.Cu")
		(net "LED41")
	)
	(segment
		(start 104.393746 -63.16345)
		(end 102.990396 -64.5668)
		(width 0.127)
		(layer "In2.Cu")
		(net "LED41")
	)
	(segment
		(start 106.999786 -61.000132)
		(end 106.491786 -61.508132)
		(width 0.127)
		(layer "In2.Cu")
		(net "LED41")
	)
	(segment
		(start 105.499154 -62.058042)
		(end 105.163366 -62.39383)
		(width 0.127)
		(layer "In2.Cu")
		(net "LED41")
	)
	(segment
		(start 106.491786 -61.508132)
		(end 105.837736 -61.508132)
		(width 0.127)
		(layer "In2.Cu")
		(net "LED41")
	)
	(segment
		(start 104.393746 -63.049404)
		(end 104.393746 -63.16345)
		(width 0.127)
		(layer "In2.Cu")
		(net "LED41")
	)
	(segment
		(start 97.529904 -64.5668)
		(end 95.664782 -66.431922)
		(width 0.127)
		(layer "In2.Cu")
		(net "LED41")
	)
	(segment
		(start 105.04932 -62.39383)
		(end 104.393746 -63.049404)
		(width 0.127)
		(layer "In2.Cu")
		(net "LED41")
	)
	(segment
		(start 86.30031 -69.621654)
		(end 84.328 -67.649344)
		(width 0.127)
		(layer "F.Cu")
		(net "LED40")
	)
	(segment
		(start 87.5919 -69.621654)
		(end 86.30031 -69.621654)
		(width 0.127)
		(layer "F.Cu")
		(net "LED40")
	)
	(segment
		(start 102.499922 -59.500008)
		(end 102.00005 -59.000136)
		(width 0.127)
		(layer "F.Cu")
		(net "LED40")
	)
	(via
		(at 102.00005 -59.000136)
		(size 0.4572)
		(drill 0.2032)
		(layers "F.Cu" "B.Cu")
		(net "LED40")
	)
	(via
		(at 84.328 -67.649344)
		(size 0.508)
		(drill 0.254)
		(layers "F.Cu" "B.Cu")
		(net "LED40")
	)
	(segment
		(start 86.224618 -66.9671)
		(end 91.672918 -61.5188)
		(width 0.127)
		(layer "In2.Cu")
		(net "LED40")
	)
	(segment
		(start 84.328 -67.649344)
		(end 85.010244 -66.9671)
		(width 0.127)
		(layer "In2.Cu")
		(net "LED40")
	)
	(segment
		(start 101.556566 -60.000642)
		(end 101.556566 -59.44362)
		(width 0.127)
		(layer "In2.Cu")
		(net "LED40")
	)
	(segment
		(start 91.672918 -61.5188)
		(end 99.747324 -61.5188)
		(width 0.127)
		(layer "In2.Cu")
		(net "LED40")
	)
	(segment
		(start 85.010244 -66.9671)
		(end 86.224618 -66.9671)
		(width 0.127)
		(layer "In2.Cu")
		(net "LED40")
	)
	(segment
		(start 99.747324 -61.5188)
		(end 100.661724 -60.6044)
		(width 0.127)
		(layer "In2.Cu")
		(net "LED40")
	)
	(segment
		(start 100.661724 -60.6044)
		(end 100.952808 -60.6044)
		(width 0.127)
		(layer "In2.Cu")
		(net "LED40")
	)
	(segment
		(start 101.556566 -59.44362)
		(end 102.00005 -59.000136)
		(width 0.127)
		(layer "In2.Cu")
		(net "LED40")
	)
	(segment
		(start 100.952808 -60.6044)
		(end 101.556566 -60.000642)
		(width 0.127)
		(layer "In2.Cu")
		(net "LED40")
	)
	(segment
		(start 79.553054 -68.821554)
		(end 78.2447 -67.5132)
		(width 0.127)
		(layer "F.Cu")
		(net "DEBUG_LOW_HEX_3")
	)
	(segment
		(start 75.850496 -67.5132)
		(end 75.066398 -66.729102)
		(width 0.127)
		(layer "F.Cu")
		(net "DEBUG_LOW_HEX_3")
	)
	(segment
		(start 34.880804 -114.32286)
		(end 33.999932 -115.203732)
		(width 0.127)
		(layer "F.Cu")
		(net "DEBUG_LOW_HEX_3")
	)
	(segment
		(start 58.081672 -66.729102)
		(end 44.994322 -66.729102)
		(width 0.127)
		(layer "F.Cu")
		(net "DEBUG_LOW_HEX_3")
	)
	(segment
		(start 78.2447 -67.5132)
		(end 75.850496 -67.5132)
		(width 0.127)
		(layer "F.Cu")
		(net "DEBUG_LOW_HEX_3")
	)
	(segment
		(start 33.999932 -115.203732)
		(end 33.999932 -117.87505)
		(width 0.127)
		(layer "F.Cu")
		(net "DEBUG_LOW_HEX_3")
	)
	(segment
		(start 44.994322 -66.729102)
		(end 34.880804 -76.84262)
		(width 0.127)
		(layer "F.Cu")
		(net "DEBUG_LOW_HEX_3")
	)
	(segment
		(start 34.880804 -76.84262)
		(end 34.880804 -114.32286)
		(width 0.127)
		(layer "F.Cu")
		(net "DEBUG_LOW_HEX_3")
	)
	(segment
		(start 75.066398 -66.729102)
		(end 58.081672 -66.729102)
		(width 0.127)
		(layer "F.Cu")
		(net "DEBUG_LOW_HEX_3")
	)
	(segment
		(start 81.9531 -68.821554)
		(end 79.553054 -68.821554)
		(width 0.127)
		(layer "F.Cu")
		(net "DEBUG_LOW_HEX_3")
	)
	(via
		(at 58.081672 -66.729102)
		(size 0.6604)
		(drill 0.3302)
		(layers "F.Cu" "B.Cu")
		(net "DEBUG_LOW_HEX_3")
	)
	(segment
		(start 74.8792 -69.0372)
		(end 74.349102 -68.507102)
		(width 0.127)
		(layer "F.Cu")
		(net "DEBUG_LOW_HEX_2")
	)
	(segment
		(start 80.301846 -71.7804)
		(end 77.558646 -69.0372)
		(width 0.127)
		(layer "F.Cu")
		(net "DEBUG_LOW_HEX_2")
	)
	(segment
		(start 82.979768 -71.7804)
		(end 80.301846 -71.7804)
		(width 0.127)
		(layer "F.Cu")
		(net "DEBUG_LOW_HEX_2")
	)
	(segment
		(start 33.999932 -122.124978)
		(end 33.999932 -123.865132)
		(width 0.127)
		(layer "F.Cu")
		(net "DEBUG_LOW_HEX_2")
	)
	(segment
		(start 36.8554 -124.4346)
		(end 38.097206 -123.192794)
		(width 0.127)
		(layer "F.Cu")
		(net "DEBUG_LOW_HEX_2")
	)
	(segment
		(start 34.5694 -124.4346)
		(end 36.8554 -124.4346)
		(width 0.127)
		(layer "F.Cu")
		(net "DEBUG_LOW_HEX_2")
	)
	(segment
		(start 77.558646 -69.0372)
		(end 74.8792 -69.0372)
		(width 0.127)
		(layer "F.Cu")
		(net "DEBUG_LOW_HEX_2")
	)
	(segment
		(start 33.999932 -123.865132)
		(end 34.5694 -124.4346)
		(width 0.127)
		(layer "F.Cu")
		(net "DEBUG_LOW_HEX_2")
	)
	(segment
		(start 83.5533 -71.206868)
		(end 82.979768 -71.7804)
		(width 0.127)
		(layer "F.Cu")
		(net "DEBUG_LOW_HEX_2")
	)
	(segment
		(start 81.9531 -69.221604)
		(end 83.001104 -69.221604)
		(width 0.127)
		(layer "F.Cu")
		(net "DEBUG_LOW_HEX_2")
	)
	(segment
		(start 45.372274 -68.507102)
		(end 72.458072 -68.507102)
		(width 0.127)
		(layer "F.Cu")
		(net "DEBUG_LOW_HEX_2")
	)
	(segment
		(start 83.5533 -69.7738)
		(end 83.5533 -71.206868)
		(width 0.127)
		(layer "F.Cu")
		(net "DEBUG_LOW_HEX_2")
	)
	(segment
		(start 74.349102 -68.507102)
		(end 72.458072 -68.507102)
		(width 0.127)
		(layer "F.Cu")
		(net "DEBUG_LOW_HEX_2")
	)
	(segment
		(start 83.001104 -69.221604)
		(end 83.5533 -69.7738)
		(width 0.127)
		(layer "F.Cu")
		(net "DEBUG_LOW_HEX_2")
	)
	(segment
		(start 38.097206 -75.78217)
		(end 45.372274 -68.507102)
		(width 0.127)
		(layer "F.Cu")
		(net "DEBUG_LOW_HEX_2")
	)
	(segment
		(start 38.097206 -123.192794)
		(end 38.097206 -75.78217)
		(width 0.127)
		(layer "F.Cu")
		(net "DEBUG_LOW_HEX_2")
	)
	(via
		(at 72.458072 -68.507102)
		(size 0.6604)
		(drill 0.3302)
		(layers "F.Cu" "B.Cu")
		(net "DEBUG_LOW_HEX_2")
	)
	(segment
		(start 35.999928 -114.90579)
		(end 35.999928 -117.87505)
		(width 0.127)
		(layer "F.Cu")
		(net "DEBUG_LOW_HEX_1")
	)
	(segment
		(start 79.3242 -69.3166)
		(end 79.329534 -69.3166)
		(width 0.127)
		(layer "F.Cu")
		(net "DEBUG_LOW_HEX_1")
	)
	(segment
		(start 75.578462 -68.0212)
		(end 78.0288 -68.0212)
		(width 0.127)
		(layer "F.Cu")
		(net "DEBUG_LOW_HEX_1")
	)
	(segment
		(start 78.0288 -68.0212)
		(end 79.3242 -69.3166)
		(width 0.127)
		(layer "F.Cu")
		(net "DEBUG_LOW_HEX_1")
	)
	(segment
		(start 35.388804 -77.053186)
		(end 35.388804 -114.294666)
		(width 0.127)
		(layer "F.Cu")
		(net "DEBUG_LOW_HEX_1")
	)
	(segment
		(start 79.329534 -69.3166)
		(end 79.342488 -69.329554)
		(width 0.127)
		(layer "F.Cu")
		(net "DEBUG_LOW_HEX_1")
	)
	(segment
		(start 80.848454 -69.329554)
		(end 81.140554 -69.621654)
		(width 0.127)
		(layer "F.Cu")
		(net "DEBUG_LOW_HEX_1")
	)
	(segment
		(start 45.103288 -67.338702)
		(end 35.388804 -77.053186)
		(width 0.127)
		(layer "F.Cu")
		(net "DEBUG_LOW_HEX_1")
	)
	(segment
		(start 73.982072 -67.338702)
		(end 45.103288 -67.338702)
		(width 0.127)
		(layer "F.Cu")
		(net "DEBUG_LOW_HEX_1")
	)
	(segment
		(start 73.982072 -67.338702)
		(end 74.895964 -67.338702)
		(width 0.127)
		(layer "F.Cu")
		(net "DEBUG_LOW_HEX_1")
	)
	(segment
		(start 35.388804 -114.294666)
		(end 35.999928 -114.90579)
		(width 0.127)
		(layer "F.Cu")
		(net "DEBUG_LOW_HEX_1")
	)
	(segment
		(start 74.895964 -67.338702)
		(end 75.578462 -68.0212)
		(width 0.127)
		(layer "F.Cu")
		(net "DEBUG_LOW_HEX_1")
	)
	(segment
		(start 79.342488 -69.329554)
		(end 80.848454 -69.329554)
		(width 0.127)
		(layer "F.Cu")
		(net "DEBUG_LOW_HEX_1")
	)
	(segment
		(start 81.140554 -69.621654)
		(end 81.9531 -69.621654)
		(width 0.127)
		(layer "F.Cu")
		(net "DEBUG_LOW_HEX_1")
	)
	(via
		(at 73.982072 -67.338702)
		(size 0.6604)
		(drill 0.3302)
		(layers "F.Cu" "B.Cu")
		(net "DEBUG_LOW_HEX_1")
	)
	(segment
		(start 36.6522 -123.8758)
		(end 37.589206 -122.938794)
		(width 0.127)
		(layer "F.Cu")
		(net "DEBUG_LOW_HEX_0")
	)
	(segment
		(start 80.548988 -71.2978)
		(end 77.780388 -68.5292)
		(width 0.127)
		(layer "F.Cu")
		(net "DEBUG_LOW_HEX_0")
	)
	(segment
		(start 83.0199 -71.021702)
		(end 82.743802 -71.2978)
		(width 0.127)
		(layer "F.Cu")
		(net "DEBUG_LOW_HEX_0")
	)
	(segment
		(start 37.589206 -122.938794)
		(end 37.589206 -75.571604)
		(width 0.127)
		(layer "F.Cu")
		(net "DEBUG_LOW_HEX_0")
	)
	(segment
		(start 81.9531 -70.021704)
		(end 82.823304 -70.021704)
		(width 0.127)
		(layer "F.Cu")
		(net "DEBUG_LOW_HEX_0")
	)
	(segment
		(start 36.195 -123.8758)
		(end 36.6522 -123.8758)
		(width 0.127)
		(layer "F.Cu")
		(net "DEBUG_LOW_HEX_0")
	)
	(segment
		(start 82.743802 -71.2978)
		(end 80.548988 -71.2978)
		(width 0.127)
		(layer "F.Cu")
		(net "DEBUG_LOW_HEX_0")
	)
	(segment
		(start 45.263308 -67.897502)
		(end 67.987672 -67.897502)
		(width 0.127)
		(layer "F.Cu")
		(net "DEBUG_LOW_HEX_0")
	)
	(segment
		(start 74.736198 -67.897502)
		(end 67.987672 -67.897502)
		(width 0.127)
		(layer "F.Cu")
		(net "DEBUG_LOW_HEX_0")
	)
	(segment
		(start 37.589206 -75.571604)
		(end 45.263308 -67.897502)
		(width 0.127)
		(layer "F.Cu")
		(net "DEBUG_LOW_HEX_0")
	)
	(segment
		(start 82.823304 -70.021704)
		(end 83.0199 -70.2183)
		(width 0.127)
		(layer "F.Cu")
		(net "DEBUG_LOW_HEX_0")
	)
	(segment
		(start 35.999928 -122.124978)
		(end 35.999928 -123.680728)
		(width 0.127)
		(layer "F.Cu")
		(net "DEBUG_LOW_HEX_0")
	)
	(segment
		(start 35.999928 -123.680728)
		(end 36.195 -123.8758)
		(width 0.127)
		(layer "F.Cu")
		(net "DEBUG_LOW_HEX_0")
	)
	(segment
		(start 83.0199 -70.2183)
		(end 83.0199 -71.021702)
		(width 0.127)
		(layer "F.Cu")
		(net "DEBUG_LOW_HEX_0")
	)
	(segment
		(start 75.367896 -68.5292)
		(end 74.736198 -67.897502)
		(width 0.127)
		(layer "F.Cu")
		(net "DEBUG_LOW_HEX_0")
	)
	(segment
		(start 77.780388 -68.5292)
		(end 75.367896 -68.5292)
		(width 0.127)
		(layer "F.Cu")
		(net "DEBUG_LOW_HEX_0")
	)
	(via
		(at 67.987672 -67.897502)
		(size 0.6604)
		(drill 0.3302)
		(layers "F.Cu" "B.Cu")
		(net "DEBUG_LOW_HEX_0")
	)
	(segment
		(start 44.712636 -65.573656)
		(end 33.864804 -76.421488)
		(width 0.127)
		(layer "F.Cu")
		(net "DEBUG_HIGH_HEX_3")
	)
	(segment
		(start 79.414624 -67.222624)
		(end 77.765656 -65.573656)
		(width 0.127)
		(layer "F.Cu")
		(net "DEBUG_HIGH_HEX_3")
	)
	(segment
		(start 33.864804 -76.421488)
		(end 33.864804 -112.286796)
		(width 0.127)
		(layer "F.Cu")
		(net "DEBUG_HIGH_HEX_3")
	)
	(segment
		(start 29.99994 -116.15166)
		(end 29.99994 -117.87505)
		(width 0.127)
		(layer "F.Cu")
		(net "DEBUG_HIGH_HEX_3")
	)
	(segment
		(start 77.765656 -65.573656)
		(end 51.909472 -65.573656)
		(width 0.127)
		(layer "F.Cu")
		(net "DEBUG_HIGH_HEX_3")
	)
	(segment
		(start 51.909472 -65.573656)
		(end 44.712636 -65.573656)
		(width 0.127)
		(layer "F.Cu")
		(net "DEBUG_HIGH_HEX_3")
	)
	(segment
		(start 33.864804 -112.286796)
		(end 29.99994 -116.15166)
		(width 0.127)
		(layer "F.Cu")
		(net "DEBUG_HIGH_HEX_3")
	)
	(segment
		(start 81.9531 -67.222624)
		(end 79.414624 -67.222624)
		(width 0.127)
		(layer "F.Cu")
		(net "DEBUG_HIGH_HEX_3")
	)
	(via
		(at 51.909472 -65.573656)
		(size 0.6604)
		(drill 0.3302)
		(layers "F.Cu" "B.Cu")
		(net "DEBUG_HIGH_HEX_3")
	)
	(segment
		(start 80.61833 -72.7964)
		(end 80.618076 -72.796654)
		(width 0.127)
		(layer "F.Cu")
		(net "DEBUG_HIGH_HEX_2")
	)
	(segment
		(start 84.6201 -71.5772)
		(end 83.4009 -72.7964)
		(width 0.127)
		(layer "F.Cu")
		(net "DEBUG_HIGH_HEX_2")
	)
	(segment
		(start 74.3458 -70.0532)
		(end 73.942702 -69.650102)
		(width 0.127)
		(layer "F.Cu")
		(net "DEBUG_HIGH_HEX_2")
	)
	(segment
		(start 83.4009 -72.7964)
		(end 80.61833 -72.7964)
		(width 0.127)
		(layer "F.Cu")
		(net "DEBUG_HIGH_HEX_2")
	)
	(segment
		(start 77.137514 -70.0532)
		(end 74.3458 -70.0532)
		(width 0.127)
		(layer "F.Cu")
		(net "DEBUG_HIGH_HEX_2")
	)
	(segment
		(start 84.6201 -69.403468)
		(end 84.6201 -71.5772)
		(width 0.127)
		(layer "F.Cu")
		(net "DEBUG_HIGH_HEX_2")
	)
	(segment
		(start 39.113206 -76.203302)
		(end 45.666406 -69.650102)
		(width 0.127)
		(layer "F.Cu")
		(net "DEBUG_HIGH_HEX_2")
	)
	(segment
		(start 81.9531 -67.622674)
		(end 82.839306 -67.622674)
		(width 0.127)
		(layer "F.Cu")
		(net "DEBUG_HIGH_HEX_2")
	)
	(segment
		(start 79.880968 -72.796654)
		(end 77.137514 -70.0532)
		(width 0.127)
		(layer "F.Cu")
		(net "DEBUG_HIGH_HEX_2")
	)
	(segment
		(start 39.113206 -123.613926)
		(end 39.113206 -76.203302)
		(width 0.127)
		(layer "F.Cu")
		(net "DEBUG_HIGH_HEX_2")
	)
	(segment
		(start 29.99994 -124.20854)
		(end 31.242 -125.4506)
		(width 0.127)
		(layer "F.Cu")
		(net "DEBUG_HIGH_HEX_2")
	)
	(segment
		(start 45.666406 -69.650102)
		(end 46.710854 -69.650102)
		(width 0.127)
		(layer "F.Cu")
		(net "DEBUG_HIGH_HEX_2")
	)
	(segment
		(start 31.242 -125.4506)
		(end 37.276532 -125.4506)
		(width 0.127)
		(layer "F.Cu")
		(net "DEBUG_HIGH_HEX_2")
	)
	(segment
		(start 37.276532 -125.4506)
		(end 39.113206 -123.613926)
		(width 0.127)
		(layer "F.Cu")
		(net "DEBUG_HIGH_HEX_2")
	)
	(segment
		(start 80.618076 -72.796654)
		(end 79.880968 -72.796654)
		(width 0.127)
		(layer "F.Cu")
		(net "DEBUG_HIGH_HEX_2")
	)
	(segment
		(start 73.942702 -69.650102)
		(end 46.710854 -69.650102)
		(width 0.127)
		(layer "F.Cu")
		(net "DEBUG_HIGH_HEX_2")
	)
	(segment
		(start 29.99994 -122.124978)
		(end 29.99994 -124.20854)
		(width 0.127)
		(layer "F.Cu")
		(net "DEBUG_HIGH_HEX_2")
	)
	(segment
		(start 82.839306 -67.622674)
		(end 84.6201 -69.403468)
		(width 0.127)
		(layer "F.Cu")
		(net "DEBUG_HIGH_HEX_2")
	)
	(via
		(at 46.710854 -69.650102)
		(size 0.6604)
		(drill 0.3302)
		(layers "F.Cu" "B.Cu")
		(net "DEBUG_HIGH_HEX_2")
	)
	(segment
		(start 54.881272 -66.144902)
		(end 44.859956 -66.144902)
		(width 0.127)
		(layer "F.Cu")
		(net "DEBUG_HIGH_HEX_1")
	)
	(segment
		(start 31.999936 -115.481862)
		(end 31.999936 -117.87505)
		(width 0.127)
		(layer "F.Cu")
		(net "DEBUG_HIGH_HEX_1")
	)
	(segment
		(start 79.496158 -68.022724)
		(end 81.9531 -68.022724)
		(width 0.127)
		(layer "F.Cu")
		(net "DEBUG_HIGH_HEX_1")
	)
	(segment
		(start 34.372804 -113.108994)
		(end 31.999936 -115.481862)
		(width 0.127)
		(layer "F.Cu")
		(net "DEBUG_HIGH_HEX_1")
	)
	(segment
		(start 77.618336 -66.144902)
		(end 79.496158 -68.022724)
		(width 0.127)
		(layer "F.Cu")
		(net "DEBUG_HIGH_HEX_1")
	)
	(segment
		(start 54.881272 -66.144902)
		(end 77.618336 -66.144902)
		(width 0.127)
		(layer "F.Cu")
		(net "DEBUG_HIGH_HEX_1")
	)
	(segment
		(start 44.859956 -66.144902)
		(end 34.372804 -76.632054)
		(width 0.127)
		(layer "F.Cu")
		(net "DEBUG_HIGH_HEX_1")
	)
	(segment
		(start 34.372804 -76.632054)
		(end 34.372804 -113.108994)
		(width 0.127)
		(layer "F.Cu")
		(net "DEBUG_HIGH_HEX_1")
	)
	(via
		(at 54.881272 -66.144902)
		(size 0.6604)
		(drill 0.3302)
		(layers "F.Cu" "B.Cu")
		(net "DEBUG_HIGH_HEX_1")
	)
	(segment
		(start 74.610214 -69.5452)
		(end 77.34808 -69.5452)
		(width 0.127)
		(layer "F.Cu")
		(net "DEBUG_HIGH_HEX_0")
	)
	(segment
		(start 84.1121 -71.366634)
		(end 84.1121 -69.614034)
		(width 0.127)
		(layer "F.Cu")
		(net "DEBUG_HIGH_HEX_0")
	)
	(segment
		(start 68.952872 -69.091302)
		(end 45.50664 -69.091302)
		(width 0.127)
		(layer "F.Cu")
		(net "DEBUG_HIGH_HEX_0")
	)
	(segment
		(start 38.605206 -75.992736)
		(end 38.605206 -123.40336)
		(width 0.127)
		(layer "F.Cu")
		(net "DEBUG_HIGH_HEX_0")
	)
	(segment
		(start 77.34808 -69.5452)
		(end 80.091534 -72.288654)
		(width 0.127)
		(layer "F.Cu")
		(net "DEBUG_HIGH_HEX_0")
	)
	(segment
		(start 80.40751 -72.288654)
		(end 80.407764 -72.2884)
		(width 0.127)
		(layer "F.Cu")
		(net "DEBUG_HIGH_HEX_0")
	)
	(segment
		(start 38.605206 -123.40336)
		(end 37.065966 -124.9426)
		(width 0.127)
		(layer "F.Cu")
		(net "DEBUG_HIGH_HEX_0")
	)
	(segment
		(start 80.091534 -72.288654)
		(end 80.40751 -72.288654)
		(width 0.127)
		(layer "F.Cu")
		(net "DEBUG_HIGH_HEX_0")
	)
	(segment
		(start 45.50664 -69.091302)
		(end 38.605206 -75.992736)
		(width 0.127)
		(layer "F.Cu")
		(net "DEBUG_HIGH_HEX_0")
	)
	(segment
		(start 80.407764 -72.2884)
		(end 83.190334 -72.2884)
		(width 0.127)
		(layer "F.Cu")
		(net "DEBUG_HIGH_HEX_0")
	)
	(segment
		(start 74.156316 -69.091302)
		(end 74.610214 -69.5452)
		(width 0.127)
		(layer "F.Cu")
		(net "DEBUG_HIGH_HEX_0")
	)
	(segment
		(start 84.1121 -69.614034)
		(end 82.92084 -68.422774)
		(width 0.127)
		(layer "F.Cu")
		(net "DEBUG_HIGH_HEX_0")
	)
	(segment
		(start 68.952872 -69.091302)
		(end 74.156316 -69.091302)
		(width 0.127)
		(layer "F.Cu")
		(net "DEBUG_HIGH_HEX_0")
	)
	(segment
		(start 31.999936 -124.278136)
		(end 31.999936 -122.124978)
		(width 0.127)
		(layer "F.Cu")
		(net "DEBUG_HIGH_HEX_0")
	)
	(segment
		(start 32.6644 -124.9426)
		(end 31.999936 -124.278136)
		(width 0.127)
		(layer "F.Cu")
		(net "DEBUG_HIGH_HEX_0")
	)
	(segment
		(start 82.92084 -68.422774)
		(end 81.9531 -68.422774)
		(width 0.127)
		(layer "F.Cu")
		(net "DEBUG_HIGH_HEX_0")
	)
	(segment
		(start 37.065966 -124.9426)
		(end 32.6644 -124.9426)
		(width 0.127)
		(layer "F.Cu")
		(net "DEBUG_HIGH_HEX_0")
	)
	(segment
		(start 83.190334 -72.2884)
		(end 84.1121 -71.366634)
		(width 0.127)
		(layer "F.Cu")
		(net "DEBUG_HIGH_HEX_0")
	)
	(via
		(at 68.952872 -69.091302)
		(size 0.6604)
		(drill 0.3302)
		(layers "F.Cu" "B.Cu")
		(net "DEBUG_HIGH_HEX_0")
	)
	(segment
		(start 63.700914 -17.570958)
		(end 64.809116 -17.570958)
		(width 0.127)
		(layer "F.Cu")
		(net "LS_EN_N")
	)
	(segment
		(start 166.751 -16.0655)
		(end 166.751 -14.3891)
		(width 0.127)
		(layer "F.Cu")
		(net "LS_EN_N")
	)
	(segment
		(start 83.346036 -63.410592)
		(end 82.863944 -62.9285)
		(width 0.127)
		(layer "F.Cu")
		(net "LS_EN_N")
	)
	(segment
		(start 83.346036 -64.19088)
		(end 83.346036 -63.410592)
		(width 0.127)
		(layer "F.Cu")
		(net "LS_EN_N")
	)
	(segment
		(start 82.863944 -62.9285)
		(end 82.2706 -62.9285)
		(width 0.127)
		(layer "F.Cu")
		(net "LS_EN_N")
	)
	(segment
		(start 166.751 -14.3891)
		(end 168.440608 -12.699492)
		(width 0.127)
		(layer "F.Cu")
		(net "LS_EN_N")
	)
	(segment
		(start 168.732454 -8.97001)
		(end 168.732454 -10.186416)
		(width 0.127)
		(layer "F.Cu")
		(net "LS_EN_N")
	)
	(segment
		(start 168.440608 -12.699492)
		(end 168.732454 -12.699492)
		(width 0.127)
		(layer "F.Cu")
		(net "LS_EN_N")
	)
	(via
		(at 64.809116 -17.570958)
		(size 0.508)
		(drill 0.254)
		(layers "F.Cu" "B.Cu")
		(net "LS_EN_N")
	)
	(via
		(at 83.346036 -64.19088)
		(size 0.508)
		(drill 0.254)
		(layers "F.Cu" "B.Cu")
		(net "LS_EN_N")
	)
	(via
		(at 168.732454 -12.699492)
		(size 0.508)
		(drill 0.254)
		(layers "F.Cu" "B.Cu")
		(net "LS_EN_N")
	)
	(via
		(at 164.084 -15.813786)
		(size 0.6096)
		(drill 0.3048)
		(layers "F.Cu" "B.Cu")
		(net "LS_EN_N")
	)
	(via
		(at 168.732454 -10.186416)
		(size 0.508)
		(drill 0.254)
		(layers "F.Cu" "B.Cu")
		(net "LS_EN_N")
	)
	(via
		(at 94.619318 -46.319948)
		(size 0.508)
		(drill 0.254)
		(layers "F.Cu" "B.Cu")
		(net "LS_EN_N")
	)
	(segment
		(start 168.732454 -10.186416)
		(end 168.732454 -12.699492)
		(width 0.127)
		(layer "B.Cu")
		(net "LS_EN_N")
	)
	(segment
		(start 166.101014 -15.813786)
		(end 164.084 -15.813786)
		(width 0.127)
		(layer "B.Cu")
		(net "LS_EN_N")
	)
	(segment
		(start 168.732454 -12.699492)
		(end 168.732454 -13.182346)
		(width 0.127)
		(layer "B.Cu")
		(net "LS_EN_N")
	)
	(segment
		(start 168.732454 -13.182346)
		(end 166.101014 -15.813786)
		(width 0.127)
		(layer "B.Cu")
		(net "LS_EN_N")
	)
	(segment
		(start 161.798762 -15.813786)
		(end 160.784286 -15.813786)
		(width 0.127)
		(layer "B.Cu")
		(net "LS_EN_N")
	)
	(segment
		(start 161.798762 -15.813786)
		(end 162.814762 -15.813786)
		(width 0.127)
		(layer "B.Cu")
		(net "LS_EN_N")
	)
	(segment
		(start 160.784286 -15.813786)
		(end 160.782 -15.8115)
		(width 0.127)
		(layer "B.Cu")
		(net "LS_EN_N")
	)
	(segment
		(start 162.814762 -15.813786)
		(end 164.084 -15.813786)
		(width 0.127)
		(layer "B.Cu")
		(net "LS_EN_N")
	)
	(segment
		(start 164.5539 -14.0081)
		(end 160.909 -17.653)
		(width 0.127)
		(layer "In2.Cu")
		(net "LS_EN_N")
	)
	(segment
		(start 122.37212 -39.943532)
		(end 108.663994 -39.943532)
		(width 0.127)
		(layer "In2.Cu")
		(net "LS_EN_N")
	)
	(segment
		(start 83.346036 -63.229998)
		(end 83.346036 -64.19088)
		(width 0.127)
		(layer "In2.Cu")
		(net "LS_EN_N")
	)
	(segment
		(start 91.241372 -52.62753)
		(end 88.392 -55.476902)
		(width 0.127)
		(layer "In2.Cu")
		(net "LS_EN_N")
	)
	(segment
		(start 138.967972 -23.34768)
		(end 122.37212 -39.943532)
		(width 0.127)
		(layer "In2.Cu")
		(net "LS_EN_N")
	)
	(segment
		(start 93.439488 -52.62753)
		(end 91.241372 -52.62753)
		(width 0.127)
		(layer "In2.Cu")
		(net "LS_EN_N")
	)
	(segment
		(start 94.619318 -51.4477)
		(end 93.439488 -52.62753)
		(width 0.127)
		(layer "In2.Cu")
		(net "LS_EN_N")
	)
	(segment
		(start 156.838142 -17.653)
		(end 151.143462 -23.34768)
		(width 0.127)
		(layer "In2.Cu")
		(net "LS_EN_N")
	)
	(segment
		(start 88.392 -56.533288)
		(end 87.15756 -57.767728)
		(width 0.127)
		(layer "In2.Cu")
		(net "LS_EN_N")
	)
	(segment
		(start 87.15756 -59.418474)
		(end 83.346036 -63.229998)
		(width 0.127)
		(layer "In2.Cu")
		(net "LS_EN_N")
	)
	(segment
		(start 94.619318 -46.319948)
		(end 94.619318 -51.4477)
		(width 0.127)
		(layer "In2.Cu")
		(net "LS_EN_N")
	)
	(segment
		(start 167.423846 -14.0081)
		(end 164.5539 -14.0081)
		(width 0.127)
		(layer "In2.Cu")
		(net "LS_EN_N")
	)
	(segment
		(start 102.733602 -45.873924)
		(end 95.398844 -45.873924)
		(width 0.127)
		(layer "In2.Cu")
		(net "LS_EN_N")
	)
	(segment
		(start 160.909 -17.653)
		(end 156.838142 -17.653)
		(width 0.127)
		(layer "In2.Cu")
		(net "LS_EN_N")
	)
	(segment
		(start 168.732454 -12.699492)
		(end 167.423846 -14.0081)
		(width 0.127)
		(layer "In2.Cu")
		(net "LS_EN_N")
	)
	(segment
		(start 95.398844 -45.873924)
		(end 94.95282 -46.319948)
		(width 0.127)
		(layer "In2.Cu")
		(net "LS_EN_N")
	)
	(segment
		(start 151.143462 -23.34768)
		(end 138.967972 -23.34768)
		(width 0.127)
		(layer "In2.Cu")
		(net "LS_EN_N")
	)
	(segment
		(start 88.392 -55.476902)
		(end 88.392 -56.533288)
		(width 0.127)
		(layer "In2.Cu")
		(net "LS_EN_N")
	)
	(segment
		(start 94.95282 -46.319948)
		(end 94.619318 -46.319948)
		(width 0.127)
		(layer "In2.Cu")
		(net "LS_EN_N")
	)
	(segment
		(start 87.15756 -57.767728)
		(end 87.15756 -59.418474)
		(width 0.127)
		(layer "In2.Cu")
		(net "LS_EN_N")
	)
	(segment
		(start 108.663994 -39.943532)
		(end 102.733602 -45.873924)
		(width 0.127)
		(layer "In2.Cu")
		(net "LS_EN_N")
	)
	(segment
		(start 87.353394 -36.631372)
		(end 88.361266 -37.639244)
		(width 0.127)
		(layer "In5.Cu")
		(net "LS_EN_N")
	)
	(segment
		(start 88.361266 -41.39438)
		(end 92.906342 -45.939456)
		(width 0.127)
		(layer "In5.Cu")
		(net "LS_EN_N")
	)
	(segment
		(start 88.361266 -37.639244)
		(end 88.361266 -41.39438)
		(width 0.127)
		(layer "In5.Cu")
		(net "LS_EN_N")
	)
	(segment
		(start 70.961758 -17.570958)
		(end 75.120754 -21.729954)
		(width 0.127)
		(layer "In5.Cu")
		(net "LS_EN_N")
	)
	(segment
		(start 75.120754 -21.729954)
		(end 79.214218 -21.729954)
		(width 0.127)
		(layer "In5.Cu")
		(net "LS_EN_N")
	)
	(segment
		(start 64.809116 -17.570958)
		(end 70.961758 -17.570958)
		(width 0.127)
		(layer "In5.Cu")
		(net "LS_EN_N")
	)
	(segment
		(start 92.906342 -45.939456)
		(end 94.238826 -45.939456)
		(width 0.127)
		(layer "In5.Cu")
		(net "LS_EN_N")
	)
	(segment
		(start 79.214218 -21.729954)
		(end 87.353394 -29.86913)
		(width 0.127)
		(layer "In5.Cu")
		(net "LS_EN_N")
	)
	(segment
		(start 94.238826 -45.939456)
		(end 94.619318 -46.319948)
		(width 0.127)
		(layer "In5.Cu")
		(net "LS_EN_N")
	)
	(segment
		(start 87.353394 -29.86913)
		(end 87.353394 -36.631372)
		(width 0.127)
		(layer "In5.Cu")
		(net "LS_EN_N")
	)
	(segment
		(start 11.668252 -58.406792)
		(end 11.668252 -58.916316)
		(width 0.127)
		(layer "F.Cu")
		(net "HSW_SDA_2")
	)
	(segment
		(start 13.0048 -57.4294)
		(end 13.0048 -56.7182)
		(width 0.127)
		(layer "F.Cu")
		(net "HSW_SDA_2")
	)
	(segment
		(start 13.0048 -57.846722)
		(end 12.720828 -58.130694)
		(width 0.127)
		(layer "F.Cu")
		(net "HSW_SDA_2")
	)
	(segment
		(start 13.0048 -57.4294)
		(end 13.0048 -57.846722)
		(width 0.127)
		(layer "F.Cu")
		(net "HSW_SDA_2")
	)
	(segment
		(start 11.94435 -58.130694)
		(end 11.668252 -58.406792)
		(width 0.127)
		(layer "F.Cu")
		(net "HSW_SDA_2")
	)
	(segment
		(start 12.694666 -56.408066)
		(end 12.694666 -55.7403)
		(width 0.127)
		(layer "F.Cu")
		(net "HSW_SDA_2")
	)
	(segment
		(start 12.720828 -58.130694)
		(end 11.94435 -58.130694)
		(width 0.127)
		(layer "F.Cu")
		(net "HSW_SDA_2")
	)
	(segment
		(start 13.0048 -56.7182)
		(end 12.694666 -56.408066)
		(width 0.127)
		(layer "F.Cu")
		(net "HSW_SDA_2")
	)
	(via
		(at 13.0048 -57.4294)
		(size 0.6604)
		(drill 0.3302)
		(layers "F.Cu" "B.Cu")
		(net "HSW_SDA_2")
	)
	(segment
		(start 11.109198 -57.542684)
		(end 11.646916 -57.542684)
		(width 0.127)
		(layer "F.Cu")
		(net "HSW_SCL_2")
	)
	(segment
		(start 11.646916 -57.542684)
		(end 11.7348 -57.4548)
		(width 0.127)
		(layer "F.Cu")
		(net "HSW_SCL_2")
	)
	(segment
		(start 10.652252 -57.99963)
		(end 11.109198 -57.542684)
		(width 0.127)
		(layer "F.Cu")
		(net "HSW_SCL_2")
	)
	(segment
		(start 12.19454 -55.8165)
		(end 12.19454 -56.99506)
		(width 0.127)
		(layer "F.Cu")
		(net "HSW_SCL_2")
	)
	(segment
		(start 10.652252 -58.916316)
		(end 10.652252 -57.99963)
		(width 0.127)
		(layer "F.Cu")
		(net "HSW_SCL_2")
	)
	(segment
		(start 12.19454 -56.99506)
		(end 11.7348 -57.4548)
		(width 0.127)
		(layer "F.Cu")
		(net "HSW_SCL_2")
	)
	(via
		(at 11.7348 -57.4548)
		(size 0.6604)
		(drill 0.3302)
		(layers "F.Cu" "B.Cu")
		(net "HSW_SCL_2")
	)
	(segment
		(start 120.50014 -65.50025)
		(end 120.50014 -65.499996)
		(width 0.4572)
		(layer "F.Cu")
		(net "GB_VDDH")
	)
	(segment
		(start 118.000018 -62.00013)
		(end 118.49989 -62.500002)
		(width 0.4572)
		(layer "F.Cu")
		(net "GB_VDDH")
	)
	(segment
		(start 120.000014 -62.00013)
		(end 120.499886 -62.500002)
		(width 0.4572)
		(layer "F.Cu")
		(net "GB_VDDH")
	)
	(segment
		(start 120.50014 -69.500242)
		(end 121.000012 -70.000114)
		(width 0.4572)
		(layer "F.Cu")
		(net "GB_VDDH")
	)
	(segment
		(start 109.500162 -62.500002)
		(end 109.499908 -62.500002)
		(width 0.4572)
		(layer "F.Cu")
		(net "GB_VDDH")
	)
	(segment
		(start 121.000012 -66.000122)
		(end 120.50014 -65.50025)
		(width 0.4572)
		(layer "F.Cu")
		(net "GB_VDDH")
	)
	(segment
		(start 112.00003 -62.00013)
		(end 111.500158 -62.500002)
		(width 0.4572)
		(layer "F.Cu")
		(net "GB_VDDH")
	)
	(segment
		(start 120.50014 -63.500254)
		(end 120.50014 -63.5)
		(width 0.4572)
		(layer "F.Cu")
		(net "GB_VDDH")
	)
	(segment
		(start 121.000012 -70.000114)
		(end 120.50014 -70.499986)
		(width 0.4572)
		(layer "F.Cu")
		(net "GB_VDDH")
	)
	(segment
		(start 120.50014 -70.499986)
		(end 120.50014 -70.50024)
		(width 0.4572)
		(layer "F.Cu")
		(net "GB_VDDH")
	)
	(segment
		(start 116.000022 -62.00013)
		(end 116.499894 -62.500002)
		(width 0.4572)
		(layer "F.Cu")
		(net "GB_VDDH")
	)
	(segment
		(start 110.000034 -62.00013)
		(end 109.500162 -62.500002)
		(width 0.4572)
		(layer "F.Cu")
		(net "GB_VDDH")
	)
	(segment
		(start 112.499902 -62.500002)
		(end 112.00003 -62.00013)
		(width 0.4572)
		(layer "F.Cu")
		(net "GB_VDDH")
	)
	(segment
		(start 119.500142 -62.500002)
		(end 120.000014 -62.00013)
		(width 0.4572)
		(layer "F.Cu")
		(net "GB_VDDH")
	)
	(segment
		(start 120.50014 -64.499998)
		(end 121.000012 -64.000126)
		(width 0.4572)
		(layer "F.Cu")
		(net "GB_VDDH")
	)
	(segment
		(start 111.500158 -62.500002)
		(end 111.499904 -62.500002)
		(width 0.4572)
		(layer "F.Cu")
		(net "GB_VDDH")
	)
	(segment
		(start 118.49989 -62.500002)
		(end 118.500144 -62.500002)
		(width 0.4572)
		(layer "F.Cu")
		(net "GB_VDDH")
	)
	(segment
		(start 121.000012 -68.000118)
		(end 120.50014 -68.49999)
		(width 0.4572)
		(layer "F.Cu")
		(net "GB_VDDH")
	)
	(segment
		(start 114.499898 -62.500002)
		(end 114.000026 -62.00013)
		(width 0.4572)
		(layer "F.Cu")
		(net "GB_VDDH")
	)
	(segment
		(start 113.500154 -62.500002)
		(end 113.4999 -62.500002)
		(width 0.4572)
		(layer "F.Cu")
		(net "GB_VDDH")
	)
	(segment
		(start 116.499894 -62.500002)
		(end 116.500148 -62.500002)
		(width 0.4572)
		(layer "F.Cu")
		(net "GB_VDDH")
	)
	(segment
		(start 117.500146 -62.500002)
		(end 118.000018 -62.00013)
		(width 0.4572)
		(layer "F.Cu")
		(net "GB_VDDH")
	)
	(segment
		(start 120.50014 -68.49999)
		(end 120.50014 -68.500244)
		(width 0.4572)
		(layer "F.Cu")
		(net "GB_VDDH")
	)
	(segment
		(start 114.000026 -62.00013)
		(end 113.500154 -62.500002)
		(width 0.4572)
		(layer "F.Cu")
		(net "GB_VDDH")
	)
	(segment
		(start 115.50015 -62.500002)
		(end 116.000022 -62.00013)
		(width 0.4572)
		(layer "F.Cu")
		(net "GB_VDDH")
	)
	(segment
		(start 120.50014 -66.499994)
		(end 121.000012 -66.000122)
		(width 0.4572)
		(layer "F.Cu")
		(net "GB_VDDH")
	)
	(segment
		(start 120.499886 -62.500002)
		(end 120.50014 -62.500002)
		(width 0.4572)
		(layer "F.Cu")
		(net "GB_VDDH")
	)
	(segment
		(start 110.499906 -62.500002)
		(end 110.000034 -62.00013)
		(width 0.4572)
		(layer "F.Cu")
		(net "GB_VDDH")
	)
	(segment
		(start 120.50014 -67.500246)
		(end 121.000012 -68.000118)
		(width 0.4572)
		(layer "F.Cu")
		(net "GB_VDDH")
	)
	(segment
		(start 121.000012 -64.000126)
		(end 120.50014 -63.500254)
		(width 0.4572)
		(layer "F.Cu")
		(net "GB_VDDH")
	)
	(via
		(at 147.328636 -75.698604)
		(size 0.7112)
		(drill 0.4064)
		(layers "F.Cu" "B.Cu")
		(net "GB_VDDH")
	)
	(via
		(at 146.693636 -74.555604)
		(size 0.7112)
		(drill 0.4064)
		(layers "F.Cu" "B.Cu")
		(net "GB_VDDH")
	)
	(via
		(at 146.084036 -75.698604)
		(size 0.7112)
		(drill 0.4064)
		(layers "F.Cu" "B.Cu")
		(net "GB_VDDH")
	)
	(via
		(at 143.790162 -98.154236)
		(size 0.6604)
		(drill 0.3302)
		(layers "F.Cu" "B.Cu")
		(net "GB_VDDH")
	)
	(via
		(at 144.564608 -96.242632)
		(size 0.6604)
		(drill 0.3302)
		(layers "F.Cu" "B.Cu")
		(net "GB_VDDH")
	)
	(via
		(at 143.36141 -96.604836)
		(size 0.6604)
		(drill 0.3302)
		(layers "F.Cu" "B.Cu")
		(net "GB_VDDH")
	)
	(via
		(at 121.000012 -66.000122)
		(size 0.4572)
		(drill 0.2032)
		(layers "F.Cu" "B.Cu")
		(net "GB_VDDH")
	)
	(via
		(at 114.000026 -62.00013)
		(size 0.4572)
		(drill 0.2032)
		(layers "F.Cu" "B.Cu")
		(net "GB_VDDH")
	)
	(via
		(at 110.000034 -62.00013)
		(size 0.4572)
		(drill 0.2032)
		(layers "F.Cu" "B.Cu")
		(net "GB_VDDH")
	)
	(via
		(at 147.749768 -97.632012)
		(size 0.7112)
		(drill 0.4064)
		(layers "F.Cu" "B.Cu")
		(net "GB_VDDH")
	)
	(via
		(at 145.449036 -74.555604)
		(size 0.7112)
		(drill 0.4064)
		(layers "F.Cu" "B.Cu")
		(net "GB_VDDH")
	)
	(via
		(at 118.000018 -62.00013)
		(size 0.4572)
		(drill 0.2032)
		(layers "F.Cu" "B.Cu")
		(net "GB_VDDH")
	)
	(via
		(at 121.000012 -70.000114)
		(size 0.4572)
		(drill 0.2032)
		(layers "F.Cu" "B.Cu")
		(net "GB_VDDH")
	)
	(via
		(at 121.000012 -64.000126)
		(size 0.4572)
		(drill 0.2032)
		(layers "F.Cu" "B.Cu")
		(net "GB_VDDH")
	)
	(via
		(at 142.116556 -97.766378)
		(size 0.6604)
		(drill 0.3302)
		(layers "F.Cu" "B.Cu")
		(net "GB_VDDH")
	)
	(via
		(at 116.000022 -62.00013)
		(size 0.4572)
		(drill 0.2032)
		(layers "F.Cu" "B.Cu")
		(net "GB_VDDH")
	)
	(via
		(at 144.839436 -75.698604)
		(size 0.7112)
		(drill 0.4064)
		(layers "F.Cu" "B.Cu")
		(net "GB_VDDH")
	)
	(via
		(at 145.303748 -97.632012)
		(size 0.7112)
		(drill 0.4064)
		(layers "F.Cu" "B.Cu")
		(net "GB_VDDH")
	)
	(via
		(at 147.596098 -96.410526)
		(size 0.7112)
		(drill 0.4064)
		(layers "F.Cu" "B.Cu")
		(net "GB_VDDH")
	)
	(via
		(at 121.000012 -68.000118)
		(size 0.4572)
		(drill 0.2032)
		(layers "F.Cu" "B.Cu")
		(net "GB_VDDH")
	)
	(via
		(at 120.000014 -62.00013)
		(size 0.4572)
		(drill 0.2032)
		(layers "F.Cu" "B.Cu")
		(net "GB_VDDH")
	)
	(via
		(at 146.376898 -96.410526)
		(size 0.7112)
		(drill 0.4064)
		(layers "F.Cu" "B.Cu")
		(net "GB_VDDH")
	)
	(via
		(at 146.522948 -97.632012)
		(size 0.7112)
		(drill 0.4064)
		(layers "F.Cu" "B.Cu")
		(net "GB_VDDH")
	)
	(via
		(at 112.00003 -62.00013)
		(size 0.4572)
		(drill 0.2032)
		(layers "F.Cu" "B.Cu")
		(net "GB_VDDH")
	)
	(segment
		(start 135.902192 -77.272134)
		(end 135.646414 -77.272134)
		(width 0.12446)
		(layer "F.Cu")
		(net "PHY_EXP_TO_CONN_C_9_DP")
	)
	(segment
		(start 135.073644 -77.370178)
		(end 133.42366 -75.720194)
		(width 0.12446)
		(layer "F.Cu")
		(net "PHY_EXP_TO_CONN_C_9_DP")
	)
	(segment
		(start 132.778754 -75.075288)
		(end 132.458714 -74.755248)
		(width 0.12446)
		(layer "F.Cu")
		(net "PHY_EXP_TO_CONN_C_9_DP")
	)
	(segment
		(start 133.159754 -75.075288)
		(end 132.778754 -75.075288)
		(width 0.12446)
		(layer "F.Cu")
		(net "PHY_EXP_TO_CONN_C_9_DP")
	)
	(segment
		(start 130.095244 -74.762614)
		(end 130.095244 -74.589132)
		(width 0.0889)
		(layer "F.Cu")
		(net "PHY_EXP_TO_CONN_C_9_DP")
	)
	(segment
		(start 135.646414 -77.272134)
		(end 135.54837 -77.370178)
		(width 0.12446)
		(layer "F.Cu")
		(net "PHY_EXP_TO_CONN_C_9_DP")
	)
	(segment
		(start 135.54837 -77.370178)
		(end 135.073644 -77.370178)
		(width 0.12446)
		(layer "F.Cu")
		(net "PHY_EXP_TO_CONN_C_9_DP")
	)
	(segment
		(start 133.42366 -75.339448)
		(end 133.159754 -75.075288)
		(width 0.12446)
		(layer "F.Cu")
		(net "PHY_EXP_TO_CONN_C_9_DP")
	)
	(segment
		(start 133.42366 -75.720194)
		(end 133.42366 -75.339448)
		(width 0.12446)
		(layer "F.Cu")
		(net "PHY_EXP_TO_CONN_C_9_DP")
	)
	(segment
		(start 131.72567 -74.755248)
		(end 131.703572 -74.755248)
		(width 0.0889)
		(layer "F.Cu")
		(net "PHY_EXP_TO_CONN_C_9_DP")
	)
	(segment
		(start 131.539488 -74.919332)
		(end 130.251708 -74.919332)
		(width 0.0889)
		(layer "F.Cu")
		(net "PHY_EXP_TO_CONN_C_9_DP")
	)
	(segment
		(start 130.184144 -74.500232)
		(end 130.50012 -74.500232)
		(width 0.0889)
		(layer "F.Cu")
		(net "PHY_EXP_TO_CONN_C_9_DP")
	)
	(segment
		(start 131.703572 -74.755248)
		(end 131.539488 -74.919332)
		(width 0.0889)
		(layer "F.Cu")
		(net "PHY_EXP_TO_CONN_C_9_DP")
	)
	(segment
		(start 132.458714 -74.755248)
		(end 131.72567 -74.755248)
		(width 0.12446)
		(layer "F.Cu")
		(net "PHY_EXP_TO_CONN_C_9_DP")
	)
	(arc
		(start 130.095244 -74.589132)
		(mid 130.121282 -74.52627)
		(end 130.184144 -74.500232)
		(width 0.0889)
		(layer "F.Cu")
		(net "PHY_EXP_TO_CONN_C_9_DP")
	)
	(arc
		(start 130.251708 -74.919332)
		(mid 130.191915 -74.907456)
		(end 130.141218 -74.873612)
		(width 0.0889)
		(layer "F.Cu")
		(net "PHY_EXP_TO_CONN_C_9_DP")
	)
	(arc
		(start 130.141218 -74.873612)
		(mid 130.10719 -74.822686)
		(end 130.095244 -74.762614)
		(width 0.0889)
		(layer "F.Cu")
		(net "PHY_EXP_TO_CONN_C_9_DP")
	)
	(segment
		(start 134.905242 -77.776578)
		(end 132.290312 -75.161648)
		(width 0.12446)
		(layer "F.Cu")
		(net "PHY_EXP_TO_CONN_C_9_DN")
	)
	(segment
		(start 135.627618 -77.830934)
		(end 135.573262 -77.776578)
		(width 0.12446)
		(layer "F.Cu")
		(net "PHY_EXP_TO_CONN_C_9_DN")
	)
	(segment
		(start 135.902192 -77.830934)
		(end 135.627618 -77.830934)
		(width 0.12446)
		(layer "F.Cu")
		(net "PHY_EXP_TO_CONN_C_9_DN")
	)
	(segment
		(start 131.72567 -75.161648)
		(end 131.703572 -75.161648)
		(width 0.0889)
		(layer "F.Cu")
		(net "PHY_EXP_TO_CONN_C_9_DN")
	)
	(segment
		(start 132.290312 -75.161648)
		(end 131.72567 -75.161648)
		(width 0.12446)
		(layer "F.Cu")
		(net "PHY_EXP_TO_CONN_C_9_DN")
	)
	(segment
		(start 129.815844 -74.500232)
		(end 129.500122 -74.500232)
		(width 0.0889)
		(layer "F.Cu")
		(net "PHY_EXP_TO_CONN_C_9_DN")
	)
	(segment
		(start 129.904744 -74.762614)
		(end 129.904744 -74.589132)
		(width 0.0889)
		(layer "F.Cu")
		(net "PHY_EXP_TO_CONN_C_9_DN")
	)
	(segment
		(start 131.703572 -75.161648)
		(end 131.651756 -75.109832)
		(width 0.0889)
		(layer "F.Cu")
		(net "PHY_EXP_TO_CONN_C_9_DN")
	)
	(segment
		(start 135.573262 -77.776578)
		(end 134.905242 -77.776578)
		(width 0.12446)
		(layer "F.Cu")
		(net "PHY_EXP_TO_CONN_C_9_DN")
	)
	(segment
		(start 131.651756 -75.109832)
		(end 130.251708 -75.109832)
		(width 0.0889)
		(layer "F.Cu")
		(net "PHY_EXP_TO_CONN_C_9_DN")
	)
	(arc
		(start 129.904744 -74.589132)
		(mid 129.878706 -74.52627)
		(end 129.815844 -74.500232)
		(width 0.0889)
		(layer "F.Cu")
		(net "PHY_EXP_TO_CONN_C_9_DN")
	)
	(arc
		(start 130.006598 -75.008486)
		(mid 129.931223 -74.895679)
		(end 129.904744 -74.762614)
		(width 0.0889)
		(layer "F.Cu")
		(net "PHY_EXP_TO_CONN_C_9_DN")
	)
	(arc
		(start 130.251708 -75.109832)
		(mid 130.119097 -75.08349)
		(end 130.006598 -75.008486)
		(width 0.0889)
		(layer "F.Cu")
		(net "PHY_EXP_TO_CONN_C_9_DN")
	)
	(segment
		(start 135.709914 -75.35672)
		(end 135.969502 -75.35672)
		(width 0.12446)
		(layer "F.Cu")
		(net "PHY_EXP_TO_CONN_C_8_DP")
	)
	(segment
		(start 129.095246 -73.589134)
		(end 129.095246 -73.754488)
		(width 0.0889)
		(layer "F.Cu")
		(net "PHY_EXP_TO_CONN_C_8_DP")
	)
	(segment
		(start 134.33552 -74.720196)
		(end 135.077962 -75.462638)
		(width 0.12446)
		(layer "F.Cu")
		(net "PHY_EXP_TO_CONN_C_8_DP")
	)
	(segment
		(start 131.855718 -73.774046)
		(end 131.877816 -73.774046)
		(width 0.0889)
		(layer "F.Cu")
		(net "PHY_EXP_TO_CONN_C_8_DP")
	)
	(segment
		(start 135.603996 -75.462638)
		(end 135.709914 -75.35672)
		(width 0.12446)
		(layer "F.Cu")
		(net "PHY_EXP_TO_CONN_C_8_DP")
	)
	(segment
		(start 131.71043 -73.919334)
		(end 131.855718 -73.774046)
		(width 0.0889)
		(layer "F.Cu")
		(net "PHY_EXP_TO_CONN_C_8_DP")
	)
	(segment
		(start 129.260092 -73.919334)
		(end 131.71043 -73.919334)
		(width 0.0889)
		(layer "F.Cu")
		(net "PHY_EXP_TO_CONN_C_8_DP")
	)
	(segment
		(start 134.071614 -74.07529)
		(end 134.33552 -74.33945)
		(width 0.12446)
		(layer "F.Cu")
		(net "PHY_EXP_TO_CONN_C_8_DP")
	)
	(segment
		(start 133.38937 -73.774046)
		(end 133.690614 -74.07529)
		(width 0.12446)
		(layer "F.Cu")
		(net "PHY_EXP_TO_CONN_C_8_DP")
	)
	(segment
		(start 134.33552 -74.33945)
		(end 134.33552 -74.720196)
		(width 0.12446)
		(layer "F.Cu")
		(net "PHY_EXP_TO_CONN_C_8_DP")
	)
	(segment
		(start 129.500122 -73.500234)
		(end 129.184146 -73.500234)
		(width 0.0889)
		(layer "F.Cu")
		(net "PHY_EXP_TO_CONN_C_8_DP")
	)
	(segment
		(start 135.077962 -75.462638)
		(end 135.603996 -75.462638)
		(width 0.12446)
		(layer "F.Cu")
		(net "PHY_EXP_TO_CONN_C_8_DP")
	)
	(segment
		(start 131.877816 -73.774046)
		(end 133.38937 -73.774046)
		(width 0.12446)
		(layer "F.Cu")
		(net "PHY_EXP_TO_CONN_C_8_DP")
	)
	(segment
		(start 133.690614 -74.07529)
		(end 134.071614 -74.07529)
		(width 0.12446)
		(layer "F.Cu")
		(net "PHY_EXP_TO_CONN_C_8_DP")
	)
	(arc
		(start 129.095246 -73.754488)
		(mid 129.107794 -73.817572)
		(end 129.143506 -73.871074)
		(width 0.0889)
		(layer "F.Cu")
		(net "PHY_EXP_TO_CONN_C_8_DP")
	)
	(arc
		(start 129.143506 -73.871074)
		(mid 129.196996 -73.906815)
		(end 129.260092 -73.919334)
		(width 0.0889)
		(layer "F.Cu")
		(net "PHY_EXP_TO_CONN_C_8_DP")
	)
	(arc
		(start 129.184146 -73.500234)
		(mid 129.121284 -73.526272)
		(end 129.095246 -73.589134)
		(width 0.0889)
		(layer "F.Cu")
		(net "PHY_EXP_TO_CONN_C_8_DP")
	)
	(segment
		(start 135.69442 -75.91552)
		(end 135.969502 -75.91552)
		(width 0.12446)
		(layer "F.Cu")
		(net "PHY_EXP_TO_CONN_C_8_DN")
	)
	(segment
		(start 135.647938 -75.869038)
		(end 135.69442 -75.91552)
		(width 0.12446)
		(layer "F.Cu")
		(net "PHY_EXP_TO_CONN_C_8_DN")
	)
	(segment
		(start 131.855718 -74.180446)
		(end 131.877816 -74.180446)
		(width 0.0889)
		(layer "F.Cu")
		(net "PHY_EXP_TO_CONN_C_8_DN")
	)
	(segment
		(start 128.500124 -73.500234)
		(end 128.815846 -73.500234)
		(width 0.0889)
		(layer "F.Cu")
		(net "PHY_EXP_TO_CONN_C_8_DN")
	)
	(segment
		(start 128.904746 -73.589134)
		(end 128.904746 -73.754488)
		(width 0.0889)
		(layer "F.Cu")
		(net "PHY_EXP_TO_CONN_C_8_DN")
	)
	(segment
		(start 134.90956 -75.869038)
		(end 135.647938 -75.869038)
		(width 0.12446)
		(layer "F.Cu")
		(net "PHY_EXP_TO_CONN_C_8_DN")
	)
	(segment
		(start 133.220968 -74.180446)
		(end 134.90956 -75.869038)
		(width 0.12446)
		(layer "F.Cu")
		(net "PHY_EXP_TO_CONN_C_8_DN")
	)
	(segment
		(start 131.877816 -74.180446)
		(end 133.220968 -74.180446)
		(width 0.12446)
		(layer "F.Cu")
		(net "PHY_EXP_TO_CONN_C_8_DN")
	)
	(segment
		(start 129.260092 -74.109834)
		(end 131.785106 -74.109834)
		(width 0.0889)
		(layer "F.Cu")
		(net "PHY_EXP_TO_CONN_C_8_DN")
	)
	(segment
		(start 131.785106 -74.109834)
		(end 131.855718 -74.180446)
		(width 0.0889)
		(layer "F.Cu")
		(net "PHY_EXP_TO_CONN_C_8_DN")
	)
	(arc
		(start 128.904746 -73.754488)
		(mid 128.931697 -73.890541)
		(end 129.008632 -74.005948)
		(width 0.0889)
		(layer "F.Cu")
		(net "PHY_EXP_TO_CONN_C_8_DN")
	)
	(arc
		(start 128.815846 -73.500234)
		(mid 128.878708 -73.526272)
		(end 128.904746 -73.589134)
		(width 0.0889)
		(layer "F.Cu")
		(net "PHY_EXP_TO_CONN_C_8_DN")
	)
	(arc
		(start 129.008632 -74.005948)
		(mid 129.124032 -74.0829)
		(end 129.260092 -74.109834)
		(width 0.0889)
		(layer "F.Cu")
		(net "PHY_EXP_TO_CONN_C_8_DN")
	)
	(segment
		(start 130.842512 -76.796392)
		(end 130.719576 -76.919328)
		(width 0.0889)
		(layer "F.Cu")
		(net "PHY_EXP_TO_CONN_C_11_DP")
	)
	(segment
		(start 133.582156 -79.351886)
		(end 133.201156 -79.351886)
		(width 0.12446)
		(layer "F.Cu")
		(net "PHY_EXP_TO_CONN_C_11_DP")
	)
	(segment
		(start 130.719576 -76.919328)
		(end 130.299968 -76.919328)
		(width 0.0889)
		(layer "F.Cu")
		(net "PHY_EXP_TO_CONN_C_11_DP")
	)
	(segment
		(start 130.184144 -76.500228)
		(end 130.50012 -76.500228)
		(width 0.0889)
		(layer "F.Cu")
		(net "PHY_EXP_TO_CONN_C_11_DP")
	)
	(segment
		(start 135.70712 -80.5688)
		(end 135.60044 -80.67548)
		(width 0.12446)
		(layer "F.Cu")
		(net "PHY_EXP_TO_CONN_C_11_DP")
	)
	(segment
		(start 130.86461 -76.796392)
		(end 130.842512 -76.796392)
		(width 0.0889)
		(layer "F.Cu")
		(net "PHY_EXP_TO_CONN_C_11_DP")
	)
	(segment
		(start 133.201156 -79.351886)
		(end 132.93725 -79.08798)
		(width 0.12446)
		(layer "F.Cu")
		(net "PHY_EXP_TO_CONN_C_11_DP")
	)
	(segment
		(start 133.846062 -79.996792)
		(end 133.846062 -79.616046)
		(width 0.12446)
		(layer "F.Cu")
		(net "PHY_EXP_TO_CONN_C_11_DP")
	)
	(segment
		(start 135.9662 -80.5688)
		(end 135.70712 -80.5688)
		(width 0.12446)
		(layer "F.Cu")
		(net "PHY_EXP_TO_CONN_C_11_DP")
	)
	(segment
		(start 132.93725 -79.08798)
		(end 132.93725 -78.450694)
		(width 0.12446)
		(layer "F.Cu")
		(net "PHY_EXP_TO_CONN_C_11_DP")
	)
	(segment
		(start 131.282948 -76.796392)
		(end 130.86461 -76.796392)
		(width 0.12446)
		(layer "F.Cu")
		(net "PHY_EXP_TO_CONN_C_11_DP")
	)
	(segment
		(start 133.846062 -79.616046)
		(end 133.582156 -79.351886)
		(width 0.12446)
		(layer "F.Cu")
		(net "PHY_EXP_TO_CONN_C_11_DP")
	)
	(segment
		(start 134.52475 -80.67548)
		(end 133.846062 -79.996792)
		(width 0.12446)
		(layer "F.Cu")
		(net "PHY_EXP_TO_CONN_C_11_DP")
	)
	(segment
		(start 135.60044 -80.67548)
		(end 134.52475 -80.67548)
		(width 0.12446)
		(layer "F.Cu")
		(net "PHY_EXP_TO_CONN_C_11_DP")
	)
	(segment
		(start 132.93725 -78.450694)
		(end 131.282948 -76.796392)
		(width 0.12446)
		(layer "F.Cu")
		(net "PHY_EXP_TO_CONN_C_11_DP")
	)
	(segment
		(start 130.095244 -76.714604)
		(end 130.095244 -76.589128)
		(width 0.0889)
		(layer "F.Cu")
		(net "PHY_EXP_TO_CONN_C_11_DP")
	)
	(arc
		(start 130.299968 -76.919328)
		(mid 130.221624 -76.903744)
		(end 130.155188 -76.859384)
		(width 0.0889)
		(layer "F.Cu")
		(net "PHY_EXP_TO_CONN_C_11_DP")
	)
	(arc
		(start 130.095244 -76.589128)
		(mid 130.121282 -76.526266)
		(end 130.184144 -76.500228)
		(width 0.0889)
		(layer "F.Cu")
		(net "PHY_EXP_TO_CONN_C_11_DP")
	)
	(arc
		(start 130.155188 -76.859384)
		(mid 130.110804 -76.792958)
		(end 130.095244 -76.714604)
		(width 0.0889)
		(layer "F.Cu")
		(net "PHY_EXP_TO_CONN_C_11_DP")
	)
	(segment
		(start 135.649208 -81.08188)
		(end 134.356348 -81.08188)
		(width 0.12446)
		(layer "F.Cu")
		(net "PHY_EXP_TO_CONN_C_11_DN")
	)
	(segment
		(start 132.53085 -78.619096)
		(end 131.114546 -77.202792)
		(width 0.12446)
		(layer "F.Cu")
		(net "PHY_EXP_TO_CONN_C_11_DN")
	)
	(segment
		(start 130.86461 -77.202792)
		(end 130.842512 -77.202792)
		(width 0.0889)
		(layer "F.Cu")
		(net "PHY_EXP_TO_CONN_C_11_DN")
	)
	(segment
		(start 129.904744 -76.714604)
		(end 129.904744 -76.589128)
		(width 0.0889)
		(layer "F.Cu")
		(net "PHY_EXP_TO_CONN_C_11_DN")
	)
	(segment
		(start 135.694928 -81.1276)
		(end 135.649208 -81.08188)
		(width 0.12446)
		(layer "F.Cu")
		(net "PHY_EXP_TO_CONN_C_11_DN")
	)
	(segment
		(start 134.356348 -81.08188)
		(end 132.53085 -79.256382)
		(width 0.12446)
		(layer "F.Cu")
		(net "PHY_EXP_TO_CONN_C_11_DN")
	)
	(segment
		(start 129.815844 -76.500228)
		(end 129.500122 -76.500228)
		(width 0.0889)
		(layer "F.Cu")
		(net "PHY_EXP_TO_CONN_C_11_DN")
	)
	(segment
		(start 130.842512 -77.202792)
		(end 130.749548 -77.109828)
		(width 0.0889)
		(layer "F.Cu")
		(net "PHY_EXP_TO_CONN_C_11_DN")
	)
	(segment
		(start 130.749548 -77.109828)
		(end 130.299968 -77.109828)
		(width 0.0889)
		(layer "F.Cu")
		(net "PHY_EXP_TO_CONN_C_11_DN")
	)
	(segment
		(start 132.53085 -79.256382)
		(end 132.53085 -78.619096)
		(width 0.12446)
		(layer "F.Cu")
		(net "PHY_EXP_TO_CONN_C_11_DN")
	)
	(segment
		(start 135.9662 -81.1276)
		(end 135.694928 -81.1276)
		(width 0.12446)
		(layer "F.Cu")
		(net "PHY_EXP_TO_CONN_C_11_DN")
	)
	(segment
		(start 131.114546 -77.202792)
		(end 130.86461 -77.202792)
		(width 0.12446)
		(layer "F.Cu")
		(net "PHY_EXP_TO_CONN_C_11_DN")
	)
	(arc
		(start 129.904744 -76.589128)
		(mid 129.878706 -76.526266)
		(end 129.815844 -76.500228)
		(width 0.0889)
		(layer "F.Cu")
		(net "PHY_EXP_TO_CONN_C_11_DN")
	)
	(arc
		(start 130.299968 -77.109828)
		(mid 130.148654 -77.079841)
		(end 130.020314 -76.994258)
		(width 0.0889)
		(layer "F.Cu")
		(net "PHY_EXP_TO_CONN_C_11_DN")
	)
	(arc
		(start 130.020314 -76.994258)
		(mid 129.934719 -76.865922)
		(end 129.904744 -76.714604)
		(width 0.0889)
		(layer "F.Cu")
		(net "PHY_EXP_TO_CONN_C_11_DN")
	)
	(segment
		(start 129.293874 -75.91933)
		(end 130.738372 -75.91933)
		(width 0.0889)
		(layer "F.Cu")
		(net "PHY_EXP_TO_CONN_C_10_DP")
	)
	(segment
		(start 135.593074 -79.26705)
		(end 135.688832 -79.171292)
		(width 0.12446)
		(layer "F.Cu")
		(net "PHY_EXP_TO_CONN_C_10_DP")
	)
	(segment
		(start 130.869182 -76.05014)
		(end 131.068318 -76.05014)
		(width 0.0889)
		(layer "F.Cu")
		(net "PHY_EXP_TO_CONN_C_10_DP")
	)
	(segment
		(start 132.91693 -76.934314)
		(end 135.249666 -79.26705)
		(width 0.12446)
		(layer "F.Cu")
		(net "PHY_EXP_TO_CONN_C_10_DP")
	)
	(segment
		(start 132.653024 -76.289662)
		(end 132.91693 -76.553568)
		(width 0.12446)
		(layer "F.Cu")
		(net "PHY_EXP_TO_CONN_C_10_DP")
	)
	(segment
		(start 131.068318 -76.05014)
		(end 131.21386 -75.904598)
		(width 0.0889)
		(layer "F.Cu")
		(net "PHY_EXP_TO_CONN_C_10_DP")
	)
	(segment
		(start 131.21386 -75.904598)
		(end 131.235958 -75.904598)
		(width 0.0889)
		(layer "F.Cu")
		(net "PHY_EXP_TO_CONN_C_10_DP")
	)
	(segment
		(start 131.235958 -75.904598)
		(end 131.887214 -75.904598)
		(width 0.12446)
		(layer "F.Cu")
		(net "PHY_EXP_TO_CONN_C_10_DP")
	)
	(segment
		(start 130.738372 -75.91933)
		(end 130.869182 -76.05014)
		(width 0.0889)
		(layer "F.Cu")
		(net "PHY_EXP_TO_CONN_C_10_DP")
	)
	(segment
		(start 132.272278 -76.289662)
		(end 132.653024 -76.289662)
		(width 0.12446)
		(layer "F.Cu")
		(net "PHY_EXP_TO_CONN_C_10_DP")
	)
	(segment
		(start 129.500122 -75.50023)
		(end 129.184146 -75.50023)
		(width 0.0889)
		(layer "F.Cu")
		(net "PHY_EXP_TO_CONN_C_10_DP")
	)
	(segment
		(start 135.688832 -79.171292)
		(end 135.947912 -79.171292)
		(width 0.12446)
		(layer "F.Cu")
		(net "PHY_EXP_TO_CONN_C_10_DP")
	)
	(segment
		(start 132.91693 -76.553568)
		(end 132.91693 -76.934314)
		(width 0.12446)
		(layer "F.Cu")
		(net "PHY_EXP_TO_CONN_C_10_DP")
	)
	(segment
		(start 129.095246 -75.58913)
		(end 129.095246 -75.720702)
		(width 0.0889)
		(layer "F.Cu")
		(net "PHY_EXP_TO_CONN_C_10_DP")
	)
	(segment
		(start 131.887214 -75.904598)
		(end 132.272278 -76.289662)
		(width 0.12446)
		(layer "F.Cu")
		(net "PHY_EXP_TO_CONN_C_10_DP")
	)
	(segment
		(start 135.249666 -79.26705)
		(end 135.593074 -79.26705)
		(width 0.12446)
		(layer "F.Cu")
		(net "PHY_EXP_TO_CONN_C_10_DP")
	)
	(arc
		(start 129.095246 -75.720702)
		(mid 129.110366 -75.796714)
		(end 129.153412 -75.861164)
		(width 0.0889)
		(layer "F.Cu")
		(net "PHY_EXP_TO_CONN_C_10_DP")
	)
	(arc
		(start 129.153412 -75.861164)
		(mid 129.217857 -75.904224)
		(end 129.293874 -75.91933)
		(width 0.0889)
		(layer "F.Cu")
		(net "PHY_EXP_TO_CONN_C_10_DP")
	)
	(arc
		(start 129.184146 -75.50023)
		(mid 129.121284 -75.526268)
		(end 129.095246 -75.58913)
		(width 0.0889)
		(layer "F.Cu")
		(net "PHY_EXP_TO_CONN_C_10_DP")
	)
	(segment
		(start 130.790188 -76.24064)
		(end 131.143502 -76.24064)
		(width 0.0889)
		(layer "F.Cu")
		(net "PHY_EXP_TO_CONN_C_10_DN")
	)
	(segment
		(start 131.21386 -76.310998)
		(end 131.235958 -76.310998)
		(width 0.0889)
		(layer "F.Cu")
		(net "PHY_EXP_TO_CONN_C_10_DN")
	)
	(segment
		(start 128.904746 -75.58913)
		(end 128.904746 -75.720702)
		(width 0.0889)
		(layer "F.Cu")
		(net "PHY_EXP_TO_CONN_C_10_DN")
	)
	(segment
		(start 131.143502 -76.24064)
		(end 131.21386 -76.310998)
		(width 0.0889)
		(layer "F.Cu")
		(net "PHY_EXP_TO_CONN_C_10_DN")
	)
	(segment
		(start 129.293874 -76.10983)
		(end 130.659378 -76.10983)
		(width 0.0889)
		(layer "F.Cu")
		(net "PHY_EXP_TO_CONN_C_10_DN")
	)
	(segment
		(start 135.081264 -79.67345)
		(end 135.619998 -79.67345)
		(width 0.12446)
		(layer "F.Cu")
		(net "PHY_EXP_TO_CONN_C_10_DN")
	)
	(segment
		(start 131.235958 -76.310998)
		(end 131.718812 -76.310998)
		(width 0.12446)
		(layer "F.Cu")
		(net "PHY_EXP_TO_CONN_C_10_DN")
	)
	(segment
		(start 131.718812 -76.310998)
		(end 135.081264 -79.67345)
		(width 0.12446)
		(layer "F.Cu")
		(net "PHY_EXP_TO_CONN_C_10_DN")
	)
	(segment
		(start 128.500124 -75.50023)
		(end 128.815846 -75.50023)
		(width 0.0889)
		(layer "F.Cu")
		(net "PHY_EXP_TO_CONN_C_10_DN")
	)
	(segment
		(start 135.67664 -79.730092)
		(end 135.947912 -79.730092)
		(width 0.12446)
		(layer "F.Cu")
		(net "PHY_EXP_TO_CONN_C_10_DN")
	)
	(segment
		(start 130.659378 -76.10983)
		(end 130.790188 -76.24064)
		(width 0.0889)
		(layer "F.Cu")
		(net "PHY_EXP_TO_CONN_C_10_DN")
	)
	(segment
		(start 135.619998 -79.67345)
		(end 135.67664 -79.730092)
		(width 0.12446)
		(layer "F.Cu")
		(net "PHY_EXP_TO_CONN_C_10_DN")
	)
	(arc
		(start 129.018538 -75.996038)
		(mid 129.144892 -76.080309)
		(end 129.293874 -76.10983)
		(width 0.0889)
		(layer "F.Cu")
		(net "PHY_EXP_TO_CONN_C_10_DN")
	)
	(arc
		(start 128.815846 -75.50023)
		(mid 128.878708 -75.526268)
		(end 128.904746 -75.58913)
		(width 0.0889)
		(layer "F.Cu")
		(net "PHY_EXP_TO_CONN_C_10_DN")
	)
	(arc
		(start 128.904746 -75.720702)
		(mid 128.934269 -75.869683)
		(end 129.018538 -75.996038)
		(width 0.0889)
		(layer "F.Cu")
		(net "PHY_EXP_TO_CONN_C_10_DN")
	)
	(segment
		(start 109.337856 -89.223088)
		(end 109.337856 -90.518742)
		(width 0.127)
		(layer "F.Cu")
		(net "SCC_LOC_HEARTBEAT_LS")
	)
	(segment
		(start 67.369182 -15.784322)
		(end 68.109338 -15.784322)
		(width 0.127)
		(layer "F.Cu")
		(net "SCC_LOC_HEARTBEAT_LS")
	)
	(segment
		(start 119.500142 -82.500216)
		(end 119.500142 -83.109816)
		(width 0.127)
		(layer "F.Cu")
		(net "SCC_LOC_HEARTBEAT_LS")
	)
	(segment
		(start 68.109338 -15.784322)
		(end 70.621906 -18.29689)
		(width 0.127)
		(layer "F.Cu")
		(net "SCC_LOC_HEARTBEAT_LS")
	)
	(segment
		(start 70.621906 -18.29689)
		(end 70.621906 -20.87499)
		(width 0.127)
		(layer "F.Cu")
		(net "SCC_LOC_HEARTBEAT_LS")
	)
	(segment
		(start 66.319908 -15.92961)
		(end 67.223894 -15.92961)
		(width 0.127)
		(layer "F.Cu")
		(net "SCC_LOC_HEARTBEAT_LS")
	)
	(segment
		(start 109.337856 -88.157812)
		(end 109.337856 -89.223088)
		(width 0.127)
		(layer "F.Cu")
		(net "SCC_LOC_HEARTBEAT_LS")
	)
	(segment
		(start 67.223894 -15.92961)
		(end 67.369182 -15.784322)
		(width 0.127)
		(layer "F.Cu")
		(net "SCC_LOC_HEARTBEAT_LS")
	)
	(via
		(at 109.337856 -88.157812)
		(size 0.508)
		(drill 0.254)
		(layers "F.Cu" "B.Cu")
		(net "SCC_LOC_HEARTBEAT_LS")
	)
	(via
		(at 70.621906 -20.87499)
		(size 0.508)
		(drill 0.254)
		(layers "F.Cu" "B.Cu")
		(net "SCC_LOC_HEARTBEAT_LS")
	)
	(via
		(at 109.337856 -89.223088)
		(size 0.6604)
		(drill 0.3302)
		(layers "F.Cu" "B.Cu")
		(net "SCC_LOC_HEARTBEAT_LS")
	)
	(via
		(at 119.500142 -83.109816)
		(size 0.4572)
		(drill 0.2032)
		(layers "F.Cu" "B.Cu")
		(net "SCC_LOC_HEARTBEAT_LS")
	)
	(segment
		(start 100.171504 -89.388696)
		(end 108.106972 -89.388696)
		(width 0.127)
		(layer "In5.Cu")
		(net "SCC_LOC_HEARTBEAT_LS")
	)
	(segment
		(start 70.0913 -66.376804)
		(end 75.476354 -71.761858)
		(width 0.127)
		(layer "In5.Cu")
		(net "SCC_LOC_HEARTBEAT_LS")
	)
	(segment
		(start 75.476354 -77.384656)
		(end 77.050392 -78.958694)
		(width 0.127)
		(layer "In5.Cu")
		(net "SCC_LOC_HEARTBEAT_LS")
	)
	(segment
		(start 78.2828 -84.399374)
		(end 79.8068 -85.923374)
		(width 0.127)
		(layer "In5.Cu")
		(net "SCC_LOC_HEARTBEAT_LS")
	)
	(segment
		(start 69.394324 -20.87499)
		(end 68.309998 -21.959316)
		(width 0.127)
		(layer "In5.Cu")
		(net "SCC_LOC_HEARTBEAT_LS")
	)
	(segment
		(start 116.480082 -85.57514)
		(end 116.864892 -85.19033)
		(width 0.127)
		(layer "In5.Cu")
		(net "SCC_LOC_HEARTBEAT_LS")
	)
	(segment
		(start 116.480082 -85.873336)
		(end 116.480082 -85.57514)
		(width 0.127)
		(layer "In5.Cu")
		(net "SCC_LOC_HEARTBEAT_LS")
	)
	(segment
		(start 110.411768 -87.0839)
		(end 115.269518 -87.0839)
		(width 0.127)
		(layer "In5.Cu")
		(net "SCC_LOC_HEARTBEAT_LS")
	)
	(segment
		(start 109.337856 -88.157812)
		(end 110.411768 -87.0839)
		(width 0.127)
		(layer "In5.Cu")
		(net "SCC_LOC_HEARTBEAT_LS")
	)
	(segment
		(start 70.621906 -20.87499)
		(end 69.394324 -20.87499)
		(width 0.127)
		(layer "In5.Cu")
		(net "SCC_LOC_HEARTBEAT_LS")
	)
	(segment
		(start 98.107246 -91.452954)
		(end 100.171504 -89.388696)
		(width 0.127)
		(layer "In5.Cu")
		(net "SCC_LOC_HEARTBEAT_LS")
	)
	(segment
		(start 79.8068 -87.486744)
		(end 81.689956 -89.3699)
		(width 0.127)
		(layer "In5.Cu")
		(net "SCC_LOC_HEARTBEAT_LS")
	)
	(segment
		(start 82.2579 -89.3699)
		(end 84.340954 -91.452954)
		(width 0.127)
		(layer "In5.Cu")
		(net "SCC_LOC_HEARTBEAT_LS")
	)
	(segment
		(start 84.340954 -91.452954)
		(end 98.107246 -91.452954)
		(width 0.127)
		(layer "In5.Cu")
		(net "SCC_LOC_HEARTBEAT_LS")
	)
	(segment
		(start 70.0913 -31.173928)
		(end 70.0913 -66.376804)
		(width 0.127)
		(layer "In5.Cu")
		(net "SCC_LOC_HEARTBEAT_LS")
	)
	(segment
		(start 117.419628 -85.19033)
		(end 119.500142 -83.109816)
		(width 0.127)
		(layer "In5.Cu")
		(net "SCC_LOC_HEARTBEAT_LS")
	)
	(segment
		(start 68.309998 -21.959316)
		(end 68.309998 -29.392626)
		(width 0.127)
		(layer "In5.Cu")
		(net "SCC_LOC_HEARTBEAT_LS")
	)
	(segment
		(start 68.309998 -29.392626)
		(end 70.0913 -31.173928)
		(width 0.127)
		(layer "In5.Cu")
		(net "SCC_LOC_HEARTBEAT_LS")
	)
	(segment
		(start 77.050392 -80.165194)
		(end 78.2828 -81.397602)
		(width 0.127)
		(layer "In5.Cu")
		(net "SCC_LOC_HEARTBEAT_LS")
	)
	(segment
		(start 108.106972 -89.388696)
		(end 109.337856 -88.157812)
		(width 0.127)
		(layer "In5.Cu")
		(net "SCC_LOC_HEARTBEAT_LS")
	)
	(segment
		(start 115.269518 -87.0839)
		(end 116.480082 -85.873336)
		(width 0.127)
		(layer "In5.Cu")
		(net "SCC_LOC_HEARTBEAT_LS")
	)
	(segment
		(start 116.864892 -85.19033)
		(end 117.419628 -85.19033)
		(width 0.127)
		(layer "In5.Cu")
		(net "SCC_LOC_HEARTBEAT_LS")
	)
	(segment
		(start 75.476354 -71.761858)
		(end 75.476354 -77.384656)
		(width 0.127)
		(layer "In5.Cu")
		(net "SCC_LOC_HEARTBEAT_LS")
	)
	(segment
		(start 79.8068 -85.923374)
		(end 79.8068 -87.486744)
		(width 0.127)
		(layer "In5.Cu")
		(net "SCC_LOC_HEARTBEAT_LS")
	)
	(segment
		(start 81.689956 -89.3699)
		(end 82.2579 -89.3699)
		(width 0.127)
		(layer "In5.Cu")
		(net "SCC_LOC_HEARTBEAT_LS")
	)
	(segment
		(start 77.050392 -78.958694)
		(end 77.050392 -80.165194)
		(width 0.127)
		(layer "In5.Cu")
		(net "SCC_LOC_HEARTBEAT_LS")
	)
	(segment
		(start 78.2828 -81.397602)
		(end 78.2828 -84.399374)
		(width 0.127)
		(layer "In5.Cu")
		(net "SCC_LOC_HEARTBEAT_LS")
	)
	(segment
		(start 103.49992 -52.500022)
		(end 103.000048 -52.00015)
		(width 0.104902)
		(layer "F.Cu")
		(net "PHY_SCC_TO_DPB_15_DP")
	)
	(via
		(at 103.000048 -52.00015)
		(size 0.4572)
		(drill 0.2032)
		(layers "F.Cu" "B.Cu")
		(net "PHY_SCC_TO_DPB_15_DP")
	)
	(segment
		(start 100.652326 -45.404532)
		(end 100.582984 -45.011086)
		(width 0.1016)
		(layer "In5.Cu")
		(net "PHY_SCC_TO_DPB_15_DP")
	)
	(segment
		(start 100.848414 -32.529018)
		(end 100.309172 -29.992066)
		(width 0.1016)
		(layer "In5.Cu")
		(net "PHY_SCC_TO_DPB_15_DP")
	)
	(segment
		(start 100.582984 -43.581828)
		(end 100.587556 -43.555666)
		(width 0.1016)
		(layer "In5.Cu")
		(net "PHY_SCC_TO_DPB_15_DP")
	)
	(segment
		(start 90.347546 -12.946888)
		(end 90.347546 -10.871454)
		(width 0.1016)
		(layer "In5.Cu")
		(net "PHY_SCC_TO_DPB_15_DP")
	)
	(segment
		(start 103.347266 -50.523902)
		(end 103.347266 -50.102262)
		(width 0.1016)
		(layer "In5.Cu")
		(net "PHY_SCC_TO_DPB_15_DP")
	)
	(segment
		(start 103.347266 -50.546)
		(end 103.347266 -50.523902)
		(width 0.0889)
		(layer "In5.Cu")
		(net "PHY_SCC_TO_DPB_15_DP")
	)
	(segment
		(start 91.400122 -10.168382)
		(end 91.400122 -9.800082)
		(width 0.1016)
		(layer "In5.Cu")
		(net "PHY_SCC_TO_DPB_15_DP")
	)
	(segment
		(start 100.755704 -45.55236)
		(end 100.652326 -45.404532)
		(width 0.1016)
		(layer "In5.Cu")
		(net "PHY_SCC_TO_DPB_15_DP")
	)
	(segment
		(start 101.92258 -37.786056)
		(end 101.942138 -37.674804)
		(width 0.1016)
		(layer "In5.Cu")
		(net "PHY_SCC_TO_DPB_15_DP")
	)
	(segment
		(start 103.347266 -50.102262)
		(end 103.276654 -49.771046)
		(width 0.1016)
		(layer "In5.Cu")
		(net "PHY_SCC_TO_DPB_15_DP")
	)
	(segment
		(start 100.309172 -29.992066)
		(end 99.770184 -27.455622)
		(width 0.1016)
		(layer "In5.Cu")
		(net "PHY_SCC_TO_DPB_15_DP")
	)
	(segment
		(start 100.582984 -45.011086)
		(end 100.582984 -43.581828)
		(width 0.1016)
		(layer "In5.Cu")
		(net "PHY_SCC_TO_DPB_15_DP")
	)
	(segment
		(start 103.088948 -52.404772)
		(end 103.255318 -52.404772)
		(width 0.0889)
		(layer "In5.Cu")
		(net "PHY_SCC_TO_DPB_15_DP")
	)
	(segment
		(start 99.770184 -27.455622)
		(end 95.09887 -20.26285)
		(width 0.1016)
		(layer "In5.Cu")
		(net "PHY_SCC_TO_DPB_15_DP")
	)
	(segment
		(start 100.587556 -43.555666)
		(end 100.612194 -43.415204)
		(width 0.1016)
		(layer "In5.Cu")
		(net "PHY_SCC_TO_DPB_15_DP")
	)
	(segment
		(start 100.861622 -46.050454)
		(end 100.755704 -45.55236)
		(width 0.1016)
		(layer "In5.Cu")
		(net "PHY_SCC_TO_DPB_15_DP")
	)
	(segment
		(start 100.64877 -43.207686)
		(end 101.073458 -42.601896)
		(width 0.1016)
		(layer "In5.Cu")
		(net "PHY_SCC_TO_DPB_15_DP")
	)
	(segment
		(start 103.276654 -49.771046)
		(end 100.861622 -46.050454)
		(width 0.1016)
		(layer "In5.Cu")
		(net "PHY_SCC_TO_DPB_15_DP")
	)
	(segment
		(start 101.942138 -37.674804)
		(end 100.848414 -32.529018)
		(width 0.1016)
		(layer "In5.Cu")
		(net "PHY_SCC_TO_DPB_15_DP")
	)
	(segment
		(start 90.871294 -10.347706)
		(end 91.220798 -10.347706)
		(width 0.1016)
		(layer "In5.Cu")
		(net "PHY_SCC_TO_DPB_15_DP")
	)
	(segment
		(start 95.09887 -20.26285)
		(end 90.347546 -12.946888)
		(width 0.1016)
		(layer "In5.Cu")
		(net "PHY_SCC_TO_DPB_15_DP")
	)
	(segment
		(start 103.000048 -52.00015)
		(end 103.000048 -52.315872)
		(width 0.0889)
		(layer "In5.Cu")
		(net "PHY_SCC_TO_DPB_15_DP")
	)
	(segment
		(start 103.404416 -52.255674)
		(end 103.404416 -50.60315)
		(width 0.0889)
		(layer "In5.Cu")
		(net "PHY_SCC_TO_DPB_15_DP")
	)
	(segment
		(start 101.073458 -42.601896)
		(end 101.92258 -37.786056)
		(width 0.1016)
		(layer "In5.Cu")
		(net "PHY_SCC_TO_DPB_15_DP")
	)
	(segment
		(start 103.404416 -50.60315)
		(end 103.347266 -50.546)
		(width 0.0889)
		(layer "In5.Cu")
		(net "PHY_SCC_TO_DPB_15_DP")
	)
	(segment
		(start 100.62464 -43.344846)
		(end 100.64877 -43.207686)
		(width 0.1016)
		(layer "In5.Cu")
		(net "PHY_SCC_TO_DPB_15_DP")
	)
	(segment
		(start 100.612194 -43.415204)
		(end 100.62464 -43.344846)
		(width 0.1016)
		(layer "In5.Cu")
		(net "PHY_SCC_TO_DPB_15_DP")
	)
	(arc
		(start 103.000048 -52.315872)
		(mid 103.026086 -52.378734)
		(end 103.088948 -52.404772)
		(width 0.0889)
		(layer "In5.Cu")
		(net "PHY_SCC_TO_DPB_15_DP")
	)
	(arc
		(start 91.220798 -10.347706)
		(mid 91.347599 -10.295183)
		(end 91.400122 -10.168382)
		(width 0.1016)
		(layer "In5.Cu")
		(net "PHY_SCC_TO_DPB_15_DP")
	)
	(arc
		(start 103.360728 -52.361084)
		(mid 103.393043 -52.312721)
		(end 103.404416 -52.255674)
		(width 0.0889)
		(layer "In5.Cu")
		(net "PHY_SCC_TO_DPB_15_DP")
	)
	(arc
		(start 103.255318 -52.404772)
		(mid 103.312375 -52.393423)
		(end 103.360728 -52.361084)
		(width 0.0889)
		(layer "In5.Cu")
		(net "PHY_SCC_TO_DPB_15_DP")
	)
	(arc
		(start 90.347546 -10.871454)
		(mid 90.500948 -10.501108)
		(end 90.871294 -10.347706)
		(width 0.1016)
		(layer "In5.Cu")
		(net "PHY_SCC_TO_DPB_15_DP")
	)
	(segment
		(start 103.49992 -53.50002)
		(end 103.000048 -53.000148)
		(width 0.104902)
		(layer "F.Cu")
		(net "PHY_SCC_TO_DPB_15_DN")
	)
	(via
		(at 103.000048 -53.000148)
		(size 0.4572)
		(drill 0.2032)
		(layers "F.Cu" "B.Cu")
		(net "PHY_SCC_TO_DPB_15_DN")
	)
	(segment
		(start 103.563166 -49.652174)
		(end 103.321866 -49.280826)
		(width 0.1016)
		(layer "In5.Cu")
		(net "PHY_SCC_TO_DPB_15_DN")
	)
	(segment
		(start 103.321866 -49.280826)
		(end 103.378 -49.017428)
		(width 0.1016)
		(layer "In5.Cu")
		(net "PHY_SCC_TO_DPB_15_DN")
	)
	(segment
		(start 100.056696 -27.337004)
		(end 90.652346 -12.856464)
		(width 0.1016)
		(layer "In5.Cu")
		(net "PHY_SCC_TO_DPB_15_DN")
	)
	(segment
		(start 103.652066 -50.546)
		(end 103.652066 -50.523902)
		(width 0.0889)
		(layer "In5.Cu")
		(net "PHY_SCC_TO_DPB_15_DN")
	)
	(segment
		(start 101.040946 -45.428154)
		(end 100.94087 -45.285152)
		(width 0.1016)
		(layer "In5.Cu")
		(net "PHY_SCC_TO_DPB_15_DN")
	)
	(segment
		(start 103.378 -49.017428)
		(end 103.212138 -48.76165)
		(width 0.1016)
		(layer "In5.Cu")
		(net "PHY_SCC_TO_DPB_15_DN")
	)
	(segment
		(start 101.148134 -45.931836)
		(end 101.040946 -45.428154)
		(width 0.1016)
		(layer "In5.Cu")
		(net "PHY_SCC_TO_DPB_15_DN")
	)
	(segment
		(start 103.212138 -48.76165)
		(end 102.948486 -48.705516)
		(width 0.1016)
		(layer "In5.Cu")
		(net "PHY_SCC_TO_DPB_15_DN")
	)
	(segment
		(start 102.252526 -37.668962)
		(end 101.14661 -32.465772)
		(width 0.1016)
		(layer "In5.Cu")
		(net "PHY_SCC_TO_DPB_15_DN")
	)
	(segment
		(start 90.652346 -12.856464)
		(end 90.652346 -10.871454)
		(width 0.1016)
		(layer "In5.Cu")
		(net "PHY_SCC_TO_DPB_15_DN")
	)
	(segment
		(start 90.871294 -10.652506)
		(end 91.220798 -10.652506)
		(width 0.1016)
		(layer "In5.Cu")
		(net "PHY_SCC_TO_DPB_15_DN")
	)
	(segment
		(start 100.887784 -43.608498)
		(end 100.937314 -43.32732)
		(width 0.1016)
		(layer "In5.Cu")
		(net "PHY_SCC_TO_DPB_15_DN")
	)
	(segment
		(start 103.652066 -50.070004)
		(end 103.563166 -49.652174)
		(width 0.1016)
		(layer "In5.Cu")
		(net "PHY_SCC_TO_DPB_15_DN")
	)
	(segment
		(start 103.652066 -50.523902)
		(end 103.652066 -50.070004)
		(width 0.1016)
		(layer "In5.Cu")
		(net "PHY_SCC_TO_DPB_15_DN")
	)
	(segment
		(start 103.594916 -52.255674)
		(end 103.594916 -50.60315)
		(width 0.0889)
		(layer "In5.Cu")
		(net "PHY_SCC_TO_DPB_15_DN")
	)
	(segment
		(start 100.887784 -44.984162)
		(end 100.887784 -43.608498)
		(width 0.1016)
		(layer "In5.Cu")
		(net "PHY_SCC_TO_DPB_15_DN")
	)
	(segment
		(start 103.000048 -53.000148)
		(end 103.000048 -52.684172)
		(width 0.0889)
		(layer "In5.Cu")
		(net "PHY_SCC_TO_DPB_15_DN")
	)
	(segment
		(start 100.94087 -45.285152)
		(end 100.887784 -44.984162)
		(width 0.1016)
		(layer "In5.Cu")
		(net "PHY_SCC_TO_DPB_15_DN")
	)
	(segment
		(start 101.14661 -32.465772)
		(end 100.056696 -27.337004)
		(width 0.1016)
		(layer "In5.Cu")
		(net "PHY_SCC_TO_DPB_15_DN")
	)
	(segment
		(start 103.594916 -50.60315)
		(end 103.652066 -50.546)
		(width 0.0889)
		(layer "In5.Cu")
		(net "PHY_SCC_TO_DPB_15_DN")
	)
	(segment
		(start 102.223062 -37.838634)
		(end 102.252526 -37.668962)
		(width 0.1016)
		(layer "In5.Cu")
		(net "PHY_SCC_TO_DPB_15_DN")
	)
	(segment
		(start 100.937314 -43.32732)
		(end 101.362002 -42.72153)
		(width 0.1016)
		(layer "In5.Cu")
		(net "PHY_SCC_TO_DPB_15_DN")
	)
	(segment
		(start 103.088948 -52.595272)
		(end 103.255318 -52.595272)
		(width 0.0889)
		(layer "In5.Cu")
		(net "PHY_SCC_TO_DPB_15_DN")
	)
	(segment
		(start 102.948486 -48.705516)
		(end 101.148134 -45.931836)
		(width 0.1016)
		(layer "In5.Cu")
		(net "PHY_SCC_TO_DPB_15_DN")
	)
	(segment
		(start 91.400122 -10.83183)
		(end 91.400122 -11.20013)
		(width 0.1016)
		(layer "In5.Cu")
		(net "PHY_SCC_TO_DPB_15_DN")
	)
	(segment
		(start 101.362002 -42.72153)
		(end 102.223062 -37.838634)
		(width 0.1016)
		(layer "In5.Cu")
		(net "PHY_SCC_TO_DPB_15_DN")
	)
	(arc
		(start 91.220798 -10.652506)
		(mid 91.347599 -10.705029)
		(end 91.400122 -10.83183)
		(width 0.1016)
		(layer "In5.Cu")
		(net "PHY_SCC_TO_DPB_15_DN")
	)
	(arc
		(start 103.000048 -52.684172)
		(mid 103.026086 -52.62131)
		(end 103.088948 -52.595272)
		(width 0.0889)
		(layer "In5.Cu")
		(net "PHY_SCC_TO_DPB_15_DN")
	)
	(arc
		(start 103.255318 -52.595272)
		(mid 103.38533 -52.569505)
		(end 103.495602 -52.495958)
		(width 0.0889)
		(layer "In5.Cu")
		(net "PHY_SCC_TO_DPB_15_DN")
	)
	(arc
		(start 90.652346 -10.871454)
		(mid 90.716474 -10.716634)
		(end 90.871294 -10.652506)
		(width 0.1016)
		(layer "In5.Cu")
		(net "PHY_SCC_TO_DPB_15_DN")
	)
	(arc
		(start 103.495602 -52.495958)
		(mid 103.569181 -52.3857)
		(end 103.594916 -52.255674)
		(width 0.0889)
		(layer "In5.Cu")
		(net "PHY_SCC_TO_DPB_15_DN")
	)
	(segment
		(start 102.499922 -51.500024)
		(end 102.00005 -51.000152)
		(width 0.104902)
		(layer "F.Cu")
		(net "PHY_SCC_TO_DPB_14_DP")
	)
	(via
		(at 102.00005 -51.000152)
		(size 0.4572)
		(drill 0.2032)
		(layers "F.Cu" "B.Cu")
		(net "PHY_SCC_TO_DPB_14_DP")
	)
	(segment
		(start 100.892864 -37.868098)
		(end 99.918012 -33.28162)
		(width 0.1016)
		(layer "In5.Cu")
		(net "PHY_SCC_TO_DPB_14_DP")
	)
	(segment
		(start 102.408736 -51.26609)
		(end 102.408736 -50.620676)
		(width 0.0889)
		(layer "In5.Cu")
		(net "PHY_SCC_TO_DPB_14_DP")
	)
	(segment
		(start 99.917758 -33.28162)
		(end 98.943414 -28.695904)
		(width 0.1016)
		(layer "In5.Cu")
		(net "PHY_SCC_TO_DPB_14_DP")
	)
	(segment
		(start 102.00005 -51.000152)
		(end 102.00005 -51.315874)
		(width 0.0889)
		(layer "In5.Cu")
		(net "PHY_SCC_TO_DPB_14_DP")
	)
	(segment
		(start 99.058984 -43.524932)
		(end 99.06508 -43.489626)
		(width 0.1016)
		(layer "In5.Cu")
		(net "PHY_SCC_TO_DPB_14_DP")
	)
	(segment
		(start 89.164668 -14.492478)
		(end 88.617552 -13.650214)
		(width 0.1016)
		(layer "In5.Cu")
		(net "PHY_SCC_TO_DPB_14_DP")
	)
	(segment
		(start 98.943414 -28.695904)
		(end 90.124026 -15.115794)
		(width 0.1016)
		(layer "In5.Cu")
		(net "PHY_SCC_TO_DPB_14_DP")
	)
	(segment
		(start 100.064824 -41.764712)
		(end 100.892864 -37.868098)
		(width 0.1016)
		(layer "In5.Cu")
		(net "PHY_SCC_TO_DPB_14_DP")
	)
	(segment
		(start 102.351586 -50.541428)
		(end 102.351586 -50.071782)
		(width 0.1016)
		(layer "In5.Cu")
		(net "PHY_SCC_TO_DPB_14_DP")
	)
	(segment
		(start 102.351586 -50.071782)
		(end 99.305872 -45.38345)
		(width 0.1016)
		(layer "In5.Cu")
		(net "PHY_SCC_TO_DPB_14_DP")
	)
	(segment
		(start 88.617552 -13.650214)
		(end 88.547702 -13.321538)
		(width 0.1016)
		(layer "In5.Cu")
		(net "PHY_SCC_TO_DPB_14_DP")
	)
	(segment
		(start 102.08895 -51.404774)
		(end 102.270052 -51.404774)
		(width 0.0889)
		(layer "In5.Cu")
		(net "PHY_SCC_TO_DPB_14_DP")
	)
	(segment
		(start 99.306634 -45.383196)
		(end 99.058984 -45.001942)
		(width 0.1016)
		(layer "In5.Cu")
		(net "PHY_SCC_TO_DPB_14_DP")
	)
	(segment
		(start 99.135184 -43.092878)
		(end 100.064824 -41.764712)
		(width 0.1016)
		(layer "In5.Cu")
		(net "PHY_SCC_TO_DPB_14_DP")
	)
	(segment
		(start 99.305872 -45.38345)
		(end 99.306634 -45.383196)
		(width 0.1016)
		(layer "In5.Cu")
		(net "PHY_SCC_TO_DPB_14_DP")
	)
	(segment
		(start 102.408736 -50.620676)
		(end 102.351586 -50.563526)
		(width 0.0889)
		(layer "In5.Cu")
		(net "PHY_SCC_TO_DPB_14_DP")
	)
	(segment
		(start 99.918012 -33.28162)
		(end 99.917758 -33.28162)
		(width 0.1016)
		(layer "In5.Cu")
		(net "PHY_SCC_TO_DPB_14_DP")
	)
	(segment
		(start 99.058984 -45.001942)
		(end 99.058984 -43.524932)
		(width 0.1016)
		(layer "In5.Cu")
		(net "PHY_SCC_TO_DPB_14_DP")
	)
	(segment
		(start 89.600024 -11.368278)
		(end 89.600024 -10.999978)
		(width 0.1016)
		(layer "In5.Cu")
		(net "PHY_SCC_TO_DPB_14_DP")
	)
	(segment
		(start 89.071196 -11.547602)
		(end 89.4207 -11.547602)
		(width 0.1016)
		(layer "In5.Cu")
		(net "PHY_SCC_TO_DPB_14_DP")
	)
	(segment
		(start 90.124026 -15.115794)
		(end 89.164668 -14.492478)
		(width 0.1016)
		(layer "In5.Cu")
		(net "PHY_SCC_TO_DPB_14_DP")
	)
	(segment
		(start 88.547702 -13.321538)
		(end 88.547702 -12.071096)
		(width 0.1016)
		(layer "In5.Cu")
		(net "PHY_SCC_TO_DPB_14_DP")
	)
	(segment
		(start 102.351586 -50.563526)
		(end 102.351586 -50.541428)
		(width 0.0889)
		(layer "In5.Cu")
		(net "PHY_SCC_TO_DPB_14_DP")
	)
	(segment
		(start 99.06508 -43.489626)
		(end 99.135184 -43.092878)
		(width 0.1016)
		(layer "In5.Cu")
		(net "PHY_SCC_TO_DPB_14_DP")
	)
	(arc
		(start 102.00005 -51.315874)
		(mid 102.026088 -51.378736)
		(end 102.08895 -51.404774)
		(width 0.0889)
		(layer "In5.Cu")
		(net "PHY_SCC_TO_DPB_14_DP")
	)
	(arc
		(start 102.270052 -51.404774)
		(mid 102.323124 -51.394217)
		(end 102.368096 -51.364134)
		(width 0.0889)
		(layer "In5.Cu")
		(net "PHY_SCC_TO_DPB_14_DP")
	)
	(arc
		(start 102.368096 -51.364134)
		(mid 102.398153 -51.319151)
		(end 102.408736 -51.26609)
		(width 0.0889)
		(layer "In5.Cu")
		(net "PHY_SCC_TO_DPB_14_DP")
	)
	(arc
		(start 88.547702 -12.071096)
		(mid 88.70103 -11.70093)
		(end 89.071196 -11.547602)
		(width 0.1016)
		(layer "In5.Cu")
		(net "PHY_SCC_TO_DPB_14_DP")
	)
	(arc
		(start 89.4207 -11.547602)
		(mid 89.547501 -11.495079)
		(end 89.600024 -11.368278)
		(width 0.1016)
		(layer "In5.Cu")
		(net "PHY_SCC_TO_DPB_14_DP")
	)
	(segment
		(start 102.499922 -52.500022)
		(end 102.00005 -52.00015)
		(width 0.104902)
		(layer "F.Cu")
		(net "PHY_SCC_TO_DPB_14_DN")
	)
	(via
		(at 102.00005 -52.00015)
		(size 0.4572)
		(drill 0.2032)
		(layers "F.Cu" "B.Cu")
		(net "PHY_SCC_TO_DPB_14_DN")
	)
	(segment
		(start 102.00005 -52.00015)
		(end 102.00005 -51.684174)
		(width 0.0889)
		(layer "In5.Cu")
		(net "PHY_SCC_TO_DPB_14_DN")
	)
	(segment
		(start 99.229926 -28.577286)
		(end 90.344498 -14.895322)
		(width 0.1016)
		(layer "In5.Cu")
		(net "PHY_SCC_TO_DPB_14_DN")
	)
	(segment
		(start 102.656386 -50.541428)
		(end 102.656386 -49.981358)
		(width 0.1016)
		(layer "In5.Cu")
		(net "PHY_SCC_TO_DPB_14_DN")
	)
	(segment
		(start 90.289888 -14.860016)
		(end 89.38514 -14.272006)
		(width 0.1016)
		(layer "In5.Cu")
		(net "PHY_SCC_TO_DPB_14_DN")
	)
	(segment
		(start 102.599236 -51.26609)
		(end 102.599236 -50.620676)
		(width 0.0889)
		(layer "In5.Cu")
		(net "PHY_SCC_TO_DPB_14_DN")
	)
	(segment
		(start 100.190554 -45.834046)
		(end 100.024438 -45.578522)
		(width 0.1016)
		(layer "In5.Cu")
		(net "PHY_SCC_TO_DPB_14_DN")
	)
	(segment
		(start 100.35032 -41.888664)
		(end 101.204522 -37.868098)
		(width 0.1016)
		(layer "In5.Cu")
		(net "PHY_SCC_TO_DPB_14_DN")
	)
	(segment
		(start 89.600024 -12.031726)
		(end 89.600024 -12.400026)
		(width 0.1016)
		(layer "In5.Cu")
		(net "PHY_SCC_TO_DPB_14_DN")
	)
	(segment
		(start 89.38514 -14.272006)
		(end 88.904064 -13.531596)
		(width 0.1016)
		(layer "In5.Cu")
		(net "PHY_SCC_TO_DPB_14_DN")
	)
	(segment
		(start 90.344498 -14.895322)
		(end 90.289888 -14.859762)
		(width 0.1016)
		(layer "In5.Cu")
		(net "PHY_SCC_TO_DPB_14_DN")
	)
	(segment
		(start 100.024438 -45.578522)
		(end 99.76104 -45.522388)
		(width 0.1016)
		(layer "In5.Cu")
		(net "PHY_SCC_TO_DPB_14_DN")
	)
	(segment
		(start 100.134674 -46.097952)
		(end 100.13442 -46.097698)
		(width 0.1016)
		(layer "In5.Cu")
		(net "PHY_SCC_TO_DPB_14_DN")
	)
	(segment
		(start 99.76104 -45.522388)
		(end 99.363784 -44.911518)
		(width 0.1016)
		(layer "In5.Cu")
		(net "PHY_SCC_TO_DPB_14_DN")
	)
	(segment
		(start 100.350066 -41.888918)
		(end 100.35032 -41.888664)
		(width 0.1016)
		(layer "In5.Cu")
		(net "PHY_SCC_TO_DPB_14_DN")
	)
	(segment
		(start 99.363784 -43.551856)
		(end 99.423728 -43.212512)
		(width 0.1016)
		(layer "In5.Cu")
		(net "PHY_SCC_TO_DPB_14_DN")
	)
	(segment
		(start 102.656386 -50.563526)
		(end 102.656386 -50.541428)
		(width 0.0889)
		(layer "In5.Cu")
		(net "PHY_SCC_TO_DPB_14_DN")
	)
	(segment
		(start 101.204522 -37.868098)
		(end 99.229926 -28.577286)
		(width 0.1016)
		(layer "In5.Cu")
		(net "PHY_SCC_TO_DPB_14_DN")
	)
	(segment
		(start 102.08895 -51.595274)
		(end 102.270052 -51.595274)
		(width 0.0889)
		(layer "In5.Cu")
		(net "PHY_SCC_TO_DPB_14_DN")
	)
	(segment
		(start 88.852502 -13.28928)
		(end 88.852502 -12.071096)
		(width 0.1016)
		(layer "In5.Cu")
		(net "PHY_SCC_TO_DPB_14_DN")
	)
	(segment
		(start 102.599236 -50.620676)
		(end 102.656386 -50.563526)
		(width 0.0889)
		(layer "In5.Cu")
		(net "PHY_SCC_TO_DPB_14_DN")
	)
	(segment
		(start 90.289888 -14.859762)
		(end 90.289888 -14.860016)
		(width 0.1016)
		(layer "In5.Cu")
		(net "PHY_SCC_TO_DPB_14_DN")
	)
	(segment
		(start 89.071196 -11.852402)
		(end 89.4207 -11.852402)
		(width 0.1016)
		(layer "In5.Cu")
		(net "PHY_SCC_TO_DPB_14_DN")
	)
	(segment
		(start 88.904064 -13.531596)
		(end 88.852502 -13.28928)
		(width 0.1016)
		(layer "In5.Cu")
		(net "PHY_SCC_TO_DPB_14_DN")
	)
	(segment
		(start 99.423728 -43.212512)
		(end 100.350066 -41.888918)
		(width 0.1016)
		(layer "In5.Cu")
		(net "PHY_SCC_TO_DPB_14_DN")
	)
	(segment
		(start 100.13442 -46.097698)
		(end 100.190554 -45.834046)
		(width 0.1016)
		(layer "In5.Cu")
		(net "PHY_SCC_TO_DPB_14_DN")
	)
	(segment
		(start 99.363784 -44.911518)
		(end 99.363784 -43.551856)
		(width 0.1016)
		(layer "In5.Cu")
		(net "PHY_SCC_TO_DPB_14_DN")
	)
	(segment
		(start 102.656386 -49.981358)
		(end 100.134674 -46.097952)
		(width 0.1016)
		(layer "In5.Cu")
		(net "PHY_SCC_TO_DPB_14_DN")
	)
	(arc
		(start 88.852502 -12.071096)
		(mid 88.916556 -11.916456)
		(end 89.071196 -11.852402)
		(width 0.1016)
		(layer "In5.Cu")
		(net "PHY_SCC_TO_DPB_14_DN")
	)
	(arc
		(start 102.00005 -51.684174)
		(mid 102.026088 -51.621312)
		(end 102.08895 -51.595274)
		(width 0.0889)
		(layer "In5.Cu")
		(net "PHY_SCC_TO_DPB_14_DN")
	)
	(arc
		(start 102.50297 -51.499008)
		(mid 102.574291 -51.392129)
		(end 102.599236 -51.26609)
		(width 0.0889)
		(layer "In5.Cu")
		(net "PHY_SCC_TO_DPB_14_DN")
	)
	(arc
		(start 102.270052 -51.595274)
		(mid 102.396079 -51.570299)
		(end 102.50297 -51.499008)
		(width 0.0889)
		(layer "In5.Cu")
		(net "PHY_SCC_TO_DPB_14_DN")
	)
	(arc
		(start 89.4207 -11.852402)
		(mid 89.547501 -11.904925)
		(end 89.600024 -12.031726)
		(width 0.1016)
		(layer "In5.Cu")
		(net "PHY_SCC_TO_DPB_14_DN")
	)
	(segment
		(start 101.499924 -52.500022)
		(end 101.000052 -52.00015)
		(width 0.104902)
		(layer "F.Cu")
		(net "PHY_SCC_TO_DPB_13_DP")
	)
	(via
		(at 101.000052 -52.00015)
		(size 0.4572)
		(drill 0.2032)
		(layers "F.Cu" "B.Cu")
		(net "PHY_SCC_TO_DPB_13_DP")
	)
	(segment
		(start 97.575116 -43.245786)
		(end 97.809304 -42.91076)
		(width 0.1016)
		(layer "In5.Cu")
		(net "PHY_SCC_TO_DPB_13_DP")
	)
	(segment
		(start 86.747604 -12.793726)
		(end 86.747604 -10.871454)
		(width 0.1016)
		(layer "In5.Cu")
		(net "PHY_SCC_TO_DPB_13_DP")
	)
	(segment
		(start 86.831424 -13.188696)
		(end 86.747604 -12.793726)
		(width 0.1016)
		(layer "In5.Cu")
		(net "PHY_SCC_TO_DPB_13_DP")
	)
	(segment
		(start 88.03894 -15.047722)
		(end 86.831424 -13.188696)
		(width 0.1016)
		(layer "In5.Cu")
		(net "PHY_SCC_TO_DPB_13_DP")
	)
	(segment
		(start 101.34727 -50.142648)
		(end 101.298756 -49.91481)
		(width 0.1016)
		(layer "In5.Cu")
		(net "PHY_SCC_TO_DPB_13_DP")
	)
	(segment
		(start 97.604326 -45.404532)
		(end 97.534984 -45.011086)
		(width 0.1016)
		(layer "In5.Cu")
		(net "PHY_SCC_TO_DPB_13_DP")
	)
	(segment
		(start 87.271352 -10.347706)
		(end 87.620856 -10.347706)
		(width 0.1016)
		(layer "In5.Cu")
		(net "PHY_SCC_TO_DPB_13_DP")
	)
	(segment
		(start 101.000052 -52.00015)
		(end 101.000052 -52.315872)
		(width 0.0889)
		(layer "In5.Cu")
		(net "PHY_SCC_TO_DPB_13_DP")
	)
	(segment
		(start 99.674426 -47.985426)
		(end 98.60153 -46.331886)
		(width 0.1016)
		(layer "In5.Cu")
		(net "PHY_SCC_TO_DPB_13_DP")
	)
	(segment
		(start 101.34727 -50.546)
		(end 101.34727 -50.523902)
		(width 0.0889)
		(layer "In5.Cu")
		(net "PHY_SCC_TO_DPB_13_DP")
	)
	(segment
		(start 98.08337 -29.332174)
		(end 89.366598 -15.909798)
		(width 0.1016)
		(layer "In5.Cu")
		(net "PHY_SCC_TO_DPB_13_DP")
	)
	(segment
		(start 98.391218 -42.50309)
		(end 98.434398 -42.436796)
		(width 0.1016)
		(layer "In5.Cu")
		(net "PHY_SCC_TO_DPB_13_DP")
	)
	(segment
		(start 101.088952 -52.404772)
		(end 101.24821 -52.404772)
		(width 0.0889)
		(layer "In5.Cu")
		(net "PHY_SCC_TO_DPB_13_DP")
	)
	(segment
		(start 99.19589 -41.264586)
		(end 99.908106 -37.916866)
		(width 0.1016)
		(layer "In5.Cu")
		(net "PHY_SCC_TO_DPB_13_DP")
	)
	(segment
		(start 99.908106 -37.916866)
		(end 98.08337 -29.332174)
		(width 0.1016)
		(layer "In5.Cu")
		(net "PHY_SCC_TO_DPB_13_DP")
	)
	(segment
		(start 101.40442 -50.60315)
		(end 101.34727 -50.546)
		(width 0.0889)
		(layer "In5.Cu")
		(net "PHY_SCC_TO_DPB_13_DP")
	)
	(segment
		(start 101.40442 -52.248562)
		(end 101.40442 -50.60315)
		(width 0.0889)
		(layer "In5.Cu")
		(net "PHY_SCC_TO_DPB_13_DP")
	)
	(segment
		(start 100.73386 -49.04486)
		(end 99.674426 -47.985426)
		(width 0.1016)
		(layer "In5.Cu")
		(net "PHY_SCC_TO_DPB_13_DP")
	)
	(segment
		(start 101.298756 -49.91481)
		(end 100.73386 -49.04486)
		(width 0.1016)
		(layer "In5.Cu")
		(net "PHY_SCC_TO_DPB_13_DP")
	)
	(segment
		(start 101.34727 -50.523902)
		(end 101.34727 -50.142648)
		(width 0.1016)
		(layer "In5.Cu")
		(net "PHY_SCC_TO_DPB_13_DP")
	)
	(segment
		(start 97.534984 -43.47337)
		(end 97.575116 -43.245786)
		(width 0.1016)
		(layer "In5.Cu")
		(net "PHY_SCC_TO_DPB_13_DP")
	)
	(segment
		(start 87.80018 -10.168382)
		(end 87.80018 -9.800082)
		(width 0.1016)
		(layer "In5.Cu")
		(net "PHY_SCC_TO_DPB_13_DP")
	)
	(segment
		(start 97.809304 -42.91076)
		(end 98.391218 -42.50309)
		(width 0.1016)
		(layer "In5.Cu")
		(net "PHY_SCC_TO_DPB_13_DP")
	)
	(segment
		(start 97.534984 -45.011086)
		(end 97.534984 -43.47337)
		(width 0.1016)
		(layer "In5.Cu")
		(net "PHY_SCC_TO_DPB_13_DP")
	)
	(segment
		(start 98.60153 -46.331886)
		(end 97.93986 -45.868336)
		(width 0.1016)
		(layer "In5.Cu")
		(net "PHY_SCC_TO_DPB_13_DP")
	)
	(segment
		(start 97.93986 -45.868336)
		(end 97.84842 -45.753528)
		(width 0.1016)
		(layer "In5.Cu")
		(net "PHY_SCC_TO_DPB_13_DP")
	)
	(segment
		(start 89.366598 -15.909798)
		(end 88.03894 -15.047722)
		(width 0.1016)
		(layer "In5.Cu")
		(net "PHY_SCC_TO_DPB_13_DP")
	)
	(segment
		(start 98.434398 -42.436796)
		(end 99.19589 -41.264586)
		(width 0.1016)
		(layer "In5.Cu")
		(net "PHY_SCC_TO_DPB_13_DP")
	)
	(segment
		(start 97.84842 -45.753528)
		(end 97.604326 -45.404532)
		(width 0.1016)
		(layer "In5.Cu")
		(net "PHY_SCC_TO_DPB_13_DP")
	)
	(arc
		(start 87.620856 -10.347706)
		(mid 87.747657 -10.295183)
		(end 87.80018 -10.168382)
		(width 0.1016)
		(layer "In5.Cu")
		(net "PHY_SCC_TO_DPB_13_DP")
	)
	(arc
		(start 101.3587 -52.359052)
		(mid 101.392519 -52.308345)
		(end 101.40442 -52.248562)
		(width 0.0889)
		(layer "In5.Cu")
		(net "PHY_SCC_TO_DPB_13_DP")
	)
	(arc
		(start 101.000052 -52.315872)
		(mid 101.02609 -52.378734)
		(end 101.088952 -52.404772)
		(width 0.0889)
		(layer "In5.Cu")
		(net "PHY_SCC_TO_DPB_13_DP")
	)
	(arc
		(start 101.24821 -52.404772)
		(mid 101.308003 -52.392896)
		(end 101.3587 -52.359052)
		(width 0.0889)
		(layer "In5.Cu")
		(net "PHY_SCC_TO_DPB_13_DP")
	)
	(arc
		(start 86.747604 -10.871454)
		(mid 86.901006 -10.501108)
		(end 87.271352 -10.347706)
		(width 0.1016)
		(layer "In5.Cu")
		(net "PHY_SCC_TO_DPB_13_DP")
	)
	(segment
		(start 101.499924 -53.50002)
		(end 101.000052 -53.000148)
		(width 0.104902)
		(layer "F.Cu")
		(net "PHY_SCC_TO_DPB_13_DN")
	)
	(via
		(at 101.000052 -53.000148)
		(size 0.4572)
		(drill 0.2032)
		(layers "F.Cu" "B.Cu")
		(net "PHY_SCC_TO_DPB_13_DN")
	)
	(segment
		(start 88.259412 -14.82725)
		(end 87.117936 -13.070078)
		(width 0.1016)
		(layer "In5.Cu")
		(net "PHY_SCC_TO_DPB_13_DN")
	)
	(segment
		(start 101.65207 -50.546)
		(end 101.65207 -50.523902)
		(width 0.0889)
		(layer "In5.Cu")
		(net "PHY_SCC_TO_DPB_13_DN")
	)
	(segment
		(start 87.117936 -13.070078)
		(end 87.052404 -12.761468)
		(width 0.1016)
		(layer "In5.Cu")
		(net "PHY_SCC_TO_DPB_13_DN")
	)
	(segment
		(start 89.58707 -15.689326)
		(end 88.259412 -14.82725)
		(width 0.1016)
		(layer "In5.Cu")
		(net "PHY_SCC_TO_DPB_13_DN")
	)
	(segment
		(start 99.482402 -41.383458)
		(end 100.219764 -37.916866)
		(width 0.1016)
		(layer "In5.Cu")
		(net "PHY_SCC_TO_DPB_13_DN")
	)
	(segment
		(start 87.271352 -10.652506)
		(end 87.620856 -10.652506)
		(width 0.1016)
		(layer "In5.Cu")
		(net "PHY_SCC_TO_DPB_13_DN")
	)
	(segment
		(start 98.369882 -29.213556)
		(end 89.58707 -15.689326)
		(width 0.1016)
		(layer "In5.Cu")
		(net "PHY_SCC_TO_DPB_13_DN")
	)
	(segment
		(start 101.000052 -53.000148)
		(end 101.000052 -52.684172)
		(width 0.0889)
		(layer "In5.Cu")
		(net "PHY_SCC_TO_DPB_13_DN")
	)
	(segment
		(start 101.088952 -52.595272)
		(end 101.24821 -52.595272)
		(width 0.0889)
		(layer "In5.Cu")
		(net "PHY_SCC_TO_DPB_13_DN")
	)
	(segment
		(start 99.37369 -46.961552)
		(end 98.825558 -46.11624)
		(width 0.1016)
		(layer "In5.Cu")
		(net "PHY_SCC_TO_DPB_13_DN")
	)
	(segment
		(start 101.65207 -50.523902)
		(end 101.65207 -50.11039)
		(width 0.1016)
		(layer "In5.Cu")
		(net "PHY_SCC_TO_DPB_13_DN")
	)
	(segment
		(start 101.65207 -50.11039)
		(end 101.585268 -49.795938)
		(width 0.1016)
		(layer "In5.Cu")
		(net "PHY_SCC_TO_DPB_13_DN")
	)
	(segment
		(start 99.74707 -47.536608)
		(end 99.803204 -47.27321)
		(width 0.1016)
		(layer "In5.Cu")
		(net "PHY_SCC_TO_DPB_13_DN")
	)
	(segment
		(start 87.80018 -10.83183)
		(end 87.80018 -11.20013)
		(width 0.1016)
		(layer "In5.Cu")
		(net "PHY_SCC_TO_DPB_13_DN")
	)
	(segment
		(start 97.89287 -45.285152)
		(end 97.839784 -44.984162)
		(width 0.1016)
		(layer "In5.Cu")
		(net "PHY_SCC_TO_DPB_13_DN")
	)
	(segment
		(start 97.839784 -44.984162)
		(end 97.839784 -43.500294)
		(width 0.1016)
		(layer "In5.Cu")
		(net "PHY_SCC_TO_DPB_13_DN")
	)
	(segment
		(start 99.803204 -47.27321)
		(end 99.637088 -47.017432)
		(width 0.1016)
		(layer "In5.Cu")
		(net "PHY_SCC_TO_DPB_13_DN")
	)
	(segment
		(start 100.219764 -37.916866)
		(end 98.369882 -29.213556)
		(width 0.1016)
		(layer "In5.Cu")
		(net "PHY_SCC_TO_DPB_13_DN")
	)
	(segment
		(start 97.839784 -43.500294)
		(end 97.86366 -43.36542)
		(width 0.1016)
		(layer "In5.Cu")
		(net "PHY_SCC_TO_DPB_13_DN")
	)
	(segment
		(start 101.59492 -50.60315)
		(end 101.65207 -50.546)
		(width 0.0889)
		(layer "In5.Cu")
		(net "PHY_SCC_TO_DPB_13_DN")
	)
	(segment
		(start 99.912932 -47.792386)
		(end 99.74707 -47.536608)
		(width 0.1016)
		(layer "In5.Cu")
		(net "PHY_SCC_TO_DPB_13_DN")
	)
	(segment
		(start 100.972366 -48.85182)
		(end 99.912932 -47.792386)
		(width 0.1016)
		(layer "In5.Cu")
		(net "PHY_SCC_TO_DPB_13_DN")
	)
	(segment
		(start 101.59492 -52.248562)
		(end 101.59492 -50.60315)
		(width 0.0889)
		(layer "In5.Cu")
		(net "PHY_SCC_TO_DPB_13_DN")
	)
	(segment
		(start 87.052404 -12.761468)
		(end 87.052404 -10.871454)
		(width 0.1016)
		(layer "In5.Cu")
		(net "PHY_SCC_TO_DPB_13_DN")
	)
	(segment
		(start 98.614738 -42.71899)
		(end 99.482402 -41.383458)
		(width 0.1016)
		(layer "In5.Cu")
		(net "PHY_SCC_TO_DPB_13_DN")
	)
	(segment
		(start 98.093022 -45.570902)
		(end 97.89287 -45.285152)
		(width 0.1016)
		(layer "In5.Cu")
		(net "PHY_SCC_TO_DPB_13_DN")
	)
	(segment
		(start 97.86366 -43.36542)
		(end 98.028506 -43.129708)
		(width 0.1016)
		(layer "In5.Cu")
		(net "PHY_SCC_TO_DPB_13_DN")
	)
	(segment
		(start 98.028506 -43.129708)
		(end 98.614738 -42.71899)
		(width 0.1016)
		(layer "In5.Cu")
		(net "PHY_SCC_TO_DPB_13_DN")
	)
	(segment
		(start 98.825558 -46.11624)
		(end 98.150934 -45.644054)
		(width 0.1016)
		(layer "In5.Cu")
		(net "PHY_SCC_TO_DPB_13_DN")
	)
	(segment
		(start 99.637088 -47.017432)
		(end 99.37369 -46.961552)
		(width 0.1016)
		(layer "In5.Cu")
		(net "PHY_SCC_TO_DPB_13_DN")
	)
	(segment
		(start 98.150934 -45.644054)
		(end 98.093022 -45.570902)
		(width 0.1016)
		(layer "In5.Cu")
		(net "PHY_SCC_TO_DPB_13_DN")
	)
	(segment
		(start 101.585268 -49.795938)
		(end 100.972366 -48.85182)
		(width 0.1016)
		(layer "In5.Cu")
		(net "PHY_SCC_TO_DPB_13_DN")
	)
	(arc
		(start 101.493574 -52.493926)
		(mid 101.568657 -52.381323)
		(end 101.59492 -52.248562)
		(width 0.0889)
		(layer "In5.Cu")
		(net "PHY_SCC_TO_DPB_13_DN")
	)
	(arc
		(start 101.000052 -52.684172)
		(mid 101.02609 -52.62131)
		(end 101.088952 -52.595272)
		(width 0.0889)
		(layer "In5.Cu")
		(net "PHY_SCC_TO_DPB_13_DN")
	)
	(arc
		(start 87.620856 -10.652506)
		(mid 87.747657 -10.705029)
		(end 87.80018 -10.83183)
		(width 0.1016)
		(layer "In5.Cu")
		(net "PHY_SCC_TO_DPB_13_DN")
	)
	(arc
		(start 101.24821 -52.595272)
		(mid 101.380958 -52.568978)
		(end 101.493574 -52.493926)
		(width 0.0889)
		(layer "In5.Cu")
		(net "PHY_SCC_TO_DPB_13_DN")
	)
	(arc
		(start 87.052404 -10.871454)
		(mid 87.116532 -10.716634)
		(end 87.271352 -10.652506)
		(width 0.1016)
		(layer "In5.Cu")
		(net "PHY_SCC_TO_DPB_13_DN")
	)
	(segment
		(start 100.499926 -51.500024)
		(end 100.000054 -51.000152)
		(width 0.104902)
		(layer "F.Cu")
		(net "PHY_SCC_TO_DPB_12_DP")
	)
	(via
		(at 100.000054 -51.000152)
		(size 0.4572)
		(drill 0.2032)
		(layers "F.Cu" "B.Cu")
		(net "PHY_SCC_TO_DPB_12_DP")
	)
	(segment
		(start 96.217232 -42.957242)
		(end 96.063054 -43.17746)
		(width 0.1016)
		(layer "In5.Cu")
		(net "PHY_SCC_TO_DPB_12_DP")
	)
	(segment
		(start 100.278946 -51.404774)
		(end 100.088954 -51.404774)
		(width 0.0889)
		(layer "In5.Cu")
		(net "PHY_SCC_TO_DPB_12_DP")
	)
	(segment
		(start 96.063054 -43.17746)
		(end 96.010984 -43.473624)
		(width 0.1016)
		(layer "In5.Cu")
		(net "PHY_SCC_TO_DPB_12_DP")
	)
	(segment
		(start 99.016566 -38.37813)
		(end 98.464878 -40.969438)
		(width 0.1016)
		(layer "In5.Cu")
		(net "PHY_SCC_TO_DPB_12_DP")
	)
	(segment
		(start 100.407216 -50.71364)
		(end 100.407216 -51.249072)
		(width 0.0889)
		(layer "In5.Cu")
		(net "PHY_SCC_TO_DPB_12_DP")
	)
	(segment
		(start 86.000082 -10.999978)
		(end 86.000082 -11.368278)
		(width 0.1016)
		(layer "In5.Cu")
		(net "PHY_SCC_TO_DPB_12_DP")
	)
	(segment
		(start 96.010984 -45.011086)
		(end 96.080326 -45.404532)
		(width 0.1016)
		(layer "In5.Cu")
		(net "PHY_SCC_TO_DPB_12_DP")
	)
	(segment
		(start 96.701356 -46.037754)
		(end 97.887282 -48.204628)
		(width 0.1016)
		(layer "In5.Cu")
		(net "PHY_SCC_TO_DPB_12_DP")
	)
	(segment
		(start 96.010984 -43.473624)
		(end 96.010984 -45.011086)
		(width 0.1016)
		(layer "In5.Cu")
		(net "PHY_SCC_TO_DPB_12_DP")
	)
	(segment
		(start 100.000054 -51.315874)
		(end 100.000054 -51.000152)
		(width 0.0889)
		(layer "In5.Cu")
		(net "PHY_SCC_TO_DPB_12_DP")
	)
	(segment
		(start 97.970594 -41.730422)
		(end 97.970086 -41.730422)
		(width 0.1016)
		(layer "In5.Cu")
		(net "PHY_SCC_TO_DPB_12_DP")
	)
	(segment
		(start 96.080326 -45.404532)
		(end 96.352106 -45.793152)
		(width 0.1016)
		(layer "In5.Cu")
		(net "PHY_SCC_TO_DPB_12_DP")
	)
	(segment
		(start 100.315268 -50.157634)
		(end 100.350066 -50.320702)
		(width 0.1016)
		(layer "In5.Cu")
		(net "PHY_SCC_TO_DPB_12_DP")
	)
	(segment
		(start 99.892866 -49.506378)
		(end 100.315268 -50.157634)
		(width 0.1016)
		(layer "In5.Cu")
		(net "PHY_SCC_TO_DPB_12_DP")
	)
	(segment
		(start 97.970086 -41.730422)
		(end 96.217232 -42.957242)
		(width 0.1016)
		(layer "In5.Cu")
		(net "PHY_SCC_TO_DPB_12_DP")
	)
	(segment
		(start 84.9122 -12.106656)
		(end 84.9122 -13.020802)
		(width 0.1016)
		(layer "In5.Cu")
		(net "PHY_SCC_TO_DPB_12_DP")
	)
	(segment
		(start 96.352106 -45.793152)
		(end 96.701356 -46.037754)
		(width 0.1016)
		(layer "In5.Cu")
		(net "PHY_SCC_TO_DPB_12_DP")
	)
	(segment
		(start 88.735916 -16.90243)
		(end 97.23247 -29.98597)
		(width 0.1016)
		(layer "In5.Cu")
		(net "PHY_SCC_TO_DPB_12_DP")
	)
	(segment
		(start 84.9122 -13.020802)
		(end 85.113622 -13.96873)
		(width 0.1016)
		(layer "In5.Cu")
		(net "PHY_SCC_TO_DPB_12_DP")
	)
	(segment
		(start 100.350066 -50.634392)
		(end 100.350066 -50.65649)
		(width 0.0889)
		(layer "In5.Cu")
		(net "PHY_SCC_TO_DPB_12_DP")
	)
	(segment
		(start 97.23247 -29.98597)
		(end 99.016566 -38.37813)
		(width 0.1016)
		(layer "In5.Cu")
		(net "PHY_SCC_TO_DPB_12_DP")
	)
	(segment
		(start 97.887282 -48.204628)
		(end 99.892866 -49.506378)
		(width 0.1016)
		(layer "In5.Cu")
		(net "PHY_SCC_TO_DPB_12_DP")
	)
	(segment
		(start 85.820758 -11.547602)
		(end 85.471254 -11.547602)
		(width 0.1016)
		(layer "In5.Cu")
		(net "PHY_SCC_TO_DPB_12_DP")
	)
	(segment
		(start 100.350066 -50.65649)
		(end 100.407216 -50.71364)
		(width 0.0889)
		(layer "In5.Cu")
		(net "PHY_SCC_TO_DPB_12_DP")
	)
	(segment
		(start 85.766656 -14.974316)
		(end 88.735916 -16.90243)
		(width 0.1016)
		(layer "In5.Cu")
		(net "PHY_SCC_TO_DPB_12_DP")
	)
	(segment
		(start 100.361496 -51.359054)
		(end 100.342192 -51.378612)
		(width 0.0889)
		(layer "In5.Cu")
		(net "PHY_SCC_TO_DPB_12_DP")
	)
	(segment
		(start 85.113622 -13.96873)
		(end 85.766656 -14.974316)
		(width 0.1016)
		(layer "In5.Cu")
		(net "PHY_SCC_TO_DPB_12_DP")
	)
	(segment
		(start 100.350066 -50.320702)
		(end 100.350066 -50.634392)
		(width 0.1016)
		(layer "In5.Cu")
		(net "PHY_SCC_TO_DPB_12_DP")
	)
	(segment
		(start 98.464878 -40.969438)
		(end 97.970594 -41.730422)
		(width 0.1016)
		(layer "In5.Cu")
		(net "PHY_SCC_TO_DPB_12_DP")
	)
	(arc
		(start 100.088954 -51.404774)
		(mid 100.026092 -51.378736)
		(end 100.000054 -51.315874)
		(width 0.0889)
		(layer "In5.Cu")
		(net "PHY_SCC_TO_DPB_12_DP")
	)
	(arc
		(start 100.342192 -51.378612)
		(mid 100.313188 -51.398025)
		(end 100.278946 -51.404774)
		(width 0.0889)
		(layer "In5.Cu")
		(net "PHY_SCC_TO_DPB_12_DP")
	)
	(arc
		(start 86.000082 -11.368278)
		(mid 85.947559 -11.495079)
		(end 85.820758 -11.547602)
		(width 0.1016)
		(layer "In5.Cu")
		(net "PHY_SCC_TO_DPB_12_DP")
	)
	(arc
		(start 100.407216 -51.249072)
		(mid 100.395281 -51.308603)
		(end 100.361496 -51.359054)
		(width 0.0889)
		(layer "In5.Cu")
		(net "PHY_SCC_TO_DPB_12_DP")
	)
	(arc
		(start 85.471254 -11.547602)
		(mid 85.075943 -11.711345)
		(end 84.9122 -12.106656)
		(width 0.1016)
		(layer "In5.Cu")
		(net "PHY_SCC_TO_DPB_12_DP")
	)
	(segment
		(start 100.499926 -52.500022)
		(end 100.000054 -52.00015)
		(width 0.104902)
		(layer "F.Cu")
		(net "PHY_SCC_TO_DPB_12_DN")
	)
	(via
		(at 100.000054 -52.00015)
		(size 0.4572)
		(drill 0.2032)
		(layers "F.Cu" "B.Cu")
		(net "PHY_SCC_TO_DPB_12_DN")
	)
	(segment
		(start 96.43618 -43.176444)
		(end 96.351598 -43.297094)
		(width 0.1016)
		(layer "In5.Cu")
		(net "PHY_SCC_TO_DPB_12_DN")
	)
	(segment
		(start 96.315784 -44.984162)
		(end 96.36887 -45.285152)
		(width 0.1016)
		(layer "In5.Cu")
		(net "PHY_SCC_TO_DPB_12_DN")
	)
	(segment
		(start 99.05238 -48.597312)
		(end 99.315778 -48.541178)
		(width 0.1016)
		(layer "In5.Cu")
		(net "PHY_SCC_TO_DPB_12_DN")
	)
	(segment
		(start 100.113338 -49.285906)
		(end 100.60178 -50.039016)
		(width 0.1016)
		(layer "In5.Cu")
		(net "PHY_SCC_TO_DPB_12_DN")
	)
	(segment
		(start 99.62769 -48.970692)
		(end 100.113338 -49.285906)
		(width 0.1016)
		(layer "In5.Cu")
		(net "PHY_SCC_TO_DPB_12_DN")
	)
	(segment
		(start 85.400134 -13.850112)
		(end 85.987128 -14.753844)
		(width 0.1016)
		(layer "In5.Cu")
		(net "PHY_SCC_TO_DPB_12_DN")
	)
	(segment
		(start 99.315778 -48.541178)
		(end 99.571556 -48.70704)
		(width 0.1016)
		(layer "In5.Cu")
		(net "PHY_SCC_TO_DPB_12_DN")
	)
	(segment
		(start 100.654866 -50.288444)
		(end 100.654866 -50.634392)
		(width 0.1016)
		(layer "In5.Cu")
		(net "PHY_SCC_TO_DPB_12_DN")
	)
	(segment
		(start 100.597716 -50.71364)
		(end 100.597716 -51.249326)
		(width 0.0889)
		(layer "In5.Cu")
		(net "PHY_SCC_TO_DPB_12_DN")
	)
	(segment
		(start 85.217 -12.988544)
		(end 85.400134 -13.850112)
		(width 0.1016)
		(layer "In5.Cu")
		(net "PHY_SCC_TO_DPB_12_DN")
	)
	(segment
		(start 100.496878 -51.49342)
		(end 100.477574 -51.512724)
		(width 0.0889)
		(layer "In5.Cu")
		(net "PHY_SCC_TO_DPB_12_DN")
	)
	(segment
		(start 96.315784 -43.500294)
		(end 96.315784 -44.984162)
		(width 0.1016)
		(layer "In5.Cu")
		(net "PHY_SCC_TO_DPB_12_DN")
	)
	(segment
		(start 100.000054 -51.684174)
		(end 100.000054 -52.00015)
		(width 0.0889)
		(layer "In5.Cu")
		(net "PHY_SCC_TO_DPB_12_DN")
	)
	(segment
		(start 85.820758 -11.852402)
		(end 85.471254 -11.852402)
		(width 0.1016)
		(layer "In5.Cu")
		(net "PHY_SCC_TO_DPB_12_DN")
	)
	(segment
		(start 99.571556 -48.70704)
		(end 99.62769 -48.970692)
		(width 0.1016)
		(layer "In5.Cu")
		(net "PHY_SCC_TO_DPB_12_DN")
	)
	(segment
		(start 86.000082 -12.400026)
		(end 86.000082 -12.031726)
		(width 0.1016)
		(layer "In5.Cu")
		(net "PHY_SCC_TO_DPB_12_DN")
	)
	(segment
		(start 99.328224 -38.37813)
		(end 98.75139 -41.08831)
		(width 0.1016)
		(layer "In5.Cu")
		(net "PHY_SCC_TO_DPB_12_DN")
	)
	(segment
		(start 96.36887 -45.285152)
		(end 96.571308 -45.574204)
		(width 0.1016)
		(layer "In5.Cu")
		(net "PHY_SCC_TO_DPB_12_DN")
	)
	(segment
		(start 98.75139 -41.08831)
		(end 98.194622 -41.94556)
		(width 0.1016)
		(layer "In5.Cu")
		(net "PHY_SCC_TO_DPB_12_DN")
	)
	(segment
		(start 85.987128 -14.753844)
		(end 88.956388 -16.681958)
		(width 0.1016)
		(layer "In5.Cu")
		(net "PHY_SCC_TO_DPB_12_DN")
	)
	(segment
		(start 97.518982 -29.867352)
		(end 99.328224 -38.37813)
		(width 0.1016)
		(layer "In5.Cu")
		(net "PHY_SCC_TO_DPB_12_DN")
	)
	(segment
		(start 100.654866 -50.634392)
		(end 100.654866 -50.65649)
		(width 0.0889)
		(layer "In5.Cu")
		(net "PHY_SCC_TO_DPB_12_DN")
	)
	(segment
		(start 100.60178 -50.039016)
		(end 100.654866 -50.288444)
		(width 0.1016)
		(layer "In5.Cu")
		(net "PHY_SCC_TO_DPB_12_DN")
	)
	(segment
		(start 88.956388 -16.681958)
		(end 97.518982 -29.867352)
		(width 0.1016)
		(layer "In5.Cu")
		(net "PHY_SCC_TO_DPB_12_DN")
	)
	(segment
		(start 100.278692 -51.595274)
		(end 100.088954 -51.595274)
		(width 0.0889)
		(layer "In5.Cu")
		(net "PHY_SCC_TO_DPB_12_DN")
	)
	(segment
		(start 85.217 -12.106656)
		(end 85.217 -12.988544)
		(width 0.1016)
		(layer "In5.Cu")
		(net "PHY_SCC_TO_DPB_12_DN")
	)
	(segment
		(start 96.935036 -45.82922)
		(end 98.117914 -47.99076)
		(width 0.1016)
		(layer "In5.Cu")
		(net "PHY_SCC_TO_DPB_12_DN")
	)
	(segment
		(start 98.194368 -41.94556)
		(end 96.43618 -43.176444)
		(width 0.1016)
		(layer "In5.Cu")
		(net "PHY_SCC_TO_DPB_12_DN")
	)
	(segment
		(start 96.351598 -43.297094)
		(end 96.315784 -43.500294)
		(width 0.1016)
		(layer "In5.Cu")
		(net "PHY_SCC_TO_DPB_12_DN")
	)
	(segment
		(start 98.117914 -47.99076)
		(end 99.05238 -48.597312)
		(width 0.1016)
		(layer "In5.Cu")
		(net "PHY_SCC_TO_DPB_12_DN")
	)
	(segment
		(start 100.654866 -50.65649)
		(end 100.597716 -50.71364)
		(width 0.0889)
		(layer "In5.Cu")
		(net "PHY_SCC_TO_DPB_12_DN")
	)
	(segment
		(start 98.194622 -41.94556)
		(end 98.194368 -41.94556)
		(width 0.1016)
		(layer "In5.Cu")
		(net "PHY_SCC_TO_DPB_12_DN")
	)
	(segment
		(start 96.571308 -45.574204)
		(end 96.935036 -45.82922)
		(width 0.1016)
		(layer "In5.Cu")
		(net "PHY_SCC_TO_DPB_12_DN")
	)
	(arc
		(start 100.597716 -51.249326)
		(mid 100.571452 -51.381343)
		(end 100.496878 -51.49342)
		(width 0.0889)
		(layer "In5.Cu")
		(net "PHY_SCC_TO_DPB_12_DN")
	)
	(arc
		(start 100.088954 -51.595274)
		(mid 100.026092 -51.621312)
		(end 100.000054 -51.684174)
		(width 0.0889)
		(layer "In5.Cu")
		(net "PHY_SCC_TO_DPB_12_DN")
	)
	(arc
		(start 86.000082 -12.031726)
		(mid 85.947559 -11.904925)
		(end 85.820758 -11.852402)
		(width 0.1016)
		(layer "In5.Cu")
		(net "PHY_SCC_TO_DPB_12_DN")
	)
	(arc
		(start 85.471254 -11.852402)
		(mid 85.291469 -11.926871)
		(end 85.217 -12.106656)
		(width 0.1016)
		(layer "In5.Cu")
		(net "PHY_SCC_TO_DPB_12_DN")
	)
	(arc
		(start 100.477574 -51.512724)
		(mid 100.386411 -51.573959)
		(end 100.278692 -51.595274)
		(width 0.0889)
		(layer "In5.Cu")
		(net "PHY_SCC_TO_DPB_12_DN")
	)
	(segment
		(start 139.260834 -78.302612)
		(end 139.260834 -77.970126)
		(width 0.12446)
		(layer "F.Cu")
		(net "PHY_EXP_TO_CONN_9_DP")
	)
	(segment
		(start 136.610598 -77.272134)
		(end 136.460992 -77.272134)
		(width 0.12446)
		(layer "F.Cu")
		(net "PHY_EXP_TO_CONN_9_DP")
	)
	(segment
		(start 139.629134 -78.427834)
		(end 139.38631 -78.427834)
		(width 0.12446)
		(layer "F.Cu")
		(net "PHY_EXP_TO_CONN_9_DP")
	)
	(segment
		(start 138.643106 -77.352398)
		(end 136.690862 -77.352398)
		(width 0.12446)
		(layer "F.Cu")
		(net "PHY_EXP_TO_CONN_9_DP")
	)
	(segment
		(start 136.690862 -77.352398)
		(end 136.610598 -77.272134)
		(width 0.12446)
		(layer "F.Cu")
		(net "PHY_EXP_TO_CONN_9_DP")
	)
	(arc
		(start 139.29741 -78.391004)
		(mid 139.270366 -78.350435)
		(end 139.260834 -78.302612)
		(width 0.12446)
		(layer "F.Cu")
		(net "PHY_EXP_TO_CONN_9_DP")
	)
	(arc
		(start 139.260834 -77.970126)
		(mid 139.079906 -77.533326)
		(end 138.643106 -77.352398)
		(width 0.12446)
		(layer "F.Cu")
		(net "PHY_EXP_TO_CONN_9_DP")
	)
	(arc
		(start 139.38631 -78.427834)
		(mid 139.338195 -78.418263)
		(end 139.29741 -78.391004)
		(width 0.12446)
		(layer "F.Cu")
		(net "PHY_EXP_TO_CONN_9_DP")
	)
	(segment
		(start 103.030782 -107.726734)
		(end 103.107236 -107.767628)
		(width 0.1016)
		(layer "In5.Cu")
		(net "PHY_EXP_TO_CONN_9_DP")
	)
	(segment
		(start 103.513128 -105.944162)
		(end 102.937818 -106.317288)
		(width 0.1016)
		(layer "In5.Cu")
		(net "PHY_EXP_TO_CONN_9_DP")
	)
	(segment
		(start 140.523214 -98.845116)
		(end 136.256014 -101.616002)
		(width 0.1016)
		(layer "In5.Cu")
		(net "PHY_EXP_TO_CONN_9_DP")
	)
	(segment
		(start 120.241314 -105.02011)
		(end 116.294916 -104.181148)
		(width 0.1016)
		(layer "In5.Cu")
		(net "PHY_EXP_TO_CONN_9_DP")
	)
	(segment
		(start 141.586204 -79.133446)
		(end 142.780766 -79.909162)
		(width 0.1016)
		(layer "In5.Cu")
		(net "PHY_EXP_TO_CONN_9_DP")
	)
	(segment
		(start 116.294916 -104.181148)
		(end 108.722414 -105.791)
		(width 0.1016)
		(layer "In5.Cu")
		(net "PHY_EXP_TO_CONN_9_DP")
	)
	(segment
		(start 103.244904 -107.725972)
		(end 103.49992 -107.249976)
		(width 0.1016)
		(layer "In5.Cu")
		(net "PHY_EXP_TO_CONN_9_DP")
	)
	(segment
		(start 108.722414 -105.791)
		(end 104.232456 -105.791)
		(width 0.1016)
		(layer "In5.Cu")
		(net "PHY_EXP_TO_CONN_9_DP")
	)
	(segment
		(start 145.278856 -86.335108)
		(end 143.640048 -94.045278)
		(width 0.1016)
		(layer "In5.Cu")
		(net "PHY_EXP_TO_CONN_9_DP")
	)
	(segment
		(start 144.464278 -82.501486)
		(end 145.278856 -86.335108)
		(width 0.1016)
		(layer "In5.Cu")
		(net "PHY_EXP_TO_CONN_9_DP")
	)
	(segment
		(start 102.937818 -106.317288)
		(end 102.73792 -106.998008)
		(width 0.1016)
		(layer "In5.Cu")
		(net "PHY_EXP_TO_CONN_9_DP")
	)
	(segment
		(start 139.284202 -78.457806)
		(end 139.262104 -78.479904)
		(width 0.1016)
		(layer "In5.Cu")
		(net "PHY_EXP_TO_CONN_9_DP")
	)
	(segment
		(start 143.640048 -94.045278)
		(end 140.523214 -98.845116)
		(width 0.1016)
		(layer "In5.Cu")
		(net "PHY_EXP_TO_CONN_9_DP")
	)
	(segment
		(start 139.210034 -78.605126)
		(end 139.210034 -78.784704)
		(width 0.1016)
		(layer "In5.Cu")
		(net "PHY_EXP_TO_CONN_9_DP")
	)
	(segment
		(start 102.88524 -107.587288)
		(end 103.006906 -107.708954)
		(width 0.1016)
		(layer "In5.Cu")
		(net "PHY_EXP_TO_CONN_9_DP")
	)
	(segment
		(start 139.558776 -79.133446)
		(end 141.586204 -79.133446)
		(width 0.1016)
		(layer "In5.Cu")
		(net "PHY_EXP_TO_CONN_9_DP")
	)
	(segment
		(start 136.256014 -101.616002)
		(end 120.241314 -105.02011)
		(width 0.1016)
		(layer "In5.Cu")
		(net "PHY_EXP_TO_CONN_9_DP")
	)
	(segment
		(start 104.232456 -105.791)
		(end 103.513128 -105.944162)
		(width 0.1016)
		(layer "In5.Cu")
		(net "PHY_EXP_TO_CONN_9_DP")
	)
	(segment
		(start 102.73792 -106.998008)
		(end 102.73792 -107.231688)
		(width 0.1016)
		(layer "In5.Cu")
		(net "PHY_EXP_TO_CONN_9_DP")
	)
	(segment
		(start 139.629134 -78.427834)
		(end 139.356084 -78.427834)
		(width 0.1016)
		(layer "In5.Cu")
		(net "PHY_EXP_TO_CONN_9_DP")
	)
	(segment
		(start 142.780766 -79.909162)
		(end 144.464278 -82.501486)
		(width 0.1016)
		(layer "In5.Cu")
		(net "PHY_EXP_TO_CONN_9_DP")
	)
	(arc
		(start 102.73792 -107.231688)
		(mid 102.776203 -107.424147)
		(end 102.88524 -107.587288)
		(width 0.1016)
		(layer "In5.Cu")
		(net "PHY_EXP_TO_CONN_9_DP")
	)
	(arc
		(start 139.210034 -78.784704)
		(mid 139.312178 -79.031302)
		(end 139.558776 -79.133446)
		(width 0.1016)
		(layer "In5.Cu")
		(net "PHY_EXP_TO_CONN_9_DP")
	)
	(arc
		(start 139.262104 -78.479904)
		(mid 139.223633 -78.537341)
		(end 139.210034 -78.605126)
		(width 0.1016)
		(layer "In5.Cu")
		(net "PHY_EXP_TO_CONN_9_DP")
	)
	(arc
		(start 139.356084 -78.427834)
		(mid 139.317174 -78.435685)
		(end 139.284202 -78.457806)
		(width 0.1016)
		(layer "In5.Cu")
		(net "PHY_EXP_TO_CONN_9_DP")
	)
	(arc
		(start 103.006906 -107.708954)
		(mid 103.01819 -107.718723)
		(end 103.030782 -107.726734)
		(width 0.1016)
		(layer "In5.Cu")
		(net "PHY_EXP_TO_CONN_9_DP")
	)
	(arc
		(start 103.107236 -107.767628)
		(mid 103.184682 -107.775337)
		(end 103.244904 -107.725972)
		(width 0.1016)
		(layer "In5.Cu")
		(net "PHY_EXP_TO_CONN_9_DP")
	)
	(segment
		(start 138.81735 -78.39075)
		(end 138.817096 -78.391004)
		(width 0.12446)
		(layer "F.Cu")
		(net "PHY_EXP_TO_CONN_9_DN")
	)
	(segment
		(start 136.657334 -77.758798)
		(end 138.643106 -77.758798)
		(width 0.12446)
		(layer "F.Cu")
		(net "PHY_EXP_TO_CONN_9_DN")
	)
	(segment
		(start 138.728704 -78.427834)
		(end 138.486134 -78.427834)
		(width 0.12446)
		(layer "F.Cu")
		(net "PHY_EXP_TO_CONN_9_DN")
	)
	(segment
		(start 136.460992 -77.830934)
		(end 136.585198 -77.830934)
		(width 0.12446)
		(layer "F.Cu")
		(net "PHY_EXP_TO_CONN_9_DN")
	)
	(segment
		(start 138.854434 -77.970126)
		(end 138.854434 -78.301596)
		(width 0.12446)
		(layer "F.Cu")
		(net "PHY_EXP_TO_CONN_9_DN")
	)
	(segment
		(start 136.585198 -77.830934)
		(end 136.657334 -77.758798)
		(width 0.12446)
		(layer "F.Cu")
		(net "PHY_EXP_TO_CONN_9_DN")
	)
	(arc
		(start 138.817096 -78.391004)
		(mid 138.776584 -78.418264)
		(end 138.728704 -78.427834)
		(width 0.12446)
		(layer "F.Cu")
		(net "PHY_EXP_TO_CONN_9_DN")
	)
	(arc
		(start 138.643106 -77.758798)
		(mid 138.792537 -77.820695)
		(end 138.854434 -77.970126)
		(width 0.12446)
		(layer "F.Cu")
		(net "PHY_EXP_TO_CONN_9_DN")
	)
	(arc
		(start 138.854434 -78.301596)
		(mid 138.844742 -78.349852)
		(end 138.81735 -78.39075)
		(width 0.12446)
		(layer "F.Cu")
		(net "PHY_EXP_TO_CONN_9_DN")
	)
	(segment
		(start 103.39451 -105.65765)
		(end 103.809292 -105.569258)
		(width 0.1016)
		(layer "In5.Cu")
		(net "PHY_EXP_TO_CONN_9_DN")
	)
	(segment
		(start 143.375888 -81.735168)
		(end 143.209772 -81.479644)
		(width 0.1016)
		(layer "In5.Cu")
		(net "PHY_EXP_TO_CONN_9_DN")
	)
	(segment
		(start 143.265906 -81.215992)
		(end 143.09979 -80.960468)
		(width 0.1016)
		(layer "In5.Cu")
		(net "PHY_EXP_TO_CONN_9_DN")
	)
	(segment
		(start 142.670276 -80.64881)
		(end 142.72641 -80.385158)
		(width 0.1016)
		(layer "In5.Cu")
		(net "PHY_EXP_TO_CONN_9_DN")
	)
	(segment
		(start 143.209772 -81.479644)
		(end 143.265906 -81.215992)
		(width 0.1016)
		(layer "In5.Cu")
		(net "PHY_EXP_TO_CONN_9_DN")
	)
	(segment
		(start 138.85799 -78.475586)
		(end 138.857736 -78.475332)
		(width 0.1016)
		(layer "In5.Cu")
		(net "PHY_EXP_TO_CONN_9_DN")
	)
	(segment
		(start 144.967198 -86.335108)
		(end 144.177766 -82.620104)
		(width 0.1016)
		(layer "In5.Cu")
		(net "PHY_EXP_TO_CONN_9_DN")
	)
	(segment
		(start 116.294916 -103.86949)
		(end 120.241314 -104.708452)
		(width 0.1016)
		(layer "In5.Cu")
		(net "PHY_EXP_TO_CONN_9_DN")
	)
	(segment
		(start 102.791006 -107.9246)
		(end 102.7303 -107.86364)
		(width 0.1016)
		(layer "In5.Cu")
		(net "PHY_EXP_TO_CONN_9_DN")
	)
	(segment
		(start 108.690156 -105.4862)
		(end 116.294916 -103.86949)
		(width 0.1016)
		(layer "In5.Cu")
		(net "PHY_EXP_TO_CONN_9_DN")
	)
	(segment
		(start 120.241314 -104.708452)
		(end 136.137396 -101.32949)
		(width 0.1016)
		(layer "In5.Cu")
		(net "PHY_EXP_TO_CONN_9_DN")
	)
	(segment
		(start 138.742674 -78.427834)
		(end 138.486134 -78.427834)
		(width 0.1016)
		(layer "In5.Cu")
		(net "PHY_EXP_TO_CONN_9_DN")
	)
	(segment
		(start 102.43312 -107.231942)
		(end 102.43312 -106.954066)
		(width 0.1016)
		(layer "In5.Cu")
		(net "PHY_EXP_TO_CONN_9_DN")
	)
	(segment
		(start 141.49578 -79.438246)
		(end 139.558776 -79.438246)
		(width 0.1016)
		(layer "In5.Cu")
		(net "PHY_EXP_TO_CONN_9_DN")
	)
	(segment
		(start 142.836392 -80.904334)
		(end 142.670276 -80.64881)
		(width 0.1016)
		(layer "In5.Cu")
		(net "PHY_EXP_TO_CONN_9_DN")
	)
	(segment
		(start 102.7303 -107.86364)
		(end 102.669594 -107.802934)
		(width 0.1016)
		(layer "In5.Cu")
		(net "PHY_EXP_TO_CONN_9_DN")
	)
	(segment
		(start 142.72641 -80.385158)
		(end 142.560294 -80.129634)
		(width 0.1016)
		(layer "In5.Cu")
		(net "PHY_EXP_TO_CONN_9_DN")
	)
	(segment
		(start 102.43312 -106.954066)
		(end 102.67696 -106.122978)
		(width 0.1016)
		(layer "In5.Cu")
		(net "PHY_EXP_TO_CONN_9_DN")
	)
	(segment
		(start 103.809292 -105.569258)
		(end 104.088946 -105.509822)
		(width 0.1016)
		(layer "In5.Cu")
		(net "PHY_EXP_TO_CONN_9_DN")
	)
	(segment
		(start 140.302742 -98.624644)
		(end 143.353536 -93.92666)
		(width 0.1016)
		(layer "In5.Cu")
		(net "PHY_EXP_TO_CONN_9_DN")
	)
	(segment
		(start 104.088946 -105.509822)
		(end 104.200198 -105.4862)
		(width 0.1016)
		(layer "In5.Cu")
		(net "PHY_EXP_TO_CONN_9_DN")
	)
	(segment
		(start 143.639286 -81.791302)
		(end 143.375888 -81.735168)
		(width 0.1016)
		(layer "In5.Cu")
		(net "PHY_EXP_TO_CONN_9_DN")
	)
	(segment
		(start 143.353536 -93.92666)
		(end 144.967198 -86.335108)
		(width 0.1016)
		(layer "In5.Cu")
		(net "PHY_EXP_TO_CONN_9_DN")
	)
	(segment
		(start 144.177766 -82.620104)
		(end 143.639286 -81.791302)
		(width 0.1016)
		(layer "In5.Cu")
		(net "PHY_EXP_TO_CONN_9_DN")
	)
	(segment
		(start 102.963218 -108.03636)
		(end 102.93985 -108.023914)
		(width 0.1016)
		(layer "In5.Cu")
		(net "PHY_EXP_TO_CONN_9_DN")
	)
	(segment
		(start 136.137396 -101.32949)
		(end 140.302742 -98.624644)
		(width 0.1016)
		(layer "In5.Cu")
		(net "PHY_EXP_TO_CONN_9_DN")
	)
	(segment
		(start 104.200198 -105.4862)
		(end 108.690156 -105.4862)
		(width 0.1016)
		(layer "In5.Cu")
		(net "PHY_EXP_TO_CONN_9_DN")
	)
	(segment
		(start 102.93985 -108.023914)
		(end 102.886764 -107.995466)
		(width 0.1016)
		(layer "In5.Cu")
		(net "PHY_EXP_TO_CONN_9_DN")
	)
	(segment
		(start 102.67696 -106.122978)
		(end 103.39451 -105.65765)
		(width 0.1016)
		(layer "In5.Cu")
		(net "PHY_EXP_TO_CONN_9_DN")
	)
	(segment
		(start 143.09979 -80.960468)
		(end 142.836392 -80.904334)
		(width 0.1016)
		(layer "In5.Cu")
		(net "PHY_EXP_TO_CONN_9_DN")
	)
	(segment
		(start 102.750112 -108.650024)
		(end 103.004874 -108.174028)
		(width 0.1016)
		(layer "In5.Cu")
		(net "PHY_EXP_TO_CONN_9_DN")
	)
	(segment
		(start 138.905234 -78.784704)
		(end 138.905234 -78.59014)
		(width 0.1016)
		(layer "In5.Cu")
		(net "PHY_EXP_TO_CONN_9_DN")
	)
	(segment
		(start 142.560294 -80.129634)
		(end 141.49578 -79.438246)
		(width 0.1016)
		(layer "In5.Cu")
		(net "PHY_EXP_TO_CONN_9_DN")
	)
	(arc
		(start 103.004874 -108.174028)
		(mid 103.012583 -108.096582)
		(end 102.963218 -108.03636)
		(width 0.1016)
		(layer "In5.Cu")
		(net "PHY_EXP_TO_CONN_9_DN")
	)
	(arc
		(start 102.669594 -107.802934)
		(mid 102.494603 -107.540946)
		(end 102.43312 -107.231942)
		(width 0.1016)
		(layer "In5.Cu")
		(net "PHY_EXP_TO_CONN_9_DN")
	)
	(arc
		(start 138.857736 -78.475332)
		(mid 138.80493 -78.440141)
		(end 138.742674 -78.427834)
		(width 0.1016)
		(layer "In5.Cu")
		(net "PHY_EXP_TO_CONN_9_DN")
	)
	(arc
		(start 139.558776 -79.438246)
		(mid 139.096652 -79.246828)
		(end 138.905234 -78.784704)
		(width 0.1016)
		(layer "In5.Cu")
		(net "PHY_EXP_TO_CONN_9_DN")
	)
	(arc
		(start 138.905234 -78.59014)
		(mid 138.892963 -78.52818)
		(end 138.85799 -78.475586)
		(width 0.1016)
		(layer "In5.Cu")
		(net "PHY_EXP_TO_CONN_9_DN")
	)
	(arc
		(start 102.886764 -107.995466)
		(mid 102.83627 -107.963565)
		(end 102.791006 -107.9246)
		(width 0.1016)
		(layer "In5.Cu")
		(net "PHY_EXP_TO_CONN_9_DN")
	)
	(segment
		(start 139.253722 -76.067412)
		(end 139.253722 -76.399898)
		(width 0.12446)
		(layer "F.Cu")
		(net "PHY_EXP_TO_CONN_8_DP")
	)
	(segment
		(start 136.604502 -75.43292)
		(end 138.61923 -75.43292)
		(width 0.12446)
		(layer "F.Cu")
		(net "PHY_EXP_TO_CONN_8_DP")
	)
	(segment
		(start 136.528302 -75.35672)
		(end 136.604502 -75.43292)
		(width 0.12446)
		(layer "F.Cu")
		(net "PHY_EXP_TO_CONN_8_DP")
	)
	(segment
		(start 139.379198 -76.52512)
		(end 139.622022 -76.52512)
		(width 0.12446)
		(layer "F.Cu")
		(net "PHY_EXP_TO_CONN_8_DP")
	)
	(arc
		(start 139.290298 -76.48829)
		(mid 139.331086 -76.515543)
		(end 139.379198 -76.52512)
		(width 0.12446)
		(layer "F.Cu")
		(net "PHY_EXP_TO_CONN_8_DP")
	)
	(arc
		(start 139.253722 -76.399898)
		(mid 139.26322 -76.447735)
		(end 139.290298 -76.48829)
		(width 0.12446)
		(layer "F.Cu")
		(net "PHY_EXP_TO_CONN_8_DP")
	)
	(arc
		(start 138.61923 -75.43292)
		(mid 138.862107 -75.48112)
		(end 139.068048 -75.618594)
		(width 0.12446)
		(layer "F.Cu")
		(net "PHY_EXP_TO_CONN_8_DP")
	)
	(arc
		(start 139.068048 -75.618594)
		(mid 139.205502 -75.824543)
		(end 139.253722 -76.067412)
		(width 0.12446)
		(layer "F.Cu")
		(net "PHY_EXP_TO_CONN_8_DP")
	)
	(segment
		(start 105.401872 -106.695494)
		(end 105.200196 -106.826558)
		(width 0.1016)
		(layer "In5.Cu")
		(net "PHY_EXP_TO_CONN_8_DP")
	)
	(segment
		(start 144.73301 -94.390718)
		(end 141.412976 -99.48418)
		(width 0.1016)
		(layer "In5.Cu")
		(net "PHY_EXP_TO_CONN_8_DP")
	)
	(segment
		(start 116.385086 -105.162096)
		(end 109.51845 -106.622088)
		(width 0.1016)
		(layer "In5.Cu")
		(net "PHY_EXP_TO_CONN_8_DP")
	)
	(segment
		(start 141.412976 -99.48418)
		(end 136.327642 -102.786688)
		(width 0.1016)
		(layer "In5.Cu")
		(net "PHY_EXP_TO_CONN_8_DP")
	)
	(segment
		(start 105.280968 -107.726734)
		(end 105.3338 -107.754928)
		(width 0.1016)
		(layer "In5.Cu")
		(net "PHY_EXP_TO_CONN_8_DP")
	)
	(segment
		(start 139.27709 -76.555092)
		(end 139.254992 -76.57719)
		(width 0.1016)
		(layer "In5.Cu")
		(net "PHY_EXP_TO_CONN_8_DP")
	)
	(segment
		(start 105.355644 -107.766612)
		(end 105.35666 -107.76712)
		(width 0.1016)
		(layer "In5.Cu")
		(net "PHY_EXP_TO_CONN_8_DP")
	)
	(segment
		(start 139.674092 -77.35316)
		(end 141.153642 -77.35316)
		(width 0.1016)
		(layer "In5.Cu")
		(net "PHY_EXP_TO_CONN_8_DP")
	)
	(segment
		(start 136.327642 -102.786688)
		(end 120.768872 -106.093768)
		(width 0.1016)
		(layer "In5.Cu")
		(net "PHY_EXP_TO_CONN_8_DP")
	)
	(segment
		(start 105.337864 -107.757214)
		(end 105.355644 -107.766612)
		(width 0.1016)
		(layer "In5.Cu")
		(net "PHY_EXP_TO_CONN_8_DP")
	)
	(segment
		(start 109.51845 -106.622088)
		(end 105.765092 -106.622088)
		(width 0.1016)
		(layer "In5.Cu")
		(net "PHY_EXP_TO_CONN_8_DP")
	)
	(segment
		(start 141.601698 -77.524356)
		(end 142.764256 -78.279498)
		(width 0.1016)
		(layer "In5.Cu")
		(net "PHY_EXP_TO_CONN_8_DP")
	)
	(segment
		(start 105.49509 -107.725972)
		(end 105.750106 -107.249976)
		(width 0.1016)
		(layer "In5.Cu")
		(net "PHY_EXP_TO_CONN_8_DP")
	)
	(segment
		(start 143.06931 -78.477618)
		(end 145.137886 -81.662778)
		(width 0.1016)
		(layer "In5.Cu")
		(net "PHY_EXP_TO_CONN_8_DP")
	)
	(segment
		(start 105.200196 -106.826558)
		(end 105.018586 -107.106466)
		(width 0.1016)
		(layer "In5.Cu")
		(net "PHY_EXP_TO_CONN_8_DP")
	)
	(segment
		(start 139.622022 -76.52512)
		(end 139.348972 -76.52512)
		(width 0.1016)
		(layer "In5.Cu")
		(net "PHY_EXP_TO_CONN_8_DP")
	)
	(segment
		(start 142.764256 -78.279498)
		(end 143.06931 -78.477618)
		(width 0.1016)
		(layer "In5.Cu")
		(net "PHY_EXP_TO_CONN_8_DP")
	)
	(segment
		(start 146.287998 -87.075264)
		(end 144.73301 -94.390718)
		(width 0.1016)
		(layer "In5.Cu")
		(net "PHY_EXP_TO_CONN_8_DP")
	)
	(segment
		(start 145.137886 -81.662778)
		(end 146.287998 -87.075264)
		(width 0.1016)
		(layer "In5.Cu")
		(net "PHY_EXP_TO_CONN_8_DP")
	)
	(segment
		(start 105.765092 -106.622088)
		(end 105.401872 -106.695494)
		(width 0.1016)
		(layer "In5.Cu")
		(net "PHY_EXP_TO_CONN_8_DP")
	)
	(segment
		(start 120.768872 -106.093768)
		(end 116.385086 -105.162096)
		(width 0.1016)
		(layer "In5.Cu")
		(net "PHY_EXP_TO_CONN_8_DP")
	)
	(segment
		(start 139.202922 -76.702412)
		(end 139.202922 -76.88199)
		(width 0.1016)
		(layer "In5.Cu")
		(net "PHY_EXP_TO_CONN_8_DP")
	)
	(segment
		(start 105.35666 -107.76712)
		(end 105.357422 -107.767628)
		(width 0.1016)
		(layer "In5.Cu")
		(net "PHY_EXP_TO_CONN_8_DP")
	)
	(segment
		(start 105.335578 -107.755944)
		(end 105.337864 -107.757214)
		(width 0.1016)
		(layer "In5.Cu")
		(net "PHY_EXP_TO_CONN_8_DP")
	)
	(segment
		(start 105.334562 -107.755436)
		(end 105.335578 -107.755944)
		(width 0.1016)
		(layer "In5.Cu")
		(net "PHY_EXP_TO_CONN_8_DP")
	)
	(segment
		(start 105.3338 -107.754928)
		(end 105.334562 -107.755436)
		(width 0.1016)
		(layer "In5.Cu")
		(net "PHY_EXP_TO_CONN_8_DP")
	)
	(arc
		(start 139.348972 -76.52512)
		(mid 139.310062 -76.532971)
		(end 139.27709 -76.555092)
		(width 0.1016)
		(layer "In5.Cu")
		(net "PHY_EXP_TO_CONN_8_DP")
	)
	(arc
		(start 105.018586 -107.106466)
		(mid 105.040242 -107.462972)
		(end 105.280968 -107.726734)
		(width 0.1016)
		(layer "In5.Cu")
		(net "PHY_EXP_TO_CONN_8_DP")
	)
	(arc
		(start 141.153642 -77.35316)
		(mid 141.393462 -77.397422)
		(end 141.601698 -77.524356)
		(width 0.1016)
		(layer "In5.Cu")
		(net "PHY_EXP_TO_CONN_8_DP")
	)
	(arc
		(start 105.357422 -107.767628)
		(mid 105.434868 -107.775337)
		(end 105.49509 -107.725972)
		(width 0.1016)
		(layer "In5.Cu")
		(net "PHY_EXP_TO_CONN_8_DP")
	)
	(arc
		(start 139.202922 -76.88199)
		(mid 139.340924 -77.215158)
		(end 139.674092 -77.35316)
		(width 0.1016)
		(layer "In5.Cu")
		(net "PHY_EXP_TO_CONN_8_DP")
	)
	(arc
		(start 139.254992 -76.57719)
		(mid 139.216521 -76.634627)
		(end 139.202922 -76.702412)
		(width 0.1016)
		(layer "In5.Cu")
		(net "PHY_EXP_TO_CONN_8_DP")
	)
	(segment
		(start 138.810238 -76.488036)
		(end 138.809984 -76.48829)
		(width 0.12446)
		(layer "F.Cu")
		(net "PHY_EXP_TO_CONN_8_DN")
	)
	(segment
		(start 138.721592 -76.52512)
		(end 138.479022 -76.52512)
		(width 0.12446)
		(layer "F.Cu")
		(net "PHY_EXP_TO_CONN_8_DN")
	)
	(segment
		(start 136.604502 -75.83932)
		(end 138.61923 -75.83932)
		(width 0.12446)
		(layer "F.Cu")
		(net "PHY_EXP_TO_CONN_8_DN")
	)
	(segment
		(start 136.528302 -75.91552)
		(end 136.604502 -75.83932)
		(width 0.12446)
		(layer "F.Cu")
		(net "PHY_EXP_TO_CONN_8_DN")
	)
	(segment
		(start 138.847322 -76.067412)
		(end 138.847322 -76.398882)
		(width 0.12446)
		(layer "F.Cu")
		(net "PHY_EXP_TO_CONN_8_DN")
	)
	(arc
		(start 138.847322 -76.398882)
		(mid 138.83763 -76.447138)
		(end 138.810238 -76.488036)
		(width 0.12446)
		(layer "F.Cu")
		(net "PHY_EXP_TO_CONN_8_DN")
	)
	(arc
		(start 138.61923 -75.83932)
		(mid 138.706517 -75.856682)
		(end 138.78052 -75.906122)
		(width 0.12446)
		(layer "F.Cu")
		(net "PHY_EXP_TO_CONN_8_DN")
	)
	(arc
		(start 138.809984 -76.48829)
		(mid 138.769472 -76.51555)
		(end 138.721592 -76.52512)
		(width 0.12446)
		(layer "F.Cu")
		(net "PHY_EXP_TO_CONN_8_DN")
	)
	(arc
		(start 138.78052 -75.906122)
		(mid 138.829966 -75.980122)
		(end 138.847322 -76.067412)
		(width 0.12446)
		(layer "F.Cu")
		(net "PHY_EXP_TO_CONN_8_DN")
	)
	(segment
		(start 105.19664 -108.027724)
		(end 105.213404 -108.03636)
		(width 0.1016)
		(layer "In5.Cu")
		(net "PHY_EXP_TO_CONN_8_DN")
	)
	(segment
		(start 139.674092 -77.65796)
		(end 141.153388 -77.65796)
		(width 0.1016)
		(layer "In5.Cu")
		(net "PHY_EXP_TO_CONN_8_DN")
	)
	(segment
		(start 105.705148 -106.32313)
		(end 105.52303 -106.359706)
		(width 0.1016)
		(layer "In5.Cu")
		(net "PHY_EXP_TO_CONN_8_DN")
	)
	(segment
		(start 142.848838 -78.69809)
		(end 143.533876 -79.752698)
		(width 0.1016)
		(layer "In5.Cu")
		(net "PHY_EXP_TO_CONN_8_DN")
	)
	(segment
		(start 143.907256 -80.328008)
		(end 144.073372 -80.583532)
		(width 0.1016)
		(layer "In5.Cu")
		(net "PHY_EXP_TO_CONN_8_DN")
	)
	(segment
		(start 105.734358 -106.317288)
		(end 105.705148 -106.32313)
		(width 0.1016)
		(layer "In5.Cu")
		(net "PHY_EXP_TO_CONN_8_DN")
	)
	(segment
		(start 105.52303 -106.359706)
		(end 105.284524 -106.40822)
		(width 0.1016)
		(layer "In5.Cu")
		(net "PHY_EXP_TO_CONN_8_DN")
	)
	(segment
		(start 141.192758 -99.263708)
		(end 136.209024 -102.500176)
		(width 0.1016)
		(layer "In5.Cu")
		(net "PHY_EXP_TO_CONN_8_DN")
	)
	(segment
		(start 143.533876 -79.752698)
		(end 143.477742 -80.01635)
		(width 0.1016)
		(layer "In5.Cu")
		(net "PHY_EXP_TO_CONN_8_DN")
	)
	(segment
		(start 141.412722 -77.765402)
		(end 142.848838 -78.69809)
		(width 0.1016)
		(layer "In5.Cu")
		(net "PHY_EXP_TO_CONN_8_DN")
	)
	(segment
		(start 144.447006 -81.158842)
		(end 144.851374 -81.781396)
		(width 0.1016)
		(layer "In5.Cu")
		(net "PHY_EXP_TO_CONN_8_DN")
	)
	(segment
		(start 116.385086 -104.850438)
		(end 109.486192 -106.317288)
		(width 0.1016)
		(layer "In5.Cu")
		(net "PHY_EXP_TO_CONN_8_DN")
	)
	(segment
		(start 105.195878 -108.027216)
		(end 105.19664 -108.027724)
		(width 0.1016)
		(layer "In5.Cu")
		(net "PHY_EXP_TO_CONN_8_DN")
	)
	(segment
		(start 144.017492 -80.847184)
		(end 144.183608 -81.102708)
		(width 0.1016)
		(layer "In5.Cu")
		(net "PHY_EXP_TO_CONN_8_DN")
	)
	(segment
		(start 109.486192 -106.317288)
		(end 105.734358 -106.317288)
		(width 0.1016)
		(layer "In5.Cu")
		(net "PHY_EXP_TO_CONN_8_DN")
	)
	(segment
		(start 105.192068 -108.025184)
		(end 105.1941 -108.0262)
		(width 0.1016)
		(layer "In5.Cu")
		(net "PHY_EXP_TO_CONN_8_DN")
	)
	(segment
		(start 105.191306 -108.024676)
		(end 105.192068 -108.025184)
		(width 0.1016)
		(layer "In5.Cu")
		(net "PHY_EXP_TO_CONN_8_DN")
	)
	(segment
		(start 143.477742 -80.01635)
		(end 143.643858 -80.271874)
		(width 0.1016)
		(layer "In5.Cu")
		(net "PHY_EXP_TO_CONN_8_DN")
	)
	(segment
		(start 138.850624 -76.572618)
		(end 138.850878 -76.572872)
		(width 0.1016)
		(layer "In5.Cu")
		(net "PHY_EXP_TO_CONN_8_DN")
	)
	(segment
		(start 104.97947 -106.606086)
		(end 104.74071 -106.974386)
		(width 0.1016)
		(layer "In5.Cu")
		(net "PHY_EXP_TO_CONN_8_DN")
	)
	(segment
		(start 144.183608 -81.102708)
		(end 144.447006 -81.158842)
		(width 0.1016)
		(layer "In5.Cu")
		(net "PHY_EXP_TO_CONN_8_DN")
	)
	(segment
		(start 105.25506 -108.174028)
		(end 105.000044 -108.650024)
		(width 0.1016)
		(layer "In5.Cu")
		(net "PHY_EXP_TO_CONN_8_DN")
	)
	(segment
		(start 144.851374 -81.781396)
		(end 145.97634 -87.075264)
		(width 0.1016)
		(layer "In5.Cu")
		(net "PHY_EXP_TO_CONN_8_DN")
	)
	(segment
		(start 105.137712 -107.995974)
		(end 105.189782 -108.023914)
		(width 0.1016)
		(layer "In5.Cu")
		(net "PHY_EXP_TO_CONN_8_DN")
	)
	(segment
		(start 144.446498 -94.271846)
		(end 141.192758 -99.263708)
		(width 0.1016)
		(layer "In5.Cu")
		(net "PHY_EXP_TO_CONN_8_DN")
	)
	(segment
		(start 105.1941 -108.0262)
		(end 105.195878 -108.027216)
		(width 0.1016)
		(layer "In5.Cu")
		(net "PHY_EXP_TO_CONN_8_DN")
	)
	(segment
		(start 145.97634 -87.075264)
		(end 144.446498 -94.271846)
		(width 0.1016)
		(layer "In5.Cu")
		(net "PHY_EXP_TO_CONN_8_DN")
	)
	(segment
		(start 144.073372 -80.583532)
		(end 144.017492 -80.847184)
		(width 0.1016)
		(layer "In5.Cu")
		(net "PHY_EXP_TO_CONN_8_DN")
	)
	(segment
		(start 120.768872 -105.78211)
		(end 116.385086 -104.850438)
		(width 0.1016)
		(layer "In5.Cu")
		(net "PHY_EXP_TO_CONN_8_DN")
	)
	(segment
		(start 143.643858 -80.271874)
		(end 143.907256 -80.328008)
		(width 0.1016)
		(layer "In5.Cu")
		(net "PHY_EXP_TO_CONN_8_DN")
	)
	(segment
		(start 136.209024 -102.500176)
		(end 120.768872 -105.78211)
		(width 0.1016)
		(layer "In5.Cu")
		(net "PHY_EXP_TO_CONN_8_DN")
	)
	(segment
		(start 105.284524 -106.40822)
		(end 104.97947 -106.606086)
		(width 0.1016)
		(layer "In5.Cu")
		(net "PHY_EXP_TO_CONN_8_DN")
	)
	(segment
		(start 138.898122 -76.687426)
		(end 138.898122 -76.88199)
		(width 0.1016)
		(layer "In5.Cu")
		(net "PHY_EXP_TO_CONN_8_DN")
	)
	(segment
		(start 138.479022 -76.52512)
		(end 138.735562 -76.52512)
		(width 0.1016)
		(layer "In5.Cu")
		(net "PHY_EXP_TO_CONN_8_DN")
	)
	(segment
		(start 105.189782 -108.023914)
		(end 105.190036 -108.023914)
		(width 0.1016)
		(layer "In5.Cu")
		(net "PHY_EXP_TO_CONN_8_DN")
	)
	(segment
		(start 105.190036 -108.023914)
		(end 105.191306 -108.024676)
		(width 0.1016)
		(layer "In5.Cu")
		(net "PHY_EXP_TO_CONN_8_DN")
	)
	(arc
		(start 105.213404 -108.03636)
		(mid 105.262868 -108.096552)
		(end 105.25506 -108.174028)
		(width 0.1016)
		(layer "In5.Cu")
		(net "PHY_EXP_TO_CONN_8_DN")
	)
	(arc
		(start 138.850878 -76.572872)
		(mid 138.885836 -76.625472)
		(end 138.898122 -76.687426)
		(width 0.1016)
		(layer "In5.Cu")
		(net "PHY_EXP_TO_CONN_8_DN")
	)
	(arc
		(start 104.74071 -106.974386)
		(mid 104.749985 -107.558736)
		(end 105.137712 -107.995974)
		(width 0.1016)
		(layer "In5.Cu")
		(net "PHY_EXP_TO_CONN_8_DN")
	)
	(arc
		(start 138.898122 -76.88199)
		(mid 139.125398 -77.430684)
		(end 139.674092 -77.65796)
		(width 0.1016)
		(layer "In5.Cu")
		(net "PHY_EXP_TO_CONN_8_DN")
	)
	(arc
		(start 141.153388 -77.65796)
		(mid 141.293747 -77.685879)
		(end 141.412722 -77.765402)
		(width 0.1016)
		(layer "In5.Cu")
		(net "PHY_EXP_TO_CONN_8_DN")
	)
	(arc
		(start 138.735562 -76.52512)
		(mid 138.797825 -76.537411)
		(end 138.850624 -76.572618)
		(width 0.1016)
		(layer "In5.Cu")
		(net "PHY_EXP_TO_CONN_8_DN")
	)
	(segment
		(start 136.903968 -80.5688)
		(end 137.00633 -80.671162)
		(width 0.12446)
		(layer "F.Cu")
		(net "PHY_EXP_TO_CONN_11_DP")
	)
	(segment
		(start 137.93851 -81.216246)
		(end 138.983466 -81.216246)
		(width 0.12446)
		(layer "F.Cu")
		(net "PHY_EXP_TO_CONN_11_DP")
	)
	(segment
		(start 139.617958 -81.850738)
		(end 139.617958 -82.183224)
		(width 0.12446)
		(layer "F.Cu")
		(net "PHY_EXP_TO_CONN_11_DP")
	)
	(segment
		(start 136.525 -80.5688)
		(end 136.903968 -80.5688)
		(width 0.12446)
		(layer "F.Cu")
		(net "PHY_EXP_TO_CONN_11_DP")
	)
	(segment
		(start 139.743434 -82.308446)
		(end 139.986258 -82.308446)
		(width 0.12446)
		(layer "F.Cu")
		(net "PHY_EXP_TO_CONN_11_DP")
	)
	(segment
		(start 137.393426 -80.671162)
		(end 137.93851 -81.216246)
		(width 0.12446)
		(layer "F.Cu")
		(net "PHY_EXP_TO_CONN_11_DP")
	)
	(segment
		(start 139.432284 -81.402174)
		(end 139.432538 -81.402174)
		(width 0.12446)
		(layer "F.Cu")
		(net "PHY_EXP_TO_CONN_11_DP")
	)
	(segment
		(start 137.00633 -80.671162)
		(end 137.393426 -80.671162)
		(width 0.12446)
		(layer "F.Cu")
		(net "PHY_EXP_TO_CONN_11_DP")
	)
	(arc
		(start 138.983466 -81.216246)
		(mid 139.226373 -81.264563)
		(end 139.432284 -81.402174)
		(width 0.12446)
		(layer "F.Cu")
		(net "PHY_EXP_TO_CONN_11_DP")
	)
	(arc
		(start 139.617958 -82.183224)
		(mid 139.627456 -82.231061)
		(end 139.654534 -82.271616)
		(width 0.12446)
		(layer "F.Cu")
		(net "PHY_EXP_TO_CONN_11_DP")
	)
	(arc
		(start 139.654534 -82.271616)
		(mid 139.695322 -82.298869)
		(end 139.743434 -82.308446)
		(width 0.12446)
		(layer "F.Cu")
		(net "PHY_EXP_TO_CONN_11_DP")
	)
	(arc
		(start 139.432538 -81.402174)
		(mid 139.569807 -81.608035)
		(end 139.617958 -81.850738)
		(width 0.12446)
		(layer "F.Cu")
		(net "PHY_EXP_TO_CONN_11_DP")
	)
	(segment
		(start 139.641326 -82.338418)
		(end 139.619228 -82.360516)
		(width 0.1016)
		(layer "In5.Cu")
		(net "PHY_EXP_TO_CONN_11_DP")
	)
	(segment
		(start 139.567158 -82.485738)
		(end 139.567158 -82.665316)
		(width 0.1016)
		(layer "In5.Cu")
		(net "PHY_EXP_TO_CONN_11_DP")
	)
	(segment
		(start 139.63396 -82.826606)
		(end 139.702286 -82.894932)
		(width 0.1016)
		(layer "In5.Cu")
		(net "PHY_EXP_TO_CONN_11_DP")
	)
	(segment
		(start 142.537942 -84.13115)
		(end 143.134588 -86.938866)
		(width 0.1016)
		(layer "In5.Cu")
		(net "PHY_EXP_TO_CONN_11_DP")
	)
	(segment
		(start 103.095044 -102.374192)
		(end 102.73538 -102.928166)
		(width 0.1016)
		(layer "In5.Cu")
		(net "PHY_EXP_TO_CONN_11_DP")
	)
	(segment
		(start 105.765346 -101.493828)
		(end 105.764584 -101.494082)
		(width 0.1016)
		(layer "In5.Cu")
		(net "PHY_EXP_TO_CONN_11_DP")
	)
	(segment
		(start 103.030782 -103.92664)
		(end 103.107236 -103.967534)
		(width 0.1016)
		(layer "In5.Cu")
		(net "PHY_EXP_TO_CONN_11_DP")
	)
	(segment
		(start 140.50391 -83.058762)
		(end 141.00048 -83.185254)
		(width 0.1016)
		(layer "In5.Cu")
		(net "PHY_EXP_TO_CONN_11_DP")
	)
	(segment
		(start 111.570262 -102.086918)
		(end 107.273598 -101.17328)
		(width 0.1016)
		(layer "In5.Cu")
		(net "PHY_EXP_TO_CONN_11_DP")
	)
	(segment
		(start 113.528856 -101.670866)
		(end 111.570262 -102.086918)
		(width 0.1016)
		(layer "In5.Cu")
		(net "PHY_EXP_TO_CONN_11_DP")
	)
	(segment
		(start 105.764584 -101.494082)
		(end 105.763568 -101.494336)
		(width 0.1016)
		(layer "In5.Cu")
		(net "PHY_EXP_TO_CONN_11_DP")
	)
	(segment
		(start 135.983218 -99.19843)
		(end 118.939818 -102.821232)
		(width 0.1016)
		(layer "In5.Cu")
		(net "PHY_EXP_TO_CONN_11_DP")
	)
	(segment
		(start 138.777218 -97.383346)
		(end 135.983218 -99.19843)
		(width 0.1016)
		(layer "In5.Cu")
		(net "PHY_EXP_TO_CONN_11_DP")
	)
	(segment
		(start 142.370556 -83.87334)
		(end 142.537942 -84.13115)
		(width 0.1016)
		(layer "In5.Cu")
		(net "PHY_EXP_TO_CONN_11_DP")
	)
	(segment
		(start 140.097764 -83.058762)
		(end 140.50391 -83.058762)
		(width 0.1016)
		(layer "In5.Cu")
		(net "PHY_EXP_TO_CONN_11_DP")
	)
	(segment
		(start 141.95298 -92.494862)
		(end 138.777218 -97.383346)
		(width 0.1016)
		(layer "In5.Cu")
		(net "PHY_EXP_TO_CONN_11_DP")
	)
	(segment
		(start 118.939818 -102.821232)
		(end 113.528856 -101.670866)
		(width 0.1016)
		(layer "In5.Cu")
		(net "PHY_EXP_TO_CONN_11_DP")
	)
	(segment
		(start 107.273598 -101.17328)
		(end 105.765346 -101.493828)
		(width 0.1016)
		(layer "In5.Cu")
		(net "PHY_EXP_TO_CONN_11_DP")
	)
	(segment
		(start 141.509242 -83.315048)
		(end 142.370556 -83.87334)
		(width 0.1016)
		(layer "In5.Cu")
		(net "PHY_EXP_TO_CONN_11_DP")
	)
	(segment
		(start 143.134588 -86.938866)
		(end 141.95298 -92.494862)
		(width 0.1016)
		(layer "In5.Cu")
		(net "PHY_EXP_TO_CONN_11_DP")
	)
	(segment
		(start 141.00048 -83.185254)
		(end 141.509242 -83.315048)
		(width 0.1016)
		(layer "In5.Cu")
		(net "PHY_EXP_TO_CONN_11_DP")
	)
	(segment
		(start 103.81107 -101.909118)
		(end 103.095044 -102.374192)
		(width 0.1016)
		(layer "In5.Cu")
		(net "PHY_EXP_TO_CONN_11_DP")
	)
	(segment
		(start 105.763568 -101.494336)
		(end 103.81107 -101.909118)
		(width 0.1016)
		(layer "In5.Cu")
		(net "PHY_EXP_TO_CONN_11_DP")
	)
	(segment
		(start 139.986258 -82.308446)
		(end 139.713208 -82.308446)
		(width 0.1016)
		(layer "In5.Cu")
		(net "PHY_EXP_TO_CONN_11_DP")
	)
	(arc
		(start 102.73538 -102.928166)
		(mid 102.7419 -103.454304)
		(end 103.006906 -103.90886)
		(width 0.1016)
		(layer "In5.Cu")
		(net "PHY_EXP_TO_CONN_11_DP")
	)
	(arc
		(start 139.567158 -82.665316)
		(mid 139.58452 -82.752603)
		(end 139.63396 -82.826606)
		(width 0.1016)
		(layer "In5.Cu")
		(net "PHY_EXP_TO_CONN_11_DP")
	)
	(arc
		(start 103.107236 -103.967534)
		(mid 103.184682 -103.975243)
		(end 103.244904 -103.925878)
		(width 0.1016)
		(layer "In5.Cu")
		(net "PHY_EXP_TO_CONN_11_DP")
	)
	(arc
		(start 139.619228 -82.360516)
		(mid 139.580757 -82.417953)
		(end 139.567158 -82.485738)
		(width 0.1016)
		(layer "In5.Cu")
		(net "PHY_EXP_TO_CONN_11_DP")
	)
	(arc
		(start 139.713208 -82.308446)
		(mid 139.674298 -82.316297)
		(end 139.641326 -82.338418)
		(width 0.1016)
		(layer "In5.Cu")
		(net "PHY_EXP_TO_CONN_11_DP")
	)
	(arc
		(start 103.006906 -103.90886)
		(mid 103.01819 -103.918629)
		(end 103.030782 -103.92664)
		(width 0.1016)
		(layer "In5.Cu")
		(net "PHY_EXP_TO_CONN_11_DP")
	)
	(arc
		(start 103.244904 -103.925878)
		(mid 103.372092 -103.687835)
		(end 103.49992 -103.450136)
		(width 0.1016)
		(layer "In5.Cu")
		(net "PHY_EXP_TO_CONN_11_DP")
	)
	(arc
		(start 139.702286 -82.894932)
		(mid 139.883733 -83.016171)
		(end 140.097764 -83.058762)
		(width 0.1016)
		(layer "In5.Cu")
		(net "PHY_EXP_TO_CONN_11_DP")
	)
	(segment
		(start 136.954006 -81.077562)
		(end 137.225024 -81.077562)
		(width 0.12446)
		(layer "F.Cu")
		(net "PHY_EXP_TO_CONN_11_DN")
	)
	(segment
		(start 139.211558 -81.850738)
		(end 139.211558 -82.182208)
		(width 0.12446)
		(layer "F.Cu")
		(net "PHY_EXP_TO_CONN_11_DN")
	)
	(segment
		(start 139.174474 -82.271362)
		(end 139.17422 -82.271616)
		(width 0.12446)
		(layer "F.Cu")
		(net "PHY_EXP_TO_CONN_11_DN")
	)
	(segment
		(start 137.225024 -81.077562)
		(end 137.770108 -81.622646)
		(width 0.12446)
		(layer "F.Cu")
		(net "PHY_EXP_TO_CONN_11_DN")
	)
	(segment
		(start 137.770108 -81.622646)
		(end 138.983466 -81.622646)
		(width 0.12446)
		(layer "F.Cu")
		(net "PHY_EXP_TO_CONN_11_DN")
	)
	(segment
		(start 139.085828 -82.308446)
		(end 138.843258 -82.308446)
		(width 0.12446)
		(layer "F.Cu")
		(net "PHY_EXP_TO_CONN_11_DN")
	)
	(segment
		(start 136.525 -81.1276)
		(end 136.903968 -81.1276)
		(width 0.12446)
		(layer "F.Cu")
		(net "PHY_EXP_TO_CONN_11_DN")
	)
	(segment
		(start 136.903968 -81.1276)
		(end 136.954006 -81.077562)
		(width 0.12446)
		(layer "F.Cu")
		(net "PHY_EXP_TO_CONN_11_DN")
	)
	(arc
		(start 138.983466 -81.622646)
		(mid 139.070753 -81.640008)
		(end 139.144756 -81.689448)
		(width 0.12446)
		(layer "F.Cu")
		(net "PHY_EXP_TO_CONN_11_DN")
	)
	(arc
		(start 139.144756 -81.689448)
		(mid 139.194202 -81.763448)
		(end 139.211558 -81.850738)
		(width 0.12446)
		(layer "F.Cu")
		(net "PHY_EXP_TO_CONN_11_DN")
	)
	(arc
		(start 139.17422 -82.271616)
		(mid 139.133708 -82.298876)
		(end 139.085828 -82.308446)
		(width 0.12446)
		(layer "F.Cu")
		(net "PHY_EXP_TO_CONN_11_DN")
	)
	(arc
		(start 139.211558 -82.182208)
		(mid 139.201866 -82.230464)
		(end 139.174474 -82.271362)
		(width 0.12446)
		(layer "F.Cu")
		(net "PHY_EXP_TO_CONN_11_DN")
	)
	(segment
		(start 139.418314 -83.042252)
		(end 139.48664 -83.110578)
		(width 0.1016)
		(layer "In5.Cu")
		(net "PHY_EXP_TO_CONN_11_DN")
	)
	(segment
		(start 102.886764 -104.195372)
		(end 102.93985 -104.22382)
		(width 0.1016)
		(layer "In5.Cu")
		(net "PHY_EXP_TO_CONN_11_DN")
	)
	(segment
		(start 138.843258 -82.308446)
		(end 139.099798 -82.308446)
		(width 0.1016)
		(layer "In5.Cu")
		(net "PHY_EXP_TO_CONN_11_DN")
	)
	(segment
		(start 105.701846 -101.195378)
		(end 105.701084 -101.195632)
		(width 0.1016)
		(layer "In5.Cu")
		(net "PHY_EXP_TO_CONN_11_DN")
	)
	(segment
		(start 135.8646 -98.911918)
		(end 118.939818 -102.509574)
		(width 0.1016)
		(layer "In5.Cu")
		(net "PHY_EXP_TO_CONN_11_DN")
	)
	(segment
		(start 142.181326 -89.039954)
		(end 142.117826 -89.33815)
		(width 0.1016)
		(layer "In5.Cu")
		(net "PHY_EXP_TO_CONN_11_DN")
	)
	(segment
		(start 107.273598 -100.861622)
		(end 105.701846 -101.195378)
		(width 0.1016)
		(layer "In5.Cu")
		(net "PHY_EXP_TO_CONN_11_DN")
	)
	(segment
		(start 142.61338 -87.924132)
		(end 142.38732 -88.070944)
		(width 0.1016)
		(layer "In5.Cu")
		(net "PHY_EXP_TO_CONN_11_DN")
	)
	(segment
		(start 138.556746 -97.162874)
		(end 135.8646 -98.911918)
		(width 0.1016)
		(layer "In5.Cu")
		(net "PHY_EXP_TO_CONN_11_DN")
	)
	(segment
		(start 142.82293 -86.938866)
		(end 142.61338 -87.924132)
		(width 0.1016)
		(layer "In5.Cu")
		(net "PHY_EXP_TO_CONN_11_DN")
	)
	(segment
		(start 113.528856 -101.359208)
		(end 111.570262 -101.77526)
		(width 0.1016)
		(layer "In5.Cu")
		(net "PHY_EXP_TO_CONN_11_DN")
	)
	(segment
		(start 142.32382 -88.36914)
		(end 142.470632 -88.594946)
		(width 0.1016)
		(layer "In5.Cu")
		(net "PHY_EXP_TO_CONN_11_DN")
	)
	(segment
		(start 102.874572 -102.15372)
		(end 102.453694 -102.801928)
		(width 0.1016)
		(layer "In5.Cu")
		(net "PHY_EXP_TO_CONN_11_DN")
	)
	(segment
		(start 139.262358 -82.470752)
		(end 139.262358 -82.665316)
		(width 0.1016)
		(layer "In5.Cu")
		(net "PHY_EXP_TO_CONN_11_DN")
	)
	(segment
		(start 111.570262 -101.77526)
		(end 107.273598 -100.861622)
		(width 0.1016)
		(layer "In5.Cu")
		(net "PHY_EXP_TO_CONN_11_DN")
	)
	(segment
		(start 139.21486 -82.355944)
		(end 139.215114 -82.356198)
		(width 0.1016)
		(layer "In5.Cu")
		(net "PHY_EXP_TO_CONN_11_DN")
	)
	(segment
		(start 104.7242 -101.40315)
		(end 104.7242 -101.403404)
		(width 0.1016)
		(layer "In5.Cu")
		(net "PHY_EXP_TO_CONN_11_DN")
	)
	(segment
		(start 105.700068 -101.195886)
		(end 104.7242 -101.40315)
		(width 0.1016)
		(layer "In5.Cu")
		(net "PHY_EXP_TO_CONN_11_DN")
	)
	(segment
		(start 118.939818 -102.509574)
		(end 113.528856 -101.359208)
		(width 0.1016)
		(layer "In5.Cu")
		(net "PHY_EXP_TO_CONN_11_DN")
	)
	(segment
		(start 142.25143 -84.250022)
		(end 142.82293 -86.938866)
		(width 0.1016)
		(layer "In5.Cu")
		(net "PHY_EXP_TO_CONN_11_DN")
	)
	(segment
		(start 140.09751 -83.363562)
		(end 140.465556 -83.363562)
		(width 0.1016)
		(layer "In5.Cu")
		(net "PHY_EXP_TO_CONN_11_DN")
	)
	(segment
		(start 142.150084 -84.094066)
		(end 142.25143 -84.250022)
		(width 0.1016)
		(layer "In5.Cu")
		(net "PHY_EXP_TO_CONN_11_DN")
	)
	(segment
		(start 142.407132 -88.893142)
		(end 142.181326 -89.039954)
		(width 0.1016)
		(layer "In5.Cu")
		(net "PHY_EXP_TO_CONN_11_DN")
	)
	(segment
		(start 142.117826 -89.33815)
		(end 142.264638 -89.563956)
		(width 0.1016)
		(layer "In5.Cu")
		(net "PHY_EXP_TO_CONN_11_DN")
	)
	(segment
		(start 140.465556 -83.363562)
		(end 141.38529 -83.598004)
		(width 0.1016)
		(layer "In5.Cu")
		(net "PHY_EXP_TO_CONN_11_DN")
	)
	(segment
		(start 104.7242 -101.403404)
		(end 103.692452 -101.622606)
		(width 0.1016)
		(layer "In5.Cu")
		(net "PHY_EXP_TO_CONN_11_DN")
	)
	(segment
		(start 105.701084 -101.195632)
		(end 105.700068 -101.195886)
		(width 0.1016)
		(layer "In5.Cu")
		(net "PHY_EXP_TO_CONN_11_DN")
	)
	(segment
		(start 103.004874 -104.373934)
		(end 102.750112 -104.84993)
		(width 0.1016)
		(layer "In5.Cu")
		(net "PHY_EXP_TO_CONN_11_DN")
	)
	(segment
		(start 103.692452 -101.622606)
		(end 102.874572 -102.15372)
		(width 0.1016)
		(layer "In5.Cu")
		(net "PHY_EXP_TO_CONN_11_DN")
	)
	(segment
		(start 141.38529 -83.598004)
		(end 142.150084 -84.094066)
		(width 0.1016)
		(layer "In5.Cu")
		(net "PHY_EXP_TO_CONN_11_DN")
	)
	(segment
		(start 142.470632 -88.594946)
		(end 142.407132 -88.893142)
		(width 0.1016)
		(layer "In5.Cu")
		(net "PHY_EXP_TO_CONN_11_DN")
	)
	(segment
		(start 141.666468 -92.37599)
		(end 138.556746 -97.162874)
		(width 0.1016)
		(layer "In5.Cu")
		(net "PHY_EXP_TO_CONN_11_DN")
	)
	(segment
		(start 142.264638 -89.563956)
		(end 141.666468 -92.37599)
		(width 0.1016)
		(layer "In5.Cu")
		(net "PHY_EXP_TO_CONN_11_DN")
	)
	(segment
		(start 142.38732 -88.070944)
		(end 142.32382 -88.36914)
		(width 0.1016)
		(layer "In5.Cu")
		(net "PHY_EXP_TO_CONN_11_DN")
	)
	(segment
		(start 102.93985 -104.22382)
		(end 102.963218 -104.236266)
		(width 0.1016)
		(layer "In5.Cu")
		(net "PHY_EXP_TO_CONN_11_DN")
	)
	(arc
		(start 139.099798 -82.308446)
		(mid 139.162061 -82.320737)
		(end 139.21486 -82.355944)
		(width 0.1016)
		(layer "In5.Cu")
		(net "PHY_EXP_TO_CONN_11_DN")
	)
	(arc
		(start 102.791006 -104.124252)
		(mid 102.836256 -104.163352)
		(end 102.886764 -104.195372)
		(width 0.1016)
		(layer "In5.Cu")
		(net "PHY_EXP_TO_CONN_11_DN")
	)
	(arc
		(start 102.453694 -102.801928)
		(mid 102.440959 -103.509373)
		(end 102.791006 -104.124252)
		(width 0.1016)
		(layer "In5.Cu")
		(net "PHY_EXP_TO_CONN_11_DN")
	)
	(arc
		(start 102.963218 -104.236266)
		(mid 103.012682 -104.296458)
		(end 103.004874 -104.373934)
		(width 0.1016)
		(layer "In5.Cu")
		(net "PHY_EXP_TO_CONN_11_DN")
	)
	(arc
		(start 139.262358 -82.665316)
		(mid 139.302839 -82.869299)
		(end 139.418314 -83.042252)
		(width 0.1016)
		(layer "In5.Cu")
		(net "PHY_EXP_TO_CONN_11_DN")
	)
	(arc
		(start 139.48664 -83.110578)
		(mid 139.766924 -83.297794)
		(end 140.09751 -83.363562)
		(width 0.1016)
		(layer "In5.Cu")
		(net "PHY_EXP_TO_CONN_11_DN")
	)
	(arc
		(start 139.215114 -82.356198)
		(mid 139.250072 -82.408798)
		(end 139.262358 -82.470752)
		(width 0.1016)
		(layer "In5.Cu")
		(net "PHY_EXP_TO_CONN_11_DN")
	)
	(segment
		(start 136.88568 -79.171292)
		(end 136.506712 -79.171292)
		(width 0.12446)
		(layer "F.Cu")
		(net "PHY_EXP_TO_CONN_10_DP")
	)
	(segment
		(start 139.275312 -80.07223)
		(end 139.275312 -79.755746)
		(width 0.12446)
		(layer "F.Cu")
		(net "PHY_EXP_TO_CONN_10_DP")
	)
	(segment
		(start 139.643612 -80.197452)
		(end 139.400788 -80.197452)
		(width 0.12446)
		(layer "F.Cu")
		(net "PHY_EXP_TO_CONN_10_DP")
	)
	(segment
		(start 136.96188 -79.247492)
		(end 136.88568 -79.171292)
		(width 0.12446)
		(layer "F.Cu")
		(net "PHY_EXP_TO_CONN_10_DP")
	)
	(segment
		(start 138.767058 -79.247492)
		(end 136.96188 -79.247492)
		(width 0.12446)
		(layer "F.Cu")
		(net "PHY_EXP_TO_CONN_10_DP")
	)
	(arc
		(start 139.311888 -80.160622)
		(mid 139.284844 -80.120053)
		(end 139.275312 -80.07223)
		(width 0.12446)
		(layer "F.Cu")
		(net "PHY_EXP_TO_CONN_10_DP")
	)
	(arc
		(start 139.400788 -80.197452)
		(mid 139.352673 -80.187881)
		(end 139.311888 -80.160622)
		(width 0.12446)
		(layer "F.Cu")
		(net "PHY_EXP_TO_CONN_10_DP")
	)
	(arc
		(start 139.275312 -79.755746)
		(mid 139.236623 -79.561246)
		(end 139.126468 -79.396336)
		(width 0.12446)
		(layer "F.Cu")
		(net "PHY_EXP_TO_CONN_10_DP")
	)
	(arc
		(start 139.126468 -79.396336)
		(mid 138.961569 -79.286154)
		(end 138.767058 -79.247492)
		(width 0.12446)
		(layer "F.Cu")
		(net "PHY_EXP_TO_CONN_10_DP")
	)
	(segment
		(start 105.56367 -102.515416)
		(end 106.70413 -102.272592)
		(width 0.1016)
		(layer "In5.Cu")
		(net "PHY_EXP_TO_CONN_10_DP")
	)
	(segment
		(start 105.025952 -102.991412)
		(end 105.167938 -102.772464)
		(width 0.1016)
		(layer "In5.Cu")
		(net "PHY_EXP_TO_CONN_10_DP")
	)
	(segment
		(start 119.634762 -103.894128)
		(end 136.521444 -100.305108)
		(width 0.1016)
		(layer "In5.Cu")
		(net "PHY_EXP_TO_CONN_10_DP")
	)
	(segment
		(start 139.276582 -80.249522)
		(end 139.29868 -80.227424)
		(width 0.1016)
		(layer "In5.Cu")
		(net "PHY_EXP_TO_CONN_10_DP")
	)
	(segment
		(start 105.357168 -103.967534)
		(end 105.280714 -103.92664)
		(width 0.1016)
		(layer "In5.Cu")
		(net "PHY_EXP_TO_CONN_10_DP")
	)
	(segment
		(start 106.70413 -102.272592)
		(end 110.937548 -103.172768)
		(width 0.1016)
		(layer "In5.Cu")
		(net "PHY_EXP_TO_CONN_10_DP")
	)
	(segment
		(start 105.167938 -102.772464)
		(end 105.56367 -102.515416)
		(width 0.1016)
		(layer "In5.Cu")
		(net "PHY_EXP_TO_CONN_10_DP")
	)
	(segment
		(start 144.294098 -86.502748)
		(end 143.585692 -83.16849)
		(width 0.1016)
		(layer "In5.Cu")
		(net "PHY_EXP_TO_CONN_10_DP")
	)
	(segment
		(start 104.964738 -103.384604)
		(end 104.964738 -103.279448)
		(width 0.1016)
		(layer "In5.Cu")
		(net "PHY_EXP_TO_CONN_10_DP")
	)
	(segment
		(start 119.634762 -103.894382)
		(end 119.634762 -103.894128)
		(width 0.1016)
		(layer "In5.Cu")
		(net "PHY_EXP_TO_CONN_10_DP")
	)
	(segment
		(start 113.526062 -102.62235)
		(end 119.571516 -103.90759)
		(width 0.1016)
		(layer "In5.Cu")
		(net "PHY_EXP_TO_CONN_10_DP")
	)
	(segment
		(start 136.521444 -100.305108)
		(end 139.741656 -98.213926)
		(width 0.1016)
		(layer "In5.Cu")
		(net "PHY_EXP_TO_CONN_10_DP")
	)
	(segment
		(start 104.964738 -103.279448)
		(end 105.025952 -102.991412)
		(width 0.1016)
		(layer "In5.Cu")
		(net "PHY_EXP_TO_CONN_10_DP")
	)
	(segment
		(start 110.937548 -103.172768)
		(end 113.526062 -102.62235)
		(width 0.1016)
		(layer "In5.Cu")
		(net "PHY_EXP_TO_CONN_10_DP")
	)
	(segment
		(start 139.224512 -80.595978)
		(end 139.224512 -80.374744)
		(width 0.1016)
		(layer "In5.Cu")
		(net "PHY_EXP_TO_CONN_10_DP")
	)
	(segment
		(start 119.571516 -103.90759)
		(end 119.634762 -103.894382)
		(width 0.1016)
		(layer "In5.Cu")
		(net "PHY_EXP_TO_CONN_10_DP")
	)
	(segment
		(start 139.741656 -98.213926)
		(end 142.810484 -93.486732)
		(width 0.1016)
		(layer "In5.Cu")
		(net "PHY_EXP_TO_CONN_10_DP")
	)
	(segment
		(start 142.810484 -93.486732)
		(end 144.294098 -86.502748)
		(width 0.1016)
		(layer "In5.Cu")
		(net "PHY_EXP_TO_CONN_10_DP")
	)
	(segment
		(start 105.256838 -103.90886)
		(end 105.135172 -103.787194)
		(width 0.1016)
		(layer "In5.Cu")
		(net "PHY_EXP_TO_CONN_10_DP")
	)
	(segment
		(start 142.377668 -81.309464)
		(end 140.979652 -80.874362)
		(width 0.1016)
		(layer "In5.Cu")
		(net "PHY_EXP_TO_CONN_10_DP")
	)
	(segment
		(start 143.585692 -83.16849)
		(end 142.377668 -81.309464)
		(width 0.1016)
		(layer "In5.Cu")
		(net "PHY_EXP_TO_CONN_10_DP")
	)
	(segment
		(start 140.979652 -80.874362)
		(end 139.502896 -80.874362)
		(width 0.1016)
		(layer "In5.Cu")
		(net "PHY_EXP_TO_CONN_10_DP")
	)
	(segment
		(start 139.370562 -80.197452)
		(end 139.643612 -80.197452)
		(width 0.1016)
		(layer "In5.Cu")
		(net "PHY_EXP_TO_CONN_10_DP")
	)
	(arc
		(start 105.494836 -103.925878)
		(mid 105.434644 -103.975342)
		(end 105.357168 -103.967534)
		(width 0.1016)
		(layer "In5.Cu")
		(net "PHY_EXP_TO_CONN_10_DP")
	)
	(arc
		(start 139.502896 -80.874362)
		(mid 139.396363 -80.853171)
		(end 139.306046 -80.792828)
		(width 0.1016)
		(layer "In5.Cu")
		(net "PHY_EXP_TO_CONN_10_DP")
	)
	(arc
		(start 105.280714 -103.92664)
		(mid 105.268119 -103.918632)
		(end 105.256838 -103.90886)
		(width 0.1016)
		(layer "In5.Cu")
		(net "PHY_EXP_TO_CONN_10_DP")
	)
	(arc
		(start 105.750106 -103.450136)
		(mid 105.622101 -103.687809)
		(end 105.494836 -103.925878)
		(width 0.1016)
		(layer "In5.Cu")
		(net "PHY_EXP_TO_CONN_10_DP")
	)
	(arc
		(start 139.306046 -80.792828)
		(mid 139.245699 -80.702512)
		(end 139.224512 -80.595978)
		(width 0.1016)
		(layer "In5.Cu")
		(net "PHY_EXP_TO_CONN_10_DP")
	)
	(arc
		(start 139.29868 -80.227424)
		(mid 139.33163 -80.205251)
		(end 139.370562 -80.197452)
		(width 0.1016)
		(layer "In5.Cu")
		(net "PHY_EXP_TO_CONN_10_DP")
	)
	(arc
		(start 139.224512 -80.374744)
		(mid 139.23809 -80.306951)
		(end 139.276582 -80.249522)
		(width 0.1016)
		(layer "In5.Cu")
		(net "PHY_EXP_TO_CONN_10_DP")
	)
	(arc
		(start 105.135172 -103.787194)
		(mid 105.009129 -103.603187)
		(end 104.964738 -103.384604)
		(width 0.1016)
		(layer "In5.Cu")
		(net "PHY_EXP_TO_CONN_10_DP")
	)
	(segment
		(start 136.88568 -79.730092)
		(end 136.506712 -79.730092)
		(width 0.12446)
		(layer "F.Cu")
		(net "PHY_EXP_TO_CONN_10_DN")
	)
	(segment
		(start 138.500612 -80.197452)
		(end 138.743182 -80.197452)
		(width 0.12446)
		(layer "F.Cu")
		(net "PHY_EXP_TO_CONN_10_DN")
	)
	(segment
		(start 136.96188 -79.653892)
		(end 136.88568 -79.730092)
		(width 0.12446)
		(layer "F.Cu")
		(net "PHY_EXP_TO_CONN_10_DN")
	)
	(segment
		(start 138.767058 -79.653892)
		(end 136.96188 -79.653892)
		(width 0.12446)
		(layer "F.Cu")
		(net "PHY_EXP_TO_CONN_10_DN")
	)
	(segment
		(start 138.868912 -80.071214)
		(end 138.868912 -79.755746)
		(width 0.12446)
		(layer "F.Cu")
		(net "PHY_EXP_TO_CONN_10_DN")
	)
	(segment
		(start 138.831574 -80.160622)
		(end 138.831828 -80.160368)
		(width 0.12446)
		(layer "F.Cu")
		(net "PHY_EXP_TO_CONN_10_DN")
	)
	(arc
		(start 138.743182 -80.197452)
		(mid 138.79106 -80.187875)
		(end 138.831574 -80.160622)
		(width 0.12446)
		(layer "F.Cu")
		(net "PHY_EXP_TO_CONN_10_DN")
	)
	(arc
		(start 138.868912 -79.755746)
		(mid 138.861076 -79.716822)
		(end 138.83894 -79.683864)
		(width 0.12446)
		(layer "F.Cu")
		(net "PHY_EXP_TO_CONN_10_DN")
	)
	(arc
		(start 138.831828 -80.160368)
		(mid 138.859242 -80.119479)
		(end 138.868912 -80.071214)
		(width 0.12446)
		(layer "F.Cu")
		(net "PHY_EXP_TO_CONN_10_DN")
	)
	(arc
		(start 138.83894 -79.683864)
		(mid 138.805975 -79.661745)
		(end 138.767058 -79.653892)
		(width 0.12446)
		(layer "F.Cu")
		(net "PHY_EXP_TO_CONN_10_DN")
	)
	(segment
		(start 139.521184 -97.993454)
		(end 136.402826 -100.018596)
		(width 0.1016)
		(layer "In5.Cu")
		(net "PHY_EXP_TO_CONN_10_DN")
	)
	(segment
		(start 143.857726 -85.916516)
		(end 143.98244 -86.502748)
		(width 0.1016)
		(layer "In5.Cu")
		(net "PHY_EXP_TO_CONN_10_DN")
	)
	(segment
		(start 138.872214 -80.24495)
		(end 138.872468 -80.245204)
		(width 0.1016)
		(layer "In5.Cu")
		(net "PHY_EXP_TO_CONN_10_DN")
	)
	(segment
		(start 104.73944 -102.872794)
		(end 104.659938 -103.24719)
		(width 0.1016)
		(layer "In5.Cu")
		(net "PHY_EXP_TO_CONN_10_DN")
	)
	(segment
		(start 143.29918 -83.287108)
		(end 143.29918 -83.287362)
		(width 0.1016)
		(layer "In5.Cu")
		(net "PHY_EXP_TO_CONN_10_DN")
	)
	(segment
		(start 110.937548 -102.86111)
		(end 106.70413 -101.960934)
		(width 0.1016)
		(layer "In5.Cu")
		(net "PHY_EXP_TO_CONN_10_DN")
	)
	(segment
		(start 143.715232 -85.245702)
		(end 143.568674 -85.471508)
		(width 0.1016)
		(layer "In5.Cu")
		(net "PHY_EXP_TO_CONN_10_DN")
	)
	(segment
		(start 142.181834 -81.568036)
		(end 143.29918 -83.287108)
		(width 0.1016)
		(layer "In5.Cu")
		(net "PHY_EXP_TO_CONN_10_DN")
	)
	(segment
		(start 143.568674 -85.471508)
		(end 143.63192 -85.769704)
		(width 0.1016)
		(layer "In5.Cu")
		(net "PHY_EXP_TO_CONN_10_DN")
	)
	(segment
		(start 143.36268 -84.502752)
		(end 143.425926 -84.800694)
		(width 0.1016)
		(layer "In5.Cu")
		(net "PHY_EXP_TO_CONN_10_DN")
	)
	(segment
		(start 143.509492 -84.276692)
		(end 143.36268 -84.502752)
		(width 0.1016)
		(layer "In5.Cu")
		(net "PHY_EXP_TO_CONN_10_DN")
	)
	(segment
		(start 142.523972 -93.368114)
		(end 139.521184 -97.993454)
		(width 0.1016)
		(layer "In5.Cu")
		(net "PHY_EXP_TO_CONN_10_DN")
	)
	(segment
		(start 143.63192 -85.769704)
		(end 143.857726 -85.916516)
		(width 0.1016)
		(layer "In5.Cu")
		(net "PHY_EXP_TO_CONN_10_DN")
	)
	(segment
		(start 104.947212 -102.551992)
		(end 104.73944 -102.872794)
		(width 0.1016)
		(layer "In5.Cu")
		(net "PHY_EXP_TO_CONN_10_DN")
	)
	(segment
		(start 143.425926 -84.800694)
		(end 143.651986 -84.947506)
		(width 0.1016)
		(layer "In5.Cu")
		(net "PHY_EXP_TO_CONN_10_DN")
	)
	(segment
		(start 105.136696 -104.195372)
		(end 105.189782 -104.22382)
		(width 0.1016)
		(layer "In5.Cu")
		(net "PHY_EXP_TO_CONN_10_DN")
	)
	(segment
		(start 105.199942 -102.388162)
		(end 104.947212 -102.551992)
		(width 0.1016)
		(layer "In5.Cu")
		(net "PHY_EXP_TO_CONN_10_DN")
	)
	(segment
		(start 105.189782 -104.22382)
		(end 105.21315 -104.236266)
		(width 0.1016)
		(layer "In5.Cu")
		(net "PHY_EXP_TO_CONN_10_DN")
	)
	(segment
		(start 140.93317 -81.179162)
		(end 142.181834 -81.568036)
		(width 0.1016)
		(layer "In5.Cu")
		(net "PHY_EXP_TO_CONN_10_DN")
	)
	(segment
		(start 138.500612 -80.197452)
		(end 138.757152 -80.197452)
		(width 0.1016)
		(layer "In5.Cu")
		(net "PHY_EXP_TO_CONN_10_DN")
	)
	(segment
		(start 139.502896 -81.179162)
		(end 140.93317 -81.179162)
		(width 0.1016)
		(layer "In5.Cu")
		(net "PHY_EXP_TO_CONN_10_DN")
	)
	(segment
		(start 143.98244 -86.502748)
		(end 142.523972 -93.368114)
		(width 0.1016)
		(layer "In5.Cu")
		(net "PHY_EXP_TO_CONN_10_DN")
	)
	(segment
		(start 104.92105 -104.004364)
		(end 104.980232 -104.063546)
		(width 0.1016)
		(layer "In5.Cu")
		(net "PHY_EXP_TO_CONN_10_DN")
	)
	(segment
		(start 119.571516 -103.595932)
		(end 113.526062 -102.310692)
		(width 0.1016)
		(layer "In5.Cu")
		(net "PHY_EXP_TO_CONN_10_DN")
	)
	(segment
		(start 105.254806 -104.373934)
		(end 105.000044 -104.84993)
		(width 0.1016)
		(layer "In5.Cu")
		(net "PHY_EXP_TO_CONN_10_DN")
	)
	(segment
		(start 138.919712 -80.359758)
		(end 138.919712 -80.595978)
		(width 0.1016)
		(layer "In5.Cu")
		(net "PHY_EXP_TO_CONN_10_DN")
	)
	(segment
		(start 106.70413 -101.960934)
		(end 105.445052 -102.228904)
		(width 0.1016)
		(layer "In5.Cu")
		(net "PHY_EXP_TO_CONN_10_DN")
	)
	(segment
		(start 105.445052 -102.228904)
		(end 105.199942 -102.388162)
		(width 0.1016)
		(layer "In5.Cu")
		(net "PHY_EXP_TO_CONN_10_DN")
	)
	(segment
		(start 136.402826 -100.018596)
		(end 119.571516 -103.595932)
		(width 0.1016)
		(layer "In5.Cu")
		(net "PHY_EXP_TO_CONN_10_DN")
	)
	(segment
		(start 104.980232 -104.063546)
		(end 105.040938 -104.124506)
		(width 0.1016)
		(layer "In5.Cu")
		(net "PHY_EXP_TO_CONN_10_DN")
	)
	(segment
		(start 104.659938 -103.24719)
		(end 104.659938 -103.384604)
		(width 0.1016)
		(layer "In5.Cu")
		(net "PHY_EXP_TO_CONN_10_DN")
	)
	(segment
		(start 143.651986 -84.947506)
		(end 143.715232 -85.245702)
		(width 0.1016)
		(layer "In5.Cu")
		(net "PHY_EXP_TO_CONN_10_DN")
	)
	(segment
		(start 113.526062 -102.310692)
		(end 110.937548 -102.86111)
		(width 0.1016)
		(layer "In5.Cu")
		(net "PHY_EXP_TO_CONN_10_DN")
	)
	(segment
		(start 143.29918 -83.287362)
		(end 143.509492 -84.276692)
		(width 0.1016)
		(layer "In5.Cu")
		(net "PHY_EXP_TO_CONN_10_DN")
	)
	(arc
		(start 138.757152 -80.197452)
		(mid 138.819415 -80.209743)
		(end 138.872214 -80.24495)
		(width 0.1016)
		(layer "In5.Cu")
		(net "PHY_EXP_TO_CONN_10_DN")
	)
	(arc
		(start 138.919712 -80.595978)
		(mid 138.964021 -80.819207)
		(end 139.0904 -81.008474)
		(width 0.1016)
		(layer "In5.Cu")
		(net "PHY_EXP_TO_CONN_10_DN")
	)
	(arc
		(start 104.659938 -103.384604)
		(mid 104.727824 -103.720893)
		(end 104.92105 -104.004364)
		(width 0.1016)
		(layer "In5.Cu")
		(net "PHY_EXP_TO_CONN_10_DN")
	)
	(arc
		(start 138.872468 -80.245204)
		(mid 138.907426 -80.297804)
		(end 138.919712 -80.359758)
		(width 0.1016)
		(layer "In5.Cu")
		(net "PHY_EXP_TO_CONN_10_DN")
	)
	(arc
		(start 105.040938 -104.124506)
		(mid 105.08621 -104.163461)
		(end 105.136696 -104.195372)
		(width 0.1016)
		(layer "In5.Cu")
		(net "PHY_EXP_TO_CONN_10_DN")
	)
	(arc
		(start 139.0904 -81.008474)
		(mid 139.27967 -81.134847)
		(end 139.502896 -81.179162)
		(width 0.1016)
		(layer "In5.Cu")
		(net "PHY_EXP_TO_CONN_10_DN")
	)
	(arc
		(start 105.21315 -104.236266)
		(mid 105.262614 -104.296458)
		(end 105.254806 -104.373934)
		(width 0.1016)
		(layer "In5.Cu")
		(net "PHY_EXP_TO_CONN_10_DN")
	)
	(segment
		(start 103.49992 -55.500016)
		(end 103.000048 -55.000144)
		(width 0.104902)
		(layer "F.Cu")
		(net "PHY_DPB_TO_SCC_C_15_DP")
	)
	(via
		(at 103.000048 -55.000144)
		(size 0.4572)
		(drill 0.2032)
		(layers "F.Cu" "B.Cu")
		(net "PHY_DPB_TO_SCC_C_15_DP")
	)
	(segment
		(start 99.591622 -51.70932)
		(end 99.591622 -52.164996)
		(width 0.0889)
		(layer "B.Cu")
		(net "PHY_DPB_TO_SCC_C_15_DP")
	)
	(segment
		(start 101.839776 -54.3814)
		(end 102.229158 -54.3814)
		(width 0.0889)
		(layer "B.Cu")
		(net "PHY_DPB_TO_SCC_C_15_DP")
	)
	(segment
		(start 100.838508 -53.418486)
		(end 101.256084 -53.418486)
		(width 0.0889)
		(layer "B.Cu")
		(net "PHY_DPB_TO_SCC_C_15_DP")
	)
	(segment
		(start 96.776794 -50.366168)
		(end 97.143062 -50.366168)
		(width 0.12446)
		(layer "B.Cu")
		(net "PHY_DPB_TO_SCC_C_15_DP")
	)
	(segment
		(start 98.79203 -51.426872)
		(end 99.309174 -51.426872)
		(width 0.0889)
		(layer "B.Cu")
		(net "PHY_DPB_TO_SCC_C_15_DP")
	)
	(segment
		(start 98.505518 -51.318922)
		(end 98.661982 -51.318922)
		(width 0.12446)
		(layer "B.Cu")
		(net "PHY_DPB_TO_SCC_C_15_DP")
	)
	(segment
		(start 98.68408 -51.318922)
		(end 98.79203 -51.426872)
		(width 0.0889)
		(layer "B.Cu")
		(net "PHY_DPB_TO_SCC_C_15_DP")
	)
	(segment
		(start 100.284788 -52.407566)
		(end 100.594414 -52.717192)
		(width 0.0889)
		(layer "B.Cu")
		(net "PHY_DPB_TO_SCC_C_15_DP")
	)
	(segment
		(start 103.000048 -55.31612)
		(end 103.000048 -55.000144)
		(width 0.0889)
		(layer "B.Cu")
		(net "PHY_DPB_TO_SCC_C_15_DP")
	)
	(segment
		(start 97.641664 -50.455068)
		(end 98.505518 -51.318922)
		(width 0.12446)
		(layer "B.Cu")
		(net "PHY_DPB_TO_SCC_C_15_DP")
	)
	(segment
		(start 99.591622 -52.164996)
		(end 99.834192 -52.407566)
		(width 0.0889)
		(layer "B.Cu")
		(net "PHY_DPB_TO_SCC_C_15_DP")
	)
	(segment
		(start 101.622352 -53.784754)
		(end 101.622352 -54.163976)
		(width 0.0889)
		(layer "B.Cu")
		(net "PHY_DPB_TO_SCC_C_15_DP")
	)
	(segment
		(start 100.594414 -52.717192)
		(end 100.594414 -53.174392)
		(width 0.0889)
		(layer "B.Cu")
		(net "PHY_DPB_TO_SCC_C_15_DP")
	)
	(segment
		(start 102.761288 -55.40502)
		(end 102.911148 -55.40502)
		(width 0.0889)
		(layer "B.Cu")
		(net "PHY_DPB_TO_SCC_C_15_DP")
	)
	(segment
		(start 102.593902 -54.746144)
		(end 102.593902 -55.237634)
		(width 0.0889)
		(layer "B.Cu")
		(net "PHY_DPB_TO_SCC_C_15_DP")
	)
	(segment
		(start 99.309174 -51.426872)
		(end 99.591622 -51.70932)
		(width 0.0889)
		(layer "B.Cu")
		(net "PHY_DPB_TO_SCC_C_15_DP")
	)
	(segment
		(start 98.661982 -51.318922)
		(end 98.68408 -51.318922)
		(width 0.0889)
		(layer "B.Cu")
		(net "PHY_DPB_TO_SCC_C_15_DP")
	)
	(segment
		(start 99.834192 -52.407566)
		(end 100.284788 -52.407566)
		(width 0.0889)
		(layer "B.Cu")
		(net "PHY_DPB_TO_SCC_C_15_DP")
	)
	(segment
		(start 97.143062 -50.366168)
		(end 97.231962 -50.455068)
		(width 0.12446)
		(layer "B.Cu")
		(net "PHY_DPB_TO_SCC_C_15_DP")
	)
	(segment
		(start 101.622352 -54.163976)
		(end 101.839776 -54.3814)
		(width 0.0889)
		(layer "B.Cu")
		(net "PHY_DPB_TO_SCC_C_15_DP")
	)
	(segment
		(start 97.231962 -50.455068)
		(end 97.641664 -50.455068)
		(width 0.12446)
		(layer "B.Cu")
		(net "PHY_DPB_TO_SCC_C_15_DP")
	)
	(segment
		(start 101.256084 -53.418486)
		(end 101.622352 -53.784754)
		(width 0.0889)
		(layer "B.Cu")
		(net "PHY_DPB_TO_SCC_C_15_DP")
	)
	(segment
		(start 100.594414 -53.174392)
		(end 100.838508 -53.418486)
		(width 0.0889)
		(layer "B.Cu")
		(net "PHY_DPB_TO_SCC_C_15_DP")
	)
	(segment
		(start 102.229158 -54.3814)
		(end 102.593902 -54.746144)
		(width 0.0889)
		(layer "B.Cu")
		(net "PHY_DPB_TO_SCC_C_15_DP")
	)
	(arc
		(start 102.642924 -55.355998)
		(mid 102.69723 -55.392284)
		(end 102.761288 -55.40502)
		(width 0.0889)
		(layer "B.Cu")
		(net "PHY_DPB_TO_SCC_C_15_DP")
	)
	(arc
		(start 102.911148 -55.40502)
		(mid 102.97401 -55.378982)
		(end 103.000048 -55.31612)
		(width 0.0889)
		(layer "B.Cu")
		(net "PHY_DPB_TO_SCC_C_15_DP")
	)
	(arc
		(start 102.593902 -55.237634)
		(mid 102.606644 -55.30169)
		(end 102.642924 -55.355998)
		(width 0.0889)
		(layer "B.Cu")
		(net "PHY_DPB_TO_SCC_C_15_DP")
	)
	(segment
		(start 103.49992 -56.500014)
		(end 103.000048 -56.000142)
		(width 0.104902)
		(layer "F.Cu")
		(net "PHY_DPB_TO_SCC_C_15_DN")
	)
	(via
		(at 103.000048 -56.000142)
		(size 0.4572)
		(drill 0.2032)
		(layers "F.Cu" "B.Cu")
		(net "PHY_DPB_TO_SCC_C_15_DN")
	)
	(segment
		(start 100.759514 -53.608986)
		(end 101.17709 -53.608986)
		(width 0.0889)
		(layer "B.Cu")
		(net "PHY_DPB_TO_SCC_C_15_DN")
	)
	(segment
		(start 101.17709 -53.608986)
		(end 101.431852 -53.863748)
		(width 0.0889)
		(layer "B.Cu")
		(net "PHY_DPB_TO_SCC_C_15_DN")
	)
	(segment
		(start 100.403914 -52.796186)
		(end 100.403914 -53.253386)
		(width 0.0889)
		(layer "B.Cu")
		(net "PHY_DPB_TO_SCC_C_15_DN")
	)
	(segment
		(start 102.761288 -55.59552)
		(end 102.911148 -55.59552)
		(width 0.0889)
		(layer "B.Cu")
		(net "PHY_DPB_TO_SCC_C_15_DN")
	)
	(segment
		(start 99.23018 -51.617372)
		(end 99.401122 -51.788314)
		(width 0.0889)
		(layer "B.Cu")
		(net "PHY_DPB_TO_SCC_C_15_DN")
	)
	(segment
		(start 101.431852 -53.863748)
		(end 101.431852 -54.24297)
		(width 0.0889)
		(layer "B.Cu")
		(net "PHY_DPB_TO_SCC_C_15_DN")
	)
	(segment
		(start 97.231962 -50.861468)
		(end 97.473262 -50.861468)
		(width 0.12446)
		(layer "B.Cu")
		(net "PHY_DPB_TO_SCC_C_15_DN")
	)
	(segment
		(start 98.337116 -51.725322)
		(end 98.661982 -51.725322)
		(width 0.12446)
		(layer "B.Cu")
		(net "PHY_DPB_TO_SCC_C_15_DN")
	)
	(segment
		(start 101.760782 -54.5719)
		(end 102.150164 -54.5719)
		(width 0.0889)
		(layer "B.Cu")
		(net "PHY_DPB_TO_SCC_C_15_DN")
	)
	(segment
		(start 96.776794 -50.950368)
		(end 97.143062 -50.950368)
		(width 0.12446)
		(layer "B.Cu")
		(net "PHY_DPB_TO_SCC_C_15_DN")
	)
	(segment
		(start 97.473262 -50.861468)
		(end 98.337116 -51.725322)
		(width 0.12446)
		(layer "B.Cu")
		(net "PHY_DPB_TO_SCC_C_15_DN")
	)
	(segment
		(start 98.79203 -51.617372)
		(end 99.23018 -51.617372)
		(width 0.0889)
		(layer "B.Cu")
		(net "PHY_DPB_TO_SCC_C_15_DN")
	)
	(segment
		(start 98.68408 -51.725322)
		(end 98.79203 -51.617372)
		(width 0.0889)
		(layer "B.Cu")
		(net "PHY_DPB_TO_SCC_C_15_DN")
	)
	(segment
		(start 98.661982 -51.725322)
		(end 98.68408 -51.725322)
		(width 0.0889)
		(layer "B.Cu")
		(net "PHY_DPB_TO_SCC_C_15_DN")
	)
	(segment
		(start 100.403914 -53.253386)
		(end 100.759514 -53.608986)
		(width 0.0889)
		(layer "B.Cu")
		(net "PHY_DPB_TO_SCC_C_15_DN")
	)
	(segment
		(start 100.205794 -52.598066)
		(end 100.403914 -52.796186)
		(width 0.0889)
		(layer "B.Cu")
		(net "PHY_DPB_TO_SCC_C_15_DN")
	)
	(segment
		(start 102.403402 -54.825138)
		(end 102.403402 -55.237634)
		(width 0.0889)
		(layer "B.Cu")
		(net "PHY_DPB_TO_SCC_C_15_DN")
	)
	(segment
		(start 103.000048 -55.68442)
		(end 103.000048 -56.000142)
		(width 0.0889)
		(layer "B.Cu")
		(net "PHY_DPB_TO_SCC_C_15_DN")
	)
	(segment
		(start 101.431852 -54.24297)
		(end 101.760782 -54.5719)
		(width 0.0889)
		(layer "B.Cu")
		(net "PHY_DPB_TO_SCC_C_15_DN")
	)
	(segment
		(start 99.755198 -52.598066)
		(end 100.205794 -52.598066)
		(width 0.0889)
		(layer "B.Cu")
		(net "PHY_DPB_TO_SCC_C_15_DN")
	)
	(segment
		(start 99.401122 -51.788314)
		(end 99.401122 -52.24399)
		(width 0.0889)
		(layer "B.Cu")
		(net "PHY_DPB_TO_SCC_C_15_DN")
	)
	(segment
		(start 99.401122 -52.24399)
		(end 99.755198 -52.598066)
		(width 0.0889)
		(layer "B.Cu")
		(net "PHY_DPB_TO_SCC_C_15_DN")
	)
	(segment
		(start 97.143062 -50.950368)
		(end 97.231962 -50.861468)
		(width 0.12446)
		(layer "B.Cu")
		(net "PHY_DPB_TO_SCC_C_15_DN")
	)
	(segment
		(start 102.150164 -54.5719)
		(end 102.403402 -54.825138)
		(width 0.0889)
		(layer "B.Cu")
		(net "PHY_DPB_TO_SCC_C_15_DN")
	)
	(arc
		(start 102.403402 -55.237634)
		(mid 102.430546 -55.374659)
		(end 102.50805 -55.490872)
		(width 0.0889)
		(layer "B.Cu")
		(net "PHY_DPB_TO_SCC_C_15_DN")
	)
	(arc
		(start 102.50805 -55.490872)
		(mid 102.624266 -55.568369)
		(end 102.761288 -55.59552)
		(width 0.0889)
		(layer "B.Cu")
		(net "PHY_DPB_TO_SCC_C_15_DN")
	)
	(arc
		(start 102.911148 -55.59552)
		(mid 102.97401 -55.621558)
		(end 103.000048 -55.68442)
		(width 0.0889)
		(layer "B.Cu")
		(net "PHY_DPB_TO_SCC_C_15_DN")
	)
	(segment
		(start 102.499922 -55.500016)
		(end 102.00005 -55.000144)
		(width 0.104902)
		(layer "F.Cu")
		(net "PHY_DPB_TO_SCC_C_14_DP")
	)
	(via
		(at 102.00005 -55.000144)
		(size 0.4572)
		(drill 0.2032)
		(layers "F.Cu" "B.Cu")
		(net "PHY_DPB_TO_SCC_C_14_DP")
	)
	(segment
		(start 101.593904 -54.746144)
		(end 101.231446 -54.383686)
		(width 0.0889)
		(layer "B.Cu")
		(net "PHY_DPB_TO_SCC_C_14_DP")
	)
	(segment
		(start 100.233226 -53.405024)
		(end 99.836224 -53.405024)
		(width 0.0889)
		(layer "B.Cu")
		(net "PHY_DPB_TO_SCC_C_14_DP")
	)
	(segment
		(start 102.00005 -55.000144)
		(end 102.00005 -55.31612)
		(width 0.0889)
		(layer "B.Cu")
		(net "PHY_DPB_TO_SCC_C_14_DP")
	)
	(segment
		(start 101.231446 -54.383686)
		(end 100.762308 -54.383686)
		(width 0.0889)
		(layer "B.Cu")
		(net "PHY_DPB_TO_SCC_C_14_DP")
	)
	(segment
		(start 98.54692 -52.314602)
		(end 98.524822 -52.314602)
		(width 0.0889)
		(layer "B.Cu")
		(net "PHY_DPB_TO_SCC_C_14_DP")
	)
	(segment
		(start 99.22383 -52.422552)
		(end 98.65487 -52.422552)
		(width 0.0889)
		(layer "B.Cu")
		(net "PHY_DPB_TO_SCC_C_14_DP")
	)
	(segment
		(start 97.653856 -51.826668)
		(end 97.206562 -51.826668)
		(width 0.12446)
		(layer "B.Cu")
		(net "PHY_DPB_TO_SCC_C_14_DP")
	)
	(segment
		(start 99.57562 -53.14442)
		(end 99.57562 -52.774342)
		(width 0.0889)
		(layer "B.Cu")
		(net "PHY_DPB_TO_SCC_C_14_DP")
	)
	(segment
		(start 97.206562 -51.826668)
		(end 97.143062 -51.763168)
		(width 0.12446)
		(layer "B.Cu")
		(net "PHY_DPB_TO_SCC_C_14_DP")
	)
	(segment
		(start 101.593904 -55.237634)
		(end 101.593904 -54.746144)
		(width 0.0889)
		(layer "B.Cu")
		(net "PHY_DPB_TO_SCC_C_14_DP")
	)
	(segment
		(start 101.91115 -55.40502)
		(end 101.76129 -55.40502)
		(width 0.0889)
		(layer "B.Cu")
		(net "PHY_DPB_TO_SCC_C_14_DP")
	)
	(segment
		(start 100.594922 -53.76672)
		(end 100.233226 -53.405024)
		(width 0.0889)
		(layer "B.Cu")
		(net "PHY_DPB_TO_SCC_C_14_DP")
	)
	(segment
		(start 98.524822 -52.314602)
		(end 98.14179 -52.314602)
		(width 0.12446)
		(layer "B.Cu")
		(net "PHY_DPB_TO_SCC_C_14_DP")
	)
	(segment
		(start 98.14179 -52.314602)
		(end 97.653856 -51.826668)
		(width 0.12446)
		(layer "B.Cu")
		(net "PHY_DPB_TO_SCC_C_14_DP")
	)
	(segment
		(start 97.143062 -51.763168)
		(end 96.776794 -51.763168)
		(width 0.12446)
		(layer "B.Cu")
		(net "PHY_DPB_TO_SCC_C_14_DP")
	)
	(segment
		(start 99.836224 -53.405024)
		(end 99.57562 -53.14442)
		(width 0.0889)
		(layer "B.Cu")
		(net "PHY_DPB_TO_SCC_C_14_DP")
	)
	(segment
		(start 100.762308 -54.383686)
		(end 100.594922 -54.2163)
		(width 0.0889)
		(layer "B.Cu")
		(net "PHY_DPB_TO_SCC_C_14_DP")
	)
	(segment
		(start 99.57562 -52.774342)
		(end 99.22383 -52.422552)
		(width 0.0889)
		(layer "B.Cu")
		(net "PHY_DPB_TO_SCC_C_14_DP")
	)
	(segment
		(start 98.65487 -52.422552)
		(end 98.54692 -52.314602)
		(width 0.0889)
		(layer "B.Cu")
		(net "PHY_DPB_TO_SCC_C_14_DP")
	)
	(segment
		(start 100.594922 -54.2163)
		(end 100.594922 -53.76672)
		(width 0.0889)
		(layer "B.Cu")
		(net "PHY_DPB_TO_SCC_C_14_DP")
	)
	(arc
		(start 102.00005 -55.31612)
		(mid 101.974012 -55.378982)
		(end 101.91115 -55.40502)
		(width 0.0889)
		(layer "B.Cu")
		(net "PHY_DPB_TO_SCC_C_14_DP")
	)
	(arc
		(start 101.76129 -55.40502)
		(mid 101.697234 -55.392278)
		(end 101.642926 -55.355998)
		(width 0.0889)
		(layer "B.Cu")
		(net "PHY_DPB_TO_SCC_C_14_DP")
	)
	(arc
		(start 101.642926 -55.355998)
		(mid 101.60664 -55.301692)
		(end 101.593904 -55.237634)
		(width 0.0889)
		(layer "B.Cu")
		(net "PHY_DPB_TO_SCC_C_14_DP")
	)
	(segment
		(start 102.499922 -56.500014)
		(end 102.00005 -56.000142)
		(width 0.104902)
		(layer "F.Cu")
		(net "PHY_DPB_TO_SCC_C_14_DN")
	)
	(via
		(at 102.00005 -56.000142)
		(size 0.4572)
		(drill 0.2032)
		(layers "F.Cu" "B.Cu")
		(net "PHY_DPB_TO_SCC_C_14_DN")
	)
	(segment
		(start 98.54692 -52.721002)
		(end 98.65487 -52.613052)
		(width 0.0889)
		(layer "B.Cu")
		(net "PHY_DPB_TO_SCC_C_14_DN")
	)
	(segment
		(start 102.00005 -55.68442)
		(end 102.00005 -56.000142)
		(width 0.0889)
		(layer "B.Cu")
		(net "PHY_DPB_TO_SCC_C_14_DN")
	)
	(segment
		(start 98.65487 -52.613052)
		(end 99.144836 -52.613052)
		(width 0.0889)
		(layer "B.Cu")
		(net "PHY_DPB_TO_SCC_C_14_DN")
	)
	(segment
		(start 97.973388 -52.721002)
		(end 98.524822 -52.721002)
		(width 0.12446)
		(layer "B.Cu")
		(net "PHY_DPB_TO_SCC_C_14_DN")
	)
	(segment
		(start 99.38512 -53.223414)
		(end 99.75723 -53.595524)
		(width 0.0889)
		(layer "B.Cu")
		(net "PHY_DPB_TO_SCC_C_14_DN")
	)
	(segment
		(start 100.683314 -54.574186)
		(end 101.152452 -54.574186)
		(width 0.0889)
		(layer "B.Cu")
		(net "PHY_DPB_TO_SCC_C_14_DN")
	)
	(segment
		(start 100.404422 -54.295294)
		(end 100.683314 -54.574186)
		(width 0.0889)
		(layer "B.Cu")
		(net "PHY_DPB_TO_SCC_C_14_DN")
	)
	(segment
		(start 101.152452 -54.574186)
		(end 101.403404 -54.825138)
		(width 0.0889)
		(layer "B.Cu")
		(net "PHY_DPB_TO_SCC_C_14_DN")
	)
	(segment
		(start 99.144836 -52.613052)
		(end 99.38512 -52.853336)
		(width 0.0889)
		(layer "B.Cu")
		(net "PHY_DPB_TO_SCC_C_14_DN")
	)
	(segment
		(start 100.154232 -53.595524)
		(end 100.404422 -53.845714)
		(width 0.0889)
		(layer "B.Cu")
		(net "PHY_DPB_TO_SCC_C_14_DN")
	)
	(segment
		(start 96.776794 -52.347368)
		(end 97.143062 -52.347368)
		(width 0.12446)
		(layer "B.Cu")
		(net "PHY_DPB_TO_SCC_C_14_DN")
	)
	(segment
		(start 100.404422 -53.845714)
		(end 100.404422 -54.295294)
		(width 0.0889)
		(layer "B.Cu")
		(net "PHY_DPB_TO_SCC_C_14_DN")
	)
	(segment
		(start 101.76129 -55.59552)
		(end 101.91115 -55.59552)
		(width 0.0889)
		(layer "B.Cu")
		(net "PHY_DPB_TO_SCC_C_14_DN")
	)
	(segment
		(start 99.75723 -53.595524)
		(end 100.154232 -53.595524)
		(width 0.0889)
		(layer "B.Cu")
		(net "PHY_DPB_TO_SCC_C_14_DN")
	)
	(segment
		(start 97.257362 -52.233068)
		(end 97.485454 -52.233068)
		(width 0.12446)
		(layer "B.Cu")
		(net "PHY_DPB_TO_SCC_C_14_DN")
	)
	(segment
		(start 98.524822 -52.721002)
		(end 98.54692 -52.721002)
		(width 0.0889)
		(layer "B.Cu")
		(net "PHY_DPB_TO_SCC_C_14_DN")
	)
	(segment
		(start 101.403404 -54.825138)
		(end 101.403404 -55.237634)
		(width 0.0889)
		(layer "B.Cu")
		(net "PHY_DPB_TO_SCC_C_14_DN")
	)
	(segment
		(start 97.485454 -52.233068)
		(end 97.973388 -52.721002)
		(width 0.12446)
		(layer "B.Cu")
		(net "PHY_DPB_TO_SCC_C_14_DN")
	)
	(segment
		(start 97.143062 -52.347368)
		(end 97.257362 -52.233068)
		(width 0.12446)
		(layer "B.Cu")
		(net "PHY_DPB_TO_SCC_C_14_DN")
	)
	(segment
		(start 99.38512 -52.853336)
		(end 99.38512 -53.223414)
		(width 0.0889)
		(layer "B.Cu")
		(net "PHY_DPB_TO_SCC_C_14_DN")
	)
	(arc
		(start 101.91115 -55.59552)
		(mid 101.974012 -55.621558)
		(end 102.00005 -55.68442)
		(width 0.0889)
		(layer "B.Cu")
		(net "PHY_DPB_TO_SCC_C_14_DN")
	)
	(arc
		(start 101.403404 -55.237634)
		(mid 101.430548 -55.374659)
		(end 101.508052 -55.490872)
		(width 0.0889)
		(layer "B.Cu")
		(net "PHY_DPB_TO_SCC_C_14_DN")
	)
	(arc
		(start 101.508052 -55.490872)
		(mid 101.624268 -55.568369)
		(end 101.76129 -55.59552)
		(width 0.0889)
		(layer "B.Cu")
		(net "PHY_DPB_TO_SCC_C_14_DN")
	)
	(segment
		(start 101.499924 -55.500016)
		(end 101.000052 -55.000144)
		(width 0.104902)
		(layer "F.Cu")
		(net "PHY_DPB_TO_SCC_C_13_DP")
	)
	(via
		(at 101.000052 -55.000144)
		(size 0.4572)
		(drill 0.2032)
		(layers "F.Cu" "B.Cu")
		(net "PHY_DPB_TO_SCC_C_13_DP")
	)
	(segment
		(start 96.776794 -53.160168)
		(end 97.143062 -53.160168)
		(width 0.12446)
		(layer "B.Cu")
		(net "PHY_DPB_TO_SCC_C_13_DP")
	)
	(segment
		(start 97.2058 -53.222906)
		(end 97.614994 -53.222906)
		(width 0.12446)
		(layer "B.Cu")
		(net "PHY_DPB_TO_SCC_C_13_DP")
	)
	(segment
		(start 99.39909 -53.556916)
		(end 99.424998 -53.58257)
		(width 0.0889)
		(layer "B.Cu")
		(net "PHY_DPB_TO_SCC_C_13_DP")
	)
	(segment
		(start 98.789744 -53.405024)
		(end 99.032822 -53.405024)
		(width 0.0889)
		(layer "B.Cu")
		(net "PHY_DPB_TO_SCC_C_13_DP")
	)
	(segment
		(start 98.681794 -53.297074)
		(end 98.789744 -53.405024)
		(width 0.0889)
		(layer "B.Cu")
		(net "PHY_DPB_TO_SCC_C_13_DP")
	)
	(segment
		(start 97.614994 -53.222906)
		(end 97.689162 -53.297074)
		(width 0.12446)
		(layer "B.Cu")
		(net "PHY_DPB_TO_SCC_C_13_DP")
	)
	(segment
		(start 99.911154 -55.40502)
		(end 100.911152 -55.40502)
		(width 0.0889)
		(layer "B.Cu")
		(net "PHY_DPB_TO_SCC_C_13_DP")
	)
	(segment
		(start 99.602544 -55.096664)
		(end 99.602798 -55.09641)
		(width 0.0889)
		(layer "B.Cu")
		(net "PHY_DPB_TO_SCC_C_13_DP")
	)
	(segment
		(start 98.659696 -53.297074)
		(end 98.681794 -53.297074)
		(width 0.0889)
		(layer "B.Cu")
		(net "PHY_DPB_TO_SCC_C_13_DP")
	)
	(segment
		(start 97.143062 -53.160168)
		(end 97.2058 -53.222906)
		(width 0.12446)
		(layer "B.Cu")
		(net "PHY_DPB_TO_SCC_C_13_DP")
	)
	(segment
		(start 97.689162 -53.297074)
		(end 98.659696 -53.297074)
		(width 0.12446)
		(layer "B.Cu")
		(net "PHY_DPB_TO_SCC_C_13_DP")
	)
	(segment
		(start 101.000052 -55.31612)
		(end 101.000052 -55.000144)
		(width 0.0889)
		(layer "B.Cu")
		(net "PHY_DPB_TO_SCC_C_13_DP")
	)
	(segment
		(start 99.692714 -55.314596)
		(end 99.692968 -55.314596)
		(width 0.0889)
		(layer "B.Cu")
		(net "PHY_DPB_TO_SCC_C_13_DP")
	)
	(segment
		(start 99.602544 -54.011068)
		(end 99.602544 -55.096664)
		(width 0.0889)
		(layer "B.Cu")
		(net "PHY_DPB_TO_SCC_C_13_DP")
	)
	(arc
		(start 99.692968 -55.314596)
		(mid 99.793058 -55.381537)
		(end 99.911154 -55.40502)
		(width 0.0889)
		(layer "B.Cu")
		(net "PHY_DPB_TO_SCC_C_13_DP")
	)
	(arc
		(start 99.424998 -53.58257)
		(mid 99.556389 -53.779166)
		(end 99.602544 -54.011068)
		(width 0.0889)
		(layer "B.Cu")
		(net "PHY_DPB_TO_SCC_C_13_DP")
	)
	(arc
		(start 99.602798 -55.09641)
		(mid 99.62607 -55.214437)
		(end 99.692714 -55.314596)
		(width 0.0889)
		(layer "B.Cu")
		(net "PHY_DPB_TO_SCC_C_13_DP")
	)
	(arc
		(start 100.911152 -55.40502)
		(mid 100.974014 -55.378982)
		(end 101.000052 -55.31612)
		(width 0.0889)
		(layer "B.Cu")
		(net "PHY_DPB_TO_SCC_C_13_DP")
	)
	(arc
		(start 99.032822 -53.405024)
		(mid 99.231085 -53.444497)
		(end 99.39909 -53.556916)
		(width 0.0889)
		(layer "B.Cu")
		(net "PHY_DPB_TO_SCC_C_13_DP")
	)
	(segment
		(start 101.499924 -56.500014)
		(end 101.000052 -56.000142)
		(width 0.104902)
		(layer "F.Cu")
		(net "PHY_DPB_TO_SCC_C_13_DN")
	)
	(via
		(at 101.000052 -56.000142)
		(size 0.4572)
		(drill 0.2032)
		(layers "F.Cu" "B.Cu")
		(net "PHY_DPB_TO_SCC_C_13_DN")
	)
	(segment
		(start 99.412044 -54.011322)
		(end 99.412044 -55.09641)
		(width 0.0889)
		(layer "B.Cu")
		(net "PHY_DPB_TO_SCC_C_13_DN")
	)
	(segment
		(start 97.143062 -53.744368)
		(end 97.258124 -53.629306)
		(width 0.12446)
		(layer "B.Cu")
		(net "PHY_DPB_TO_SCC_C_13_DN")
	)
	(segment
		(start 98.789744 -53.595524)
		(end 99.032822 -53.595524)
		(width 0.0889)
		(layer "B.Cu")
		(net "PHY_DPB_TO_SCC_C_13_DN")
	)
	(segment
		(start 99.264216 -53.691536)
		(end 99.290124 -53.717444)
		(width 0.0889)
		(layer "B.Cu")
		(net "PHY_DPB_TO_SCC_C_13_DN")
	)
	(segment
		(start 97.52076 -53.703474)
		(end 98.659696 -53.703474)
		(width 0.12446)
		(layer "B.Cu")
		(net "PHY_DPB_TO_SCC_C_13_DN")
	)
	(segment
		(start 98.681794 -53.703474)
		(end 98.789744 -53.595524)
		(width 0.0889)
		(layer "B.Cu")
		(net "PHY_DPB_TO_SCC_C_13_DN")
	)
	(segment
		(start 99.911154 -55.59552)
		(end 100.911152 -55.59552)
		(width 0.0889)
		(layer "B.Cu")
		(net "PHY_DPB_TO_SCC_C_13_DN")
	)
	(segment
		(start 97.258124 -53.629306)
		(end 97.446592 -53.629306)
		(width 0.12446)
		(layer "B.Cu")
		(net "PHY_DPB_TO_SCC_C_13_DN")
	)
	(segment
		(start 97.446592 -53.629306)
		(end 97.52076 -53.703474)
		(width 0.12446)
		(layer "B.Cu")
		(net "PHY_DPB_TO_SCC_C_13_DN")
	)
	(segment
		(start 98.659696 -53.703474)
		(end 98.681794 -53.703474)
		(width 0.0889)
		(layer "B.Cu")
		(net "PHY_DPB_TO_SCC_C_13_DN")
	)
	(segment
		(start 96.776794 -53.744368)
		(end 97.143062 -53.744368)
		(width 0.12446)
		(layer "B.Cu")
		(net "PHY_DPB_TO_SCC_C_13_DN")
	)
	(segment
		(start 101.000052 -55.68442)
		(end 101.000052 -56.000142)
		(width 0.0889)
		(layer "B.Cu")
		(net "PHY_DPB_TO_SCC_C_13_DN")
	)
	(arc
		(start 99.412044 -55.09641)
		(mid 99.449954 -55.287465)
		(end 99.558094 -55.44947)
		(width 0.0889)
		(layer "B.Cu")
		(net "PHY_DPB_TO_SCC_C_13_DN")
	)
	(arc
		(start 99.032822 -53.595524)
		(mid 99.158086 -53.620476)
		(end 99.264216 -53.691536)
		(width 0.0889)
		(layer "B.Cu")
		(net "PHY_DPB_TO_SCC_C_13_DN")
	)
	(arc
		(start 100.911152 -55.59552)
		(mid 100.974014 -55.621558)
		(end 101.000052 -55.68442)
		(width 0.0889)
		(layer "B.Cu")
		(net "PHY_DPB_TO_SCC_C_13_DN")
	)
	(arc
		(start 99.558094 -55.44947)
		(mid 99.720094 -55.557622)
		(end 99.911154 -55.59552)
		(width 0.0889)
		(layer "B.Cu")
		(net "PHY_DPB_TO_SCC_C_13_DN")
	)
	(arc
		(start 99.290124 -53.717444)
		(mid 99.380299 -53.852261)
		(end 99.412044 -54.011322)
		(width 0.0889)
		(layer "B.Cu")
		(net "PHY_DPB_TO_SCC_C_13_DN")
	)
	(segment
		(start 99.499928 -54.500018)
		(end 99.000056 -54.000146)
		(width 0.104902)
		(layer "F.Cu")
		(net "PHY_DPB_TO_SCC_C_12_DP")
	)
	(via
		(at 99.000056 -54.000146)
		(size 0.4572)
		(drill 0.2032)
		(layers "F.Cu" "B.Cu")
		(net "PHY_DPB_TO_SCC_C_12_DP")
	)
	(segment
		(start 97.230184 -54.64429)
		(end 97.143062 -54.557168)
		(width 0.12446)
		(layer "B.Cu")
		(net "PHY_DPB_TO_SCC_C_12_DP")
	)
	(segment
		(start 98.187256 -54.297072)
		(end 97.840038 -54.64429)
		(width 0.12446)
		(layer "B.Cu")
		(net "PHY_DPB_TO_SCC_C_12_DP")
	)
	(segment
		(start 98.866452 -54.297072)
		(end 98.187256 -54.297072)
		(width 0.12446)
		(layer "B.Cu")
		(net "PHY_DPB_TO_SCC_C_12_DP")
	)
	(segment
		(start 97.840038 -54.64429)
		(end 97.230184 -54.64429)
		(width 0.12446)
		(layer "B.Cu")
		(net "PHY_DPB_TO_SCC_C_12_DP")
	)
	(segment
		(start 97.143062 -54.557168)
		(end 96.776794 -54.557168)
		(width 0.12446)
		(layer "B.Cu")
		(net "PHY_DPB_TO_SCC_C_12_DP")
	)
	(segment
		(start 99.000056 -54.000146)
		(end 99.000056 -54.163468)
		(width 0.12446)
		(layer "B.Cu")
		(net "PHY_DPB_TO_SCC_C_12_DP")
	)
	(arc
		(start 99.000056 -54.163468)
		(mid 98.960924 -54.25794)
		(end 98.866452 -54.297072)
		(width 0.12446)
		(layer "B.Cu")
		(net "PHY_DPB_TO_SCC_C_12_DP")
	)
	(segment
		(start 99.499928 -55.500016)
		(end 99.000056 -55.000144)
		(width 0.104902)
		(layer "F.Cu")
		(net "PHY_DPB_TO_SCC_C_12_DN")
	)
	(via
		(at 99.000056 -55.000144)
		(size 0.4572)
		(drill 0.2032)
		(layers "F.Cu" "B.Cu")
		(net "PHY_DPB_TO_SCC_C_12_DN")
	)
	(segment
		(start 98.866452 -54.703472)
		(end 98.355658 -54.703472)
		(width 0.12446)
		(layer "B.Cu")
		(net "PHY_DPB_TO_SCC_C_12_DN")
	)
	(segment
		(start 98.00844 -55.05069)
		(end 97.23374 -55.05069)
		(width 0.12446)
		(layer "B.Cu")
		(net "PHY_DPB_TO_SCC_C_12_DN")
	)
	(segment
		(start 97.143062 -55.141368)
		(end 96.776794 -55.141368)
		(width 0.12446)
		(layer "B.Cu")
		(net "PHY_DPB_TO_SCC_C_12_DN")
	)
	(segment
		(start 98.355658 -54.703472)
		(end 98.00844 -55.05069)
		(width 0.12446)
		(layer "B.Cu")
		(net "PHY_DPB_TO_SCC_C_12_DN")
	)
	(segment
		(start 99.000056 -55.000144)
		(end 99.000056 -54.837076)
		(width 0.12446)
		(layer "B.Cu")
		(net "PHY_DPB_TO_SCC_C_12_DN")
	)
	(segment
		(start 97.23374 -55.05069)
		(end 97.143062 -55.141368)
		(width 0.12446)
		(layer "B.Cu")
		(net "PHY_DPB_TO_SCC_C_12_DN")
	)
	(arc
		(start 99.000056 -54.837076)
		(mid 98.960924 -54.742604)
		(end 98.866452 -54.703472)
		(width 0.12446)
		(layer "B.Cu")
		(net "PHY_DPB_TO_SCC_C_12_DN")
	)
	(segment
		(start 92.498672 -24.78913)
		(end 92.420948 -24.423878)
		(width 0.12446)
		(layer "B.Cu")
		(net "PHY_DPB_TO_SCC_15_DP")
	)
	(segment
		(start 93.86697 -46.926754)
		(end 93.66377 -46.613572)
		(width 0.12446)
		(layer "B.Cu")
		(net "PHY_DPB_TO_SCC_15_DP")
	)
	(segment
		(start 90.936572 -3.503168)
		(end 91.280996 -3.503168)
		(width 0.12446)
		(layer "B.Cu")
		(net "PHY_DPB_TO_SCC_15_DP")
	)
	(segment
		(start 92.955364 -26.938224)
		(end 93.162882 -26.618946)
		(width 0.12446)
		(layer "B.Cu")
		(net "PHY_DPB_TO_SCC_15_DP")
	)
	(segment
		(start 92.550742 -23.739348)
		(end 92.231464 -23.532084)
		(width 0.12446)
		(layer "B.Cu")
		(net "PHY_DPB_TO_SCC_15_DP")
	)
	(segment
		(start 94.363286 -47.691802)
		(end 93.990922 -47.6123)
		(width 0.12446)
		(layer "B.Cu")
		(net "PHY_DPB_TO_SCC_15_DP")
	)
	(segment
		(start 94.566486 -48.004984)
		(end 94.363286 -47.691802)
		(width 0.12446)
		(layer "B.Cu")
		(net "PHY_DPB_TO_SCC_15_DP")
	)
	(segment
		(start 93.990922 -47.6123)
		(end 93.787722 -47.299118)
		(width 0.12446)
		(layer "B.Cu")
		(net "PHY_DPB_TO_SCC_15_DP")
	)
	(segment
		(start 93.206062 -28.117546)
		(end 92.955364 -26.938224)
		(width 0.12446)
		(layer "B.Cu")
		(net "PHY_DPB_TO_SCC_15_DP")
	)
	(segment
		(start 95.489268 -50.409094)
		(end 95.370396 -50.290222)
		(width 0.12446)
		(layer "B.Cu")
		(net "PHY_DPB_TO_SCC_15_DP")
	)
	(segment
		(start 95.851726 -50.366168)
		(end 95.8088 -50.409094)
		(width 0.12446)
		(layer "B.Cu")
		(net "PHY_DPB_TO_SCC_15_DP")
	)
	(segment
		(start 92.895674 -25.361646)
		(end 92.81795 -24.996394)
		(width 0.12446)
		(layer "B.Cu")
		(net "PHY_DPB_TO_SCC_15_DP")
	)
	(segment
		(start 95.8088 -50.409094)
		(end 95.489268 -50.409094)
		(width 0.12446)
		(layer "B.Cu")
		(net "PHY_DPB_TO_SCC_15_DP")
	)
	(segment
		(start 93.787722 -47.299118)
		(end 93.86697 -46.926754)
		(width 0.12446)
		(layer "B.Cu")
		(net "PHY_DPB_TO_SCC_15_DP")
	)
	(segment
		(start 92.01912 -44.573444)
		(end 90.864944 -39.140892)
		(width 0.12446)
		(layer "B.Cu")
		(net "PHY_DPB_TO_SCC_15_DP")
	)
	(segment
		(start 96.217994 -50.366168)
		(end 95.851726 -50.366168)
		(width 0.12446)
		(layer "B.Cu")
		(net "PHY_DPB_TO_SCC_15_DP")
	)
	(segment
		(start 92.655136 -45.55363)
		(end 92.01912 -44.573444)
		(width 0.12446)
		(layer "B.Cu")
		(net "PHY_DPB_TO_SCC_15_DP")
	)
	(segment
		(start 93.66377 -46.613572)
		(end 93.291406 -46.53407)
		(width 0.12446)
		(layer "B.Cu")
		(net "PHY_DPB_TO_SCC_15_DP")
	)
	(segment
		(start 92.688156 -25.680924)
		(end 92.895674 -25.361646)
		(width 0.12446)
		(layer "B.Cu")
		(net "PHY_DPB_TO_SCC_15_DP")
	)
	(segment
		(start 92.361258 -22.8473)
		(end 92.283534 -22.482302)
		(width 0.12446)
		(layer "B.Cu")
		(net "PHY_DPB_TO_SCC_15_DP")
	)
	(segment
		(start 93.085158 -26.253694)
		(end 92.76588 -26.046176)
		(width 0.12446)
		(layer "B.Cu")
		(net "PHY_DPB_TO_SCC_15_DP")
	)
	(segment
		(start 92.15374 -23.166832)
		(end 92.361258 -22.8473)
		(width 0.12446)
		(layer "B.Cu")
		(net "PHY_DPB_TO_SCC_15_DP")
	)
	(segment
		(start 93.291406 -46.53407)
		(end 92.655136 -45.55363)
		(width 0.12446)
		(layer "B.Cu")
		(net "PHY_DPB_TO_SCC_15_DP")
	)
	(segment
		(start 90.7034 -16.343122)
		(end 90.7034 -3.73634)
		(width 0.12446)
		(layer "B.Cu")
		(net "PHY_DPB_TO_SCC_15_DP")
	)
	(segment
		(start 95.370396 -50.290222)
		(end 95.370396 -49.738534)
		(width 0.12446)
		(layer "B.Cu")
		(net "PHY_DPB_TO_SCC_15_DP")
	)
	(segment
		(start 91.400122 -3.622294)
		(end 91.400122 -3.999992)
		(width 0.12446)
		(layer "B.Cu")
		(net "PHY_DPB_TO_SCC_15_DP")
	)
	(segment
		(start 95.370396 -49.738534)
		(end 95.100394 -49.322482)
		(width 0.12446)
		(layer "B.Cu")
		(net "PHY_DPB_TO_SCC_15_DP")
	)
	(segment
		(start 93.162882 -26.618946)
		(end 93.085158 -26.253694)
		(width 0.12446)
		(layer "B.Cu")
		(net "PHY_DPB_TO_SCC_15_DP")
	)
	(segment
		(start 92.231464 -23.532084)
		(end 92.15374 -23.166832)
		(width 0.12446)
		(layer "B.Cu")
		(net "PHY_DPB_TO_SCC_15_DP")
	)
	(segment
		(start 95.100394 -49.322482)
		(end 94.896178 -49.007776)
		(width 0.12446)
		(layer "B.Cu")
		(net "PHY_DPB_TO_SCC_15_DP")
	)
	(segment
		(start 92.628466 -24.1046)
		(end 92.550742 -23.739348)
		(width 0.12446)
		(layer "B.Cu")
		(net "PHY_DPB_TO_SCC_15_DP")
	)
	(segment
		(start 92.76588 -26.046176)
		(end 92.688156 -25.680924)
		(width 0.12446)
		(layer "B.Cu")
		(net "PHY_DPB_TO_SCC_15_DP")
	)
	(segment
		(start 91.964256 -22.274784)
		(end 90.7034 -16.343122)
		(width 0.12446)
		(layer "B.Cu")
		(net "PHY_DPB_TO_SCC_15_DP")
	)
	(segment
		(start 90.864944 -39.140892)
		(end 93.206062 -28.117546)
		(width 0.12446)
		(layer "B.Cu")
		(net "PHY_DPB_TO_SCC_15_DP")
	)
	(segment
		(start 92.420948 -24.423878)
		(end 92.628466 -24.1046)
		(width 0.12446)
		(layer "B.Cu")
		(net "PHY_DPB_TO_SCC_15_DP")
	)
	(segment
		(start 92.283534 -22.482302)
		(end 91.964256 -22.274784)
		(width 0.12446)
		(layer "B.Cu")
		(net "PHY_DPB_TO_SCC_15_DP")
	)
	(segment
		(start 92.81795 -24.996394)
		(end 92.498672 -24.78913)
		(width 0.12446)
		(layer "B.Cu")
		(net "PHY_DPB_TO_SCC_15_DP")
	)
	(segment
		(start 94.487238 -48.377348)
		(end 94.566486 -48.004984)
		(width 0.12446)
		(layer "B.Cu")
		(net "PHY_DPB_TO_SCC_15_DP")
	)
	(segment
		(start 94.896178 -49.007776)
		(end 94.487238 -48.377348)
		(width 0.12446)
		(layer "B.Cu")
		(net "PHY_DPB_TO_SCC_15_DP")
	)
	(arc
		(start 91.365324 -3.53822)
		(mid 91.391098 -3.576793)
		(end 91.400122 -3.622294)
		(width 0.12446)
		(layer "B.Cu")
		(net "PHY_DPB_TO_SCC_15_DP")
	)
	(arc
		(start 91.280996 -3.503168)
		(mid 91.326652 -3.512285)
		(end 91.365324 -3.53822)
		(width 0.12446)
		(layer "B.Cu")
		(net "PHY_DPB_TO_SCC_15_DP")
	)
	(arc
		(start 90.7034 -3.73634)
		(mid 90.771694 -3.571462)
		(end 90.936572 -3.503168)
		(width 0.12446)
		(layer "B.Cu")
		(net "PHY_DPB_TO_SCC_15_DP")
	)
	(segment
		(start 96.217994 -50.950368)
		(end 95.936054 -50.950368)
		(width 0.12446)
		(layer "B.Cu")
		(net "PHY_DPB_TO_SCC_15_DN")
	)
	(segment
		(start 94.963996 -49.85893)
		(end 91.637104 -44.731686)
		(width 0.12446)
		(layer "B.Cu")
		(net "PHY_DPB_TO_SCC_15_DN")
	)
	(segment
		(start 95.936054 -50.950368)
		(end 95.80118 -50.815494)
		(width 0.12446)
		(layer "B.Cu")
		(net "PHY_DPB_TO_SCC_15_DN")
	)
	(segment
		(start 90.4494 -39.140892)
		(end 92.790518 -28.117546)
		(width 0.12446)
		(layer "B.Cu")
		(net "PHY_DPB_TO_SCC_15_DN")
	)
	(segment
		(start 95.80118 -50.815494)
		(end 95.320866 -50.815494)
		(width 0.12446)
		(layer "B.Cu")
		(net "PHY_DPB_TO_SCC_15_DN")
	)
	(segment
		(start 91.637104 -44.731686)
		(end 90.4494 -39.140892)
		(width 0.12446)
		(layer "B.Cu")
		(net "PHY_DPB_TO_SCC_15_DN")
	)
	(segment
		(start 94.963996 -50.458624)
		(end 94.963996 -49.85893)
		(width 0.12446)
		(layer "B.Cu")
		(net "PHY_DPB_TO_SCC_15_DN")
	)
	(segment
		(start 92.790518 -28.117546)
		(end 90.297 -16.386048)
		(width 0.12446)
		(layer "B.Cu")
		(net "PHY_DPB_TO_SCC_15_DN")
	)
	(segment
		(start 91.400122 -2.977642)
		(end 91.400122 -2.600198)
		(width 0.12446)
		(layer "B.Cu")
		(net "PHY_DPB_TO_SCC_15_DN")
	)
	(segment
		(start 90.297 -16.386048)
		(end 90.297 -3.73634)
		(width 0.12446)
		(layer "B.Cu")
		(net "PHY_DPB_TO_SCC_15_DN")
	)
	(segment
		(start 95.320866 -50.815494)
		(end 94.963996 -50.458624)
		(width 0.12446)
		(layer "B.Cu")
		(net "PHY_DPB_TO_SCC_15_DN")
	)
	(segment
		(start 90.936572 -3.096768)
		(end 91.280996 -3.096768)
		(width 0.12446)
		(layer "B.Cu")
		(net "PHY_DPB_TO_SCC_15_DN")
	)
	(arc
		(start 91.365324 -3.061716)
		(mid 91.391098 -3.023143)
		(end 91.400122 -2.977642)
		(width 0.12446)
		(layer "B.Cu")
		(net "PHY_DPB_TO_SCC_15_DN")
	)
	(arc
		(start 91.280996 -3.096768)
		(mid 91.326652 -3.087651)
		(end 91.365324 -3.061716)
		(width 0.12446)
		(layer "B.Cu")
		(net "PHY_DPB_TO_SCC_15_DN")
	)
	(arc
		(start 90.297 -3.73634)
		(mid 90.484326 -3.284094)
		(end 90.936572 -3.096768)
		(width 0.12446)
		(layer "B.Cu")
		(net "PHY_DPB_TO_SCC_15_DN")
	)
	(segment
		(start 90.336624 -21.565108)
		(end 90.414348 -21.930106)
		(width 0.12446)
		(layer "B.Cu")
		(net "PHY_DPB_TO_SCC_14_DP")
	)
	(segment
		(start 89.256362 -39.991792)
		(end 89.881456 -40.953944)
		(width 0.12446)
		(layer "B.Cu")
		(net "PHY_DPB_TO_SCC_14_DP")
	)
	(segment
		(start 90.87104 -24.0792)
		(end 90.948764 -24.444452)
		(width 0.12446)
		(layer "B.Cu")
		(net "PHY_DPB_TO_SCC_14_DP")
	)
	(segment
		(start 90.284554 -22.61489)
		(end 90.603832 -22.822154)
		(width 0.12446)
		(layer "B.Cu")
		(net "PHY_DPB_TO_SCC_14_DP")
	)
	(segment
		(start 90.474038 -23.506684)
		(end 90.551762 -23.871936)
		(width 0.12446)
		(layer "B.Cu")
		(net "PHY_DPB_TO_SCC_14_DP")
	)
	(segment
		(start 91.635326 -48.49876)
		(end 92.00769 -48.5775)
		(width 0.12446)
		(layer "B.Cu")
		(net "PHY_DPB_TO_SCC_14_DP")
	)
	(segment
		(start 92.70873 -49.654714)
		(end 92.912438 -49.967642)
		(width 0.12446)
		(layer "B.Cu")
		(net "PHY_DPB_TO_SCC_14_DP")
	)
	(segment
		(start 89.600024 -5.200142)
		(end 89.600024 -4.822444)
		(width 0.12446)
		(layer "B.Cu")
		(net "PHY_DPB_TO_SCC_14_DP")
	)
	(segment
		(start 91.215972 -25.701752)
		(end 91.008454 -26.02103)
		(width 0.12446)
		(layer "B.Cu")
		(net "PHY_DPB_TO_SCC_14_DP")
	)
	(segment
		(start 90.551762 -23.871936)
		(end 90.87104 -24.0792)
		(width 0.12446)
		(layer "B.Cu")
		(net "PHY_DPB_TO_SCC_14_DP")
	)
	(segment
		(start 90.681556 -23.187406)
		(end 90.474038 -23.506684)
		(width 0.12446)
		(layer "B.Cu")
		(net "PHY_DPB_TO_SCC_14_DP")
	)
	(segment
		(start 92.336112 -49.575974)
		(end 92.70873 -49.654714)
		(width 0.12446)
		(layer "B.Cu")
		(net "PHY_DPB_TO_SCC_14_DP")
	)
	(segment
		(start 90.414348 -21.930106)
		(end 90.20683 -22.249638)
		(width 0.12446)
		(layer "B.Cu")
		(net "PHY_DPB_TO_SCC_14_DP")
	)
	(segment
		(start 90.017346 -21.35759)
		(end 90.336624 -21.565108)
		(width 0.12446)
		(layer "B.Cu")
		(net "PHY_DPB_TO_SCC_14_DP")
	)
	(segment
		(start 95.788226 -51.813968)
		(end 95.839026 -51.763168)
		(width 0.12446)
		(layer "B.Cu")
		(net "PHY_DPB_TO_SCC_14_DP")
	)
	(segment
		(start 95.839026 -51.763168)
		(end 96.217994 -51.763168)
		(width 0.12446)
		(layer "B.Cu")
		(net "PHY_DPB_TO_SCC_14_DP")
	)
	(segment
		(start 92.957396 -50.53076)
		(end 94.933008 -51.813968)
		(width 0.12446)
		(layer "B.Cu")
		(net "PHY_DPB_TO_SCC_14_DP")
	)
	(segment
		(start 89.037414 -38.960044)
		(end 89.256362 -39.991792)
		(width 0.12446)
		(layer "B.Cu")
		(net "PHY_DPB_TO_SCC_14_DP")
	)
	(segment
		(start 90.81897 -25.128982)
		(end 91.138248 -25.3365)
		(width 0.12446)
		(layer "B.Cu")
		(net "PHY_DPB_TO_SCC_14_DP")
	)
	(segment
		(start 91.414092 -48.158654)
		(end 91.635326 -48.49876)
		(width 0.12446)
		(layer "B.Cu")
		(net "PHY_DPB_TO_SCC_14_DP")
	)
	(segment
		(start 89.480898 -4.703318)
		(end 89.06129 -4.703318)
		(width 0.12446)
		(layer "B.Cu")
		(net "PHY_DPB_TO_SCC_14_DP")
	)
	(segment
		(start 92.912438 -49.967642)
		(end 92.833444 -50.34026)
		(width 0.12446)
		(layer "B.Cu")
		(net "PHY_DPB_TO_SCC_14_DP")
	)
	(segment
		(start 89.881456 -40.953944)
		(end 91.414092 -48.158654)
		(width 0.12446)
		(layer "B.Cu")
		(net "PHY_DPB_TO_SCC_14_DP")
	)
	(segment
		(start 88.903302 -16.116554)
		(end 90.017346 -21.35759)
		(width 0.12446)
		(layer "B.Cu")
		(net "PHY_DPB_TO_SCC_14_DP")
	)
	(segment
		(start 92.00769 -48.5775)
		(end 92.211398 -48.890428)
		(width 0.12446)
		(layer "B.Cu")
		(net "PHY_DPB_TO_SCC_14_DP")
	)
	(segment
		(start 91.138248 -25.3365)
		(end 91.215972 -25.701752)
		(width 0.12446)
		(layer "B.Cu")
		(net "PHY_DPB_TO_SCC_14_DP")
	)
	(segment
		(start 88.903302 -4.861306)
		(end 88.903302 -16.116554)
		(width 0.12446)
		(layer "B.Cu")
		(net "PHY_DPB_TO_SCC_14_DP")
	)
	(segment
		(start 90.948764 -24.444452)
		(end 90.741246 -24.76373)
		(width 0.12446)
		(layer "B.Cu")
		(net "PHY_DPB_TO_SCC_14_DP")
	)
	(segment
		(start 90.741246 -24.76373)
		(end 90.81897 -25.128982)
		(width 0.12446)
		(layer "B.Cu")
		(net "PHY_DPB_TO_SCC_14_DP")
	)
	(segment
		(start 91.008454 -26.02103)
		(end 91.39809 -27.854148)
		(width 0.12446)
		(layer "B.Cu")
		(net "PHY_DPB_TO_SCC_14_DP")
	)
	(segment
		(start 91.39809 -27.854148)
		(end 89.037414 -38.960044)
		(width 0.12446)
		(layer "B.Cu")
		(net "PHY_DPB_TO_SCC_14_DP")
	)
	(segment
		(start 92.211398 -48.890428)
		(end 92.132404 -49.263046)
		(width 0.12446)
		(layer "B.Cu")
		(net "PHY_DPB_TO_SCC_14_DP")
	)
	(segment
		(start 92.833444 -50.34026)
		(end 92.957396 -50.53076)
		(width 0.12446)
		(layer "B.Cu")
		(net "PHY_DPB_TO_SCC_14_DP")
	)
	(segment
		(start 90.20683 -22.249638)
		(end 90.284554 -22.61489)
		(width 0.12446)
		(layer "B.Cu")
		(net "PHY_DPB_TO_SCC_14_DP")
	)
	(segment
		(start 92.132404 -49.263046)
		(end 92.336112 -49.575974)
		(width 0.12446)
		(layer "B.Cu")
		(net "PHY_DPB_TO_SCC_14_DP")
	)
	(segment
		(start 90.603832 -22.822154)
		(end 90.681556 -23.187406)
		(width 0.12446)
		(layer "B.Cu")
		(net "PHY_DPB_TO_SCC_14_DP")
	)
	(segment
		(start 94.933008 -51.813968)
		(end 95.788226 -51.813968)
		(width 0.12446)
		(layer "B.Cu")
		(net "PHY_DPB_TO_SCC_14_DP")
	)
	(arc
		(start 89.600024 -4.822444)
		(mid 89.590975 -4.776954)
		(end 89.565226 -4.73837)
		(width 0.12446)
		(layer "B.Cu")
		(net "PHY_DPB_TO_SCC_14_DP")
	)
	(arc
		(start 89.565226 -4.73837)
		(mid 89.526565 -4.71241)
		(end 89.480898 -4.703318)
		(width 0.12446)
		(layer "B.Cu")
		(net "PHY_DPB_TO_SCC_14_DP")
	)
	(arc
		(start 89.06129 -4.703318)
		(mid 88.949576 -4.749592)
		(end 88.903302 -4.861306)
		(width 0.12446)
		(layer "B.Cu")
		(net "PHY_DPB_TO_SCC_14_DP")
	)
	(segment
		(start 92.49283 -50.562002)
		(end 92.663518 -50.824892)
		(width 0.12446)
		(layer "B.Cu")
		(net "PHY_DPB_TO_SCC_14_DN")
	)
	(segment
		(start 91.016328 -48.243236)
		(end 91.032076 -48.31715)
		(width 0.12446)
		(layer "B.Cu")
		(net "PHY_DPB_TO_SCC_14_DN")
	)
	(segment
		(start 88.874346 -40.150034)
		(end 89.49944 -41.112186)
		(width 0.12446)
		(layer "B.Cu")
		(net "PHY_DPB_TO_SCC_14_DN")
	)
	(segment
		(start 88.496902 -16.15948)
		(end 90.982546 -27.854148)
		(width 0.12446)
		(layer "B.Cu")
		(net "PHY_DPB_TO_SCC_14_DN")
	)
	(segment
		(start 88.62187 -38.960044)
		(end 88.874346 -40.150034)
		(width 0.12446)
		(layer "B.Cu")
		(net "PHY_DPB_TO_SCC_14_DN")
	)
	(segment
		(start 92.492576 -50.562256)
		(end 92.49283 -50.562002)
		(width 0.12446)
		(layer "B.Cu")
		(net "PHY_DPB_TO_SCC_14_DN")
	)
	(segment
		(start 91.016582 -48.243236)
		(end 91.016328 -48.243236)
		(width 0.12446)
		(layer "B.Cu")
		(net "PHY_DPB_TO_SCC_14_DN")
	)
	(segment
		(start 89.600024 -3.800094)
		(end 89.600024 -4.177792)
		(width 0.12446)
		(layer "B.Cu")
		(net "PHY_DPB_TO_SCC_14_DN")
	)
	(segment
		(start 95.737426 -52.220368)
		(end 95.864426 -52.347368)
		(width 0.12446)
		(layer "B.Cu")
		(net "PHY_DPB_TO_SCC_14_DN")
	)
	(segment
		(start 91.032076 -48.31715)
		(end 92.492576 -50.562256)
		(width 0.12446)
		(layer "B.Cu")
		(net "PHY_DPB_TO_SCC_14_DN")
	)
	(segment
		(start 94.812612 -52.220368)
		(end 95.737426 -52.220368)
		(width 0.12446)
		(layer "B.Cu")
		(net "PHY_DPB_TO_SCC_14_DN")
	)
	(segment
		(start 92.663518 -50.824892)
		(end 94.812612 -52.220368)
		(width 0.12446)
		(layer "B.Cu")
		(net "PHY_DPB_TO_SCC_14_DN")
	)
	(segment
		(start 90.982546 -27.854148)
		(end 88.62187 -38.960044)
		(width 0.12446)
		(layer "B.Cu")
		(net "PHY_DPB_TO_SCC_14_DN")
	)
	(segment
		(start 95.864426 -52.347368)
		(end 96.217994 -52.347368)
		(width 0.12446)
		(layer "B.Cu")
		(net "PHY_DPB_TO_SCC_14_DN")
	)
	(segment
		(start 88.496902 -4.861306)
		(end 88.496902 -16.15948)
		(width 0.12446)
		(layer "B.Cu")
		(net "PHY_DPB_TO_SCC_14_DN")
	)
	(segment
		(start 89.480898 -4.296918)
		(end 89.06129 -4.296918)
		(width 0.12446)
		(layer "B.Cu")
		(net "PHY_DPB_TO_SCC_14_DN")
	)
	(segment
		(start 89.49944 -41.112186)
		(end 91.016582 -48.243236)
		(width 0.12446)
		(layer "B.Cu")
		(net "PHY_DPB_TO_SCC_14_DN")
	)
	(arc
		(start 89.565226 -4.261866)
		(mid 89.526565 -4.287826)
		(end 89.480898 -4.296918)
		(width 0.12446)
		(layer "B.Cu")
		(net "PHY_DPB_TO_SCC_14_DN")
	)
	(arc
		(start 89.06129 -4.296918)
		(mid 88.662207 -4.462223)
		(end 88.496902 -4.861306)
		(width 0.12446)
		(layer "B.Cu")
		(net "PHY_DPB_TO_SCC_14_DN")
	)
	(arc
		(start 89.600024 -4.177792)
		(mid 89.590975 -4.223282)
		(end 89.565226 -4.261866)
		(width 0.12446)
		(layer "B.Cu")
		(net "PHY_DPB_TO_SCC_14_DN")
	)
	(segment
		(start 87.80018 -3.999992)
		(end 87.80018 -3.622294)
		(width 0.12446)
		(layer "B.Cu")
		(net "PHY_DPB_TO_SCC_13_DP")
	)
	(segment
		(start 87.36203 -39.392098)
		(end 87.681308 -39.599362)
		(width 0.12446)
		(layer "B.Cu")
		(net "PHY_DPB_TO_SCC_13_DP")
	)
	(segment
		(start 87.818976 -41.541192)
		(end 89.031064 -47.240444)
		(width 0.12446)
		(layer "B.Cu")
		(net "PHY_DPB_TO_SCC_13_DP")
	)
	(segment
		(start 89.002108 -24.265636)
		(end 88.79459 -24.584914)
		(width 0.12446)
		(layer "B.Cu")
		(net "PHY_DPB_TO_SCC_13_DP")
	)
	(segment
		(start 89.4588 -26.41473)
		(end 89.536524 -26.779728)
		(width 0.12446)
		(layer "B.Cu")
		(net "PHY_DPB_TO_SCC_13_DP")
	)
	(segment
		(start 88.337898 -22.43582)
		(end 88.657176 -22.643084)
		(width 0.12446)
		(layer "B.Cu")
		(net "PHY_DPB_TO_SCC_13_DP")
	)
	(segment
		(start 87.629238 -40.649144)
		(end 87.94877 -40.856408)
		(width 0.12446)
		(layer "B.Cu")
		(net "PHY_DPB_TO_SCC_13_DP")
	)
	(segment
		(start 88.734646 -23.008336)
		(end 88.527382 -23.327614)
		(width 0.12446)
		(layer "B.Cu")
		(net "PHY_DPB_TO_SCC_13_DP")
	)
	(segment
		(start 91.59875 -51.194462)
		(end 94.473776 -53.061616)
		(width 0.12446)
		(layer "B.Cu")
		(net "PHY_DPB_TO_SCC_13_DP")
	)
	(segment
		(start 88.872314 -24.950166)
		(end 89.191592 -25.15743)
		(width 0.12446)
		(layer "B.Cu")
		(net "PHY_DPB_TO_SCC_13_DP")
	)
	(segment
		(start 87.103458 -3.73634)
		(end 87.103458 -16.628364)
		(width 0.12446)
		(layer "B.Cu")
		(net "PHY_DPB_TO_SCC_13_DP")
	)
	(segment
		(start 89.329006 -27.09926)
		(end 89.574116 -28.252166)
		(width 0.12446)
		(layer "B.Cu")
		(net "PHY_DPB_TO_SCC_13_DP")
	)
	(segment
		(start 89.574116 -28.252166)
		(end 87.284306 -39.026846)
		(width 0.12446)
		(layer "B.Cu")
		(net "PHY_DPB_TO_SCC_13_DP")
	)
	(segment
		(start 89.139522 -26.207212)
		(end 89.4588 -26.41473)
		(width 0.12446)
		(layer "B.Cu")
		(net "PHY_DPB_TO_SCC_13_DP")
	)
	(segment
		(start 89.061798 -25.84196)
		(end 89.139522 -26.207212)
		(width 0.12446)
		(layer "B.Cu")
		(net "PHY_DPB_TO_SCC_13_DP")
	)
	(segment
		(start 89.191592 -25.15743)
		(end 89.269316 -25.522682)
		(width 0.12446)
		(layer "B.Cu")
		(net "PHY_DPB_TO_SCC_13_DP")
	)
	(segment
		(start 89.031064 -47.240444)
		(end 91.59875 -51.194462)
		(width 0.12446)
		(layer "B.Cu")
		(net "PHY_DPB_TO_SCC_13_DP")
	)
	(segment
		(start 95.839026 -53.160168)
		(end 96.217994 -53.160168)
		(width 0.12446)
		(layer "B.Cu")
		(net "PHY_DPB_TO_SCC_13_DP")
	)
	(segment
		(start 89.269316 -25.522682)
		(end 89.061798 -25.84196)
		(width 0.12446)
		(layer "B.Cu")
		(net "PHY_DPB_TO_SCC_13_DP")
	)
	(segment
		(start 87.681308 -39.599362)
		(end 87.759032 -39.964614)
		(width 0.12446)
		(layer "B.Cu")
		(net "PHY_DPB_TO_SCC_13_DP")
	)
	(segment
		(start 88.02624 -41.22166)
		(end 87.818976 -41.541192)
		(width 0.12446)
		(layer "B.Cu")
		(net "PHY_DPB_TO_SCC_13_DP")
	)
	(segment
		(start 87.551768 -40.283892)
		(end 87.629238 -40.649144)
		(width 0.12446)
		(layer "B.Cu")
		(net "PHY_DPB_TO_SCC_13_DP")
	)
	(segment
		(start 94.473776 -53.061616)
		(end 95.17761 -53.210968)
		(width 0.12446)
		(layer "B.Cu")
		(net "PHY_DPB_TO_SCC_13_DP")
	)
	(segment
		(start 95.788226 -53.210968)
		(end 95.839026 -53.160168)
		(width 0.12446)
		(layer "B.Cu")
		(net "PHY_DPB_TO_SCC_13_DP")
	)
	(segment
		(start 88.657176 -22.643084)
		(end 88.734646 -23.008336)
		(width 0.12446)
		(layer "B.Cu")
		(net "PHY_DPB_TO_SCC_13_DP")
	)
	(segment
		(start 88.924384 -23.900384)
		(end 89.002108 -24.265636)
		(width 0.12446)
		(layer "B.Cu")
		(net "PHY_DPB_TO_SCC_13_DP")
	)
	(segment
		(start 88.605106 -23.692866)
		(end 88.924384 -23.900384)
		(width 0.12446)
		(layer "B.Cu")
		(net "PHY_DPB_TO_SCC_13_DP")
	)
	(segment
		(start 87.103458 -16.628364)
		(end 88.337898 -22.43582)
		(width 0.12446)
		(layer "B.Cu")
		(net "PHY_DPB_TO_SCC_13_DP")
	)
	(segment
		(start 88.79459 -24.584914)
		(end 88.872314 -24.950166)
		(width 0.12446)
		(layer "B.Cu")
		(net "PHY_DPB_TO_SCC_13_DP")
	)
	(segment
		(start 95.17761 -53.210968)
		(end 95.788226 -53.210968)
		(width 0.12446)
		(layer "B.Cu")
		(net "PHY_DPB_TO_SCC_13_DP")
	)
	(segment
		(start 87.681054 -3.503168)
		(end 87.33663 -3.503168)
		(width 0.12446)
		(layer "B.Cu")
		(net "PHY_DPB_TO_SCC_13_DP")
	)
	(segment
		(start 87.759032 -39.964614)
		(end 87.551768 -40.283892)
		(width 0.12446)
		(layer "B.Cu")
		(net "PHY_DPB_TO_SCC_13_DP")
	)
	(segment
		(start 87.284306 -39.026846)
		(end 87.36203 -39.392098)
		(width 0.12446)
		(layer "B.Cu")
		(net "PHY_DPB_TO_SCC_13_DP")
	)
	(segment
		(start 89.536524 -26.779728)
		(end 89.329006 -27.09926)
		(width 0.12446)
		(layer "B.Cu")
		(net "PHY_DPB_TO_SCC_13_DP")
	)
	(segment
		(start 88.527382 -23.327614)
		(end 88.605106 -23.692866)
		(width 0.12446)
		(layer "B.Cu")
		(net "PHY_DPB_TO_SCC_13_DP")
	)
	(segment
		(start 87.94877 -40.856408)
		(end 88.02624 -41.22166)
		(width 0.12446)
		(layer "B.Cu")
		(net "PHY_DPB_TO_SCC_13_DP")
	)
	(arc
		(start 87.33663 -3.503168)
		(mid 87.171752 -3.571462)
		(end 87.103458 -3.73634)
		(width 0.12446)
		(layer "B.Cu")
		(net "PHY_DPB_TO_SCC_13_DP")
	)
	(arc
		(start 87.765382 -3.53822)
		(mid 87.726721 -3.51226)
		(end 87.681054 -3.503168)
		(width 0.12446)
		(layer "B.Cu")
		(net "PHY_DPB_TO_SCC_13_DP")
	)
	(arc
		(start 87.80018 -3.622294)
		(mid 87.791131 -3.576804)
		(end 87.765382 -3.53822)
		(width 0.12446)
		(layer "B.Cu")
		(net "PHY_DPB_TO_SCC_13_DP")
	)
	(segment
		(start 95.737426 -53.617368)
		(end 95.134938 -53.617368)
		(width 0.12446)
		(layer "B.Cu")
		(net "PHY_DPB_TO_SCC_13_DN")
	)
	(segment
		(start 89.158572 -28.252166)
		(end 86.697058 -16.67129)
		(width 0.12446)
		(layer "B.Cu")
		(net "PHY_DPB_TO_SCC_13_DN")
	)
	(segment
		(start 96.217994 -53.744368)
		(end 95.864426 -53.744368)
		(width 0.12446)
		(layer "B.Cu")
		(net "PHY_DPB_TO_SCC_13_DN")
	)
	(segment
		(start 95.864426 -53.744368)
		(end 95.737426 -53.617368)
		(width 0.12446)
		(layer "B.Cu")
		(net "PHY_DPB_TO_SCC_13_DN")
	)
	(segment
		(start 95.134938 -53.617368)
		(end 94.315788 -53.443632)
		(width 0.12446)
		(layer "B.Cu")
		(net "PHY_DPB_TO_SCC_13_DN")
	)
	(segment
		(start 88.649048 -47.398686)
		(end 86.868762 -39.026846)
		(width 0.12446)
		(layer "B.Cu")
		(net "PHY_DPB_TO_SCC_13_DN")
	)
	(segment
		(start 91.304872 -51.48834)
		(end 88.649048 -47.398686)
		(width 0.12446)
		(layer "B.Cu")
		(net "PHY_DPB_TO_SCC_13_DN")
	)
	(segment
		(start 86.868762 -39.026846)
		(end 89.158572 -28.252166)
		(width 0.12446)
		(layer "B.Cu")
		(net "PHY_DPB_TO_SCC_13_DN")
	)
	(segment
		(start 86.697058 -16.67129)
		(end 86.697058 -3.73634)
		(width 0.12446)
		(layer "B.Cu")
		(net "PHY_DPB_TO_SCC_13_DN")
	)
	(segment
		(start 94.315788 -53.443632)
		(end 91.304872 -51.48834)
		(width 0.12446)
		(layer "B.Cu")
		(net "PHY_DPB_TO_SCC_13_DN")
	)
	(segment
		(start 87.33663 -3.096768)
		(end 87.681054 -3.096768)
		(width 0.12446)
		(layer "B.Cu")
		(net "PHY_DPB_TO_SCC_13_DN")
	)
	(segment
		(start 87.80018 -2.977642)
		(end 87.80018 -2.600198)
		(width 0.12446)
		(layer "B.Cu")
		(net "PHY_DPB_TO_SCC_13_DN")
	)
	(arc
		(start 87.765382 -3.061716)
		(mid 87.791156 -3.023143)
		(end 87.80018 -2.977642)
		(width 0.12446)
		(layer "B.Cu")
		(net "PHY_DPB_TO_SCC_13_DN")
	)
	(arc
		(start 86.697058 -3.73634)
		(mid 86.884384 -3.284094)
		(end 87.33663 -3.096768)
		(width 0.12446)
		(layer "B.Cu")
		(net "PHY_DPB_TO_SCC_13_DN")
	)
	(arc
		(start 87.681054 -3.096768)
		(mid 87.72671 -3.087651)
		(end 87.765382 -3.061716)
		(width 0.12446)
		(layer "B.Cu")
		(net "PHY_DPB_TO_SCC_13_DN")
	)
	(segment
		(start 95.804228 -54.604666)
		(end 95.851726 -54.557168)
		(width 0.12446)
		(layer "B.Cu")
		(net "PHY_DPB_TO_SCC_12_DP")
	)
	(segment
		(start 87.752936 -29.52369)
		(end 85.746082 -38.962584)
		(width 0.12446)
		(layer "B.Cu")
		(net "PHY_DPB_TO_SCC_12_DP")
	)
	(segment
		(start 88.857836 -49.755298)
		(end 89.2302 -49.834546)
		(width 0.12446)
		(layer "B.Cu")
		(net "PHY_DPB_TO_SCC_12_DP")
	)
	(segment
		(start 90.05443 -51.598068)
		(end 90.328496 -52.019962)
		(width 0.12446)
		(layer "B.Cu")
		(net "PHY_DPB_TO_SCC_12_DP")
	)
	(segment
		(start 87.08263 -45.251624)
		(end 87.401908 -45.459142)
		(width 0.12446)
		(layer "B.Cu")
		(net "PHY_DPB_TO_SCC_12_DP")
	)
	(segment
		(start 87.734902 -29.439108)
		(end 87.735156 -29.439108)
		(width 0.12446)
		(layer "B.Cu")
		(net "PHY_DPB_TO_SCC_12_DP")
	)
	(segment
		(start 85.880956 -4.703318)
		(end 85.536532 -4.703318)
		(width 0.12446)
		(layer "B.Cu")
		(net "PHY_DPB_TO_SCC_12_DP")
	)
	(segment
		(start 86.815422 -43.994578)
		(end 87.1347 -44.201842)
		(width 0.12446)
		(layer "B.Cu")
		(net "PHY_DPB_TO_SCC_12_DP")
	)
	(segment
		(start 95.851726 -54.557168)
		(end 96.217994 -54.557168)
		(width 0.12446)
		(layer "B.Cu")
		(net "PHY_DPB_TO_SCC_12_DP")
	)
	(segment
		(start 87.004906 -44.886372)
		(end 87.08263 -45.251624)
		(width 0.12446)
		(layer "B.Cu")
		(net "PHY_DPB_TO_SCC_12_DP")
	)
	(segment
		(start 87.669116 -46.716188)
		(end 87.746586 -47.08144)
		(width 0.12446)
		(layer "B.Cu")
		(net "PHY_DPB_TO_SCC_12_DP")
	)
	(segment
		(start 87.1347 -44.201842)
		(end 87.212424 -44.567094)
		(width 0.12446)
		(layer "B.Cu")
		(net "PHY_DPB_TO_SCC_12_DP")
	)
	(segment
		(start 87.539322 -47.400718)
		(end 87.641684 -47.882302)
		(width 0.12446)
		(layer "B.Cu")
		(net "PHY_DPB_TO_SCC_12_DP")
	)
	(segment
		(start 89.55786 -50.833274)
		(end 89.930224 -50.912522)
		(width 0.12446)
		(layer "B.Cu")
		(net "PHY_DPB_TO_SCC_12_DP")
	)
	(segment
		(start 85.202776 -17.523968)
		(end 87.734902 -29.439108)
		(width 0.12446)
		(layer "B.Cu")
		(net "PHY_DPB_TO_SCC_12_DP")
	)
	(segment
		(start 87.479632 -45.82414)
		(end 87.272114 -46.143672)
		(width 0.12446)
		(layer "B.Cu")
		(net "PHY_DPB_TO_SCC_12_DP")
	)
	(segment
		(start 87.735156 -29.439108)
		(end 87.752936 -29.52369)
		(width 0.12446)
		(layer "B.Cu")
		(net "PHY_DPB_TO_SCC_12_DP")
	)
	(segment
		(start 90.612468 -52.457604)
		(end 93.344492 -54.23154)
		(width 0.12446)
		(layer "B.Cu")
		(net "PHY_DPB_TO_SCC_12_DP")
	)
	(segment
		(start 86.867492 -42.944542)
		(end 86.945216 -43.309794)
		(width 0.12446)
		(layer "B.Cu")
		(net "PHY_DPB_TO_SCC_12_DP")
	)
	(segment
		(start 89.354406 -50.520092)
		(end 89.55786 -50.833274)
		(width 0.12446)
		(layer "B.Cu")
		(net "PHY_DPB_TO_SCC_12_DP")
	)
	(segment
		(start 90.328496 -52.020216)
		(end 90.612468 -52.457604)
		(width 0.12446)
		(layer "B.Cu")
		(net "PHY_DPB_TO_SCC_12_DP")
	)
	(segment
		(start 86.945216 -43.309794)
		(end 86.737698 -43.629072)
		(width 0.12446)
		(layer "B.Cu")
		(net "PHY_DPB_TO_SCC_12_DP")
	)
	(segment
		(start 87.349838 -46.508924)
		(end 87.669116 -46.716188)
		(width 0.12446)
		(layer "B.Cu")
		(net "PHY_DPB_TO_SCC_12_DP")
	)
	(segment
		(start 86.815422 -43.994324)
		(end 86.815422 -43.994578)
		(width 0.12446)
		(layer "B.Cu")
		(net "PHY_DPB_TO_SCC_12_DP")
	)
	(segment
		(start 89.930224 -50.912522)
		(end 90.133424 -51.225704)
		(width 0.12446)
		(layer "B.Cu")
		(net "PHY_DPB_TO_SCC_12_DP")
	)
	(segment
		(start 85.746082 -38.962584)
		(end 86.548214 -42.737278)
		(width 0.12446)
		(layer "B.Cu")
		(net "PHY_DPB_TO_SCC_12_DP")
	)
	(segment
		(start 86.548214 -42.737278)
		(end 86.867492 -42.944542)
		(width 0.12446)
		(layer "B.Cu")
		(net "PHY_DPB_TO_SCC_12_DP")
	)
	(segment
		(start 95.098108 -54.604666)
		(end 95.804228 -54.604666)
		(width 0.12446)
		(layer "B.Cu")
		(net "PHY_DPB_TO_SCC_12_DP")
	)
	(segment
		(start 93.344492 -54.23154)
		(end 95.098108 -54.604666)
		(width 0.12446)
		(layer "B.Cu")
		(net "PHY_DPB_TO_SCC_12_DP")
	)
	(segment
		(start 85.202776 -5.037074)
		(end 85.202776 -17.523968)
		(width 0.12446)
		(layer "B.Cu")
		(net "PHY_DPB_TO_SCC_12_DP")
	)
	(segment
		(start 86.000082 -5.200142)
		(end 86.000082 -4.822444)
		(width 0.12446)
		(layer "B.Cu")
		(net "PHY_DPB_TO_SCC_12_DP")
	)
	(segment
		(start 87.746586 -47.08144)
		(end 87.539322 -47.400718)
		(width 0.12446)
		(layer "B.Cu")
		(net "PHY_DPB_TO_SCC_12_DP")
	)
	(segment
		(start 90.133424 -51.225704)
		(end 90.05443 -51.598068)
		(width 0.12446)
		(layer "B.Cu")
		(net "PHY_DPB_TO_SCC_12_DP")
	)
	(segment
		(start 89.2302 -49.834546)
		(end 89.433654 -50.147728)
		(width 0.12446)
		(layer "B.Cu")
		(net "PHY_DPB_TO_SCC_12_DP")
	)
	(segment
		(start 86.737698 -43.629072)
		(end 86.815422 -43.994324)
		(width 0.12446)
		(layer "B.Cu")
		(net "PHY_DPB_TO_SCC_12_DP")
	)
	(segment
		(start 89.433654 -50.147728)
		(end 89.354406 -50.520092)
		(width 0.12446)
		(layer "B.Cu")
		(net "PHY_DPB_TO_SCC_12_DP")
	)
	(segment
		(start 90.328496 -52.019962)
		(end 90.328496 -52.020216)
		(width 0.12446)
		(layer "B.Cu")
		(net "PHY_DPB_TO_SCC_12_DP")
	)
	(segment
		(start 87.272114 -46.143672)
		(end 87.349838 -46.508924)
		(width 0.12446)
		(layer "B.Cu")
		(net "PHY_DPB_TO_SCC_12_DP")
	)
	(segment
		(start 87.212424 -44.567094)
		(end 87.004906 -44.886372)
		(width 0.12446)
		(layer "B.Cu")
		(net "PHY_DPB_TO_SCC_12_DP")
	)
	(segment
		(start 87.401908 -45.459142)
		(end 87.479632 -45.82414)
		(width 0.12446)
		(layer "B.Cu")
		(net "PHY_DPB_TO_SCC_12_DP")
	)
	(segment
		(start 87.641684 -47.882302)
		(end 88.857836 -49.755298)
		(width 0.12446)
		(layer "B.Cu")
		(net "PHY_DPB_TO_SCC_12_DP")
	)
	(arc
		(start 85.536532 -4.703318)
		(mid 85.300531 -4.801073)
		(end 85.202776 -5.037074)
		(width 0.12446)
		(layer "B.Cu")
		(net "PHY_DPB_TO_SCC_12_DP")
	)
	(arc
		(start 85.965284 -4.73837)
		(mid 85.926623 -4.71241)
		(end 85.880956 -4.703318)
		(width 0.12446)
		(layer "B.Cu")
		(net "PHY_DPB_TO_SCC_12_DP")
	)
	(arc
		(start 86.000082 -4.822444)
		(mid 85.991033 -4.776954)
		(end 85.965284 -4.73837)
		(width 0.12446)
		(layer "B.Cu")
		(net "PHY_DPB_TO_SCC_12_DP")
	)
	(segment
		(start 95.055182 -55.011066)
		(end 93.18625 -54.613556)
		(width 0.12446)
		(layer "B.Cu")
		(net "PHY_DPB_TO_SCC_12_DN")
	)
	(segment
		(start 85.330538 -38.962584)
		(end 87.337392 -29.52369)
		(width 0.12446)
		(layer "B.Cu")
		(net "PHY_DPB_TO_SCC_12_DN")
	)
	(segment
		(start 90.31859 -52.751482)
		(end 87.259668 -48.040544)
		(width 0.12446)
		(layer "B.Cu")
		(net "PHY_DPB_TO_SCC_12_DN")
	)
	(segment
		(start 87.259668 -48.040544)
		(end 85.330538 -38.962584)
		(width 0.12446)
		(layer "B.Cu")
		(net "PHY_DPB_TO_SCC_12_DN")
	)
	(segment
		(start 85.536532 -4.296918)
		(end 85.880956 -4.296918)
		(width 0.12446)
		(layer "B.Cu")
		(net "PHY_DPB_TO_SCC_12_DN")
	)
	(segment
		(start 86.000082 -4.177792)
		(end 86.000082 -3.800094)
		(width 0.12446)
		(layer "B.Cu")
		(net "PHY_DPB_TO_SCC_12_DN")
	)
	(segment
		(start 84.796376 -17.567656)
		(end 84.796376 -5.037074)
		(width 0.12446)
		(layer "B.Cu")
		(net "PHY_DPB_TO_SCC_12_DN")
	)
	(segment
		(start 93.18625 -54.613556)
		(end 90.31859 -52.751482)
		(width 0.12446)
		(layer "B.Cu")
		(net "PHY_DPB_TO_SCC_12_DN")
	)
	(segment
		(start 87.337392 -29.52369)
		(end 87.337138 -29.52369)
		(width 0.12446)
		(layer "B.Cu")
		(net "PHY_DPB_TO_SCC_12_DN")
	)
	(segment
		(start 87.337138 -29.52369)
		(end 84.796376 -17.567656)
		(width 0.12446)
		(layer "B.Cu")
		(net "PHY_DPB_TO_SCC_12_DN")
	)
	(segment
		(start 95.851726 -55.141368)
		(end 95.721424 -55.011066)
		(width 0.12446)
		(layer "B.Cu")
		(net "PHY_DPB_TO_SCC_12_DN")
	)
	(segment
		(start 96.217994 -55.141368)
		(end 95.851726 -55.141368)
		(width 0.12446)
		(layer "B.Cu")
		(net "PHY_DPB_TO_SCC_12_DN")
	)
	(segment
		(start 95.721424 -55.011066)
		(end 95.055182 -55.011066)
		(width 0.12446)
		(layer "B.Cu")
		(net "PHY_DPB_TO_SCC_12_DN")
	)
	(arc
		(start 85.965284 -4.261866)
		(mid 85.991058 -4.223293)
		(end 86.000082 -4.177792)
		(width 0.12446)
		(layer "B.Cu")
		(net "PHY_DPB_TO_SCC_12_DN")
	)
	(arc
		(start 84.796376 -5.037074)
		(mid 85.013163 -4.513705)
		(end 85.536532 -4.296918)
		(width 0.12446)
		(layer "B.Cu")
		(net "PHY_DPB_TO_SCC_12_DN")
	)
	(arc
		(start 85.880956 -4.296918)
		(mid 85.926612 -4.287801)
		(end 85.965284 -4.261866)
		(width 0.12446)
		(layer "B.Cu")
		(net "PHY_DPB_TO_SCC_12_DN")
	)
	(segment
		(start 126.500128 -74.500232)
		(end 127 -75.000104)
		(width 0.104902)
		(layer "F.Cu")
		(net "PHY_CONN_TO_EXP_C_9_DP")
	)
	(via
		(at 127 -75.000104)
		(size 0.4572)
		(drill 0.2032)
		(layers "F.Cu" "B.Cu")
		(net "PHY_CONN_TO_EXP_C_9_DP")
	)
	(segment
		(start 135.43153 -77.600302)
		(end 134.708646 -77.600302)
		(width 0.12446)
		(layer "B.Cu")
		(net "PHY_CONN_TO_EXP_C_9_DP")
	)
	(segment
		(start 132.61848 -75.114912)
		(end 132.223256 -75.114912)
		(width 0.12446)
		(layer "B.Cu")
		(net "PHY_CONN_TO_EXP_C_9_DP")
	)
	(segment
		(start 126.684024 -75.000104)
		(end 127 -75.000104)
		(width 0.0889)
		(layer "B.Cu")
		(net "PHY_CONN_TO_EXP_C_9_DP")
	)
	(segment
		(start 131.782312 -74.673968)
		(end 130.424428 -74.673968)
		(width 0.12446)
		(layer "B.Cu")
		(net "PHY_CONN_TO_EXP_C_9_DP")
	)
	(segment
		(start 129.299716 -75.402694)
		(end 126.772924 -75.402694)
		(width 0.0889)
		(layer "B.Cu")
		(net "PHY_CONN_TO_EXP_C_9_DP")
	)
	(segment
		(start 132.223256 -75.114912)
		(end 131.782312 -74.673968)
		(width 0.12446)
		(layer "B.Cu")
		(net "PHY_CONN_TO_EXP_C_9_DP")
	)
	(segment
		(start 126.595124 -75.224894)
		(end 126.595124 -75.089004)
		(width 0.0889)
		(layer "B.Cu")
		(net "PHY_CONN_TO_EXP_C_9_DP")
	)
	(segment
		(start 129.852166 -75.24623)
		(end 129.478278 -75.24623)
		(width 0.12446)
		(layer "B.Cu")
		(net "PHY_CONN_TO_EXP_C_9_DP")
	)
	(segment
		(start 135.536432 -77.4954)
		(end 135.43153 -77.600302)
		(width 0.12446)
		(layer "B.Cu")
		(net "PHY_CONN_TO_EXP_C_9_DP")
	)
	(segment
		(start 134.708646 -77.600302)
		(end 132.88264 -75.774296)
		(width 0.12446)
		(layer "B.Cu")
		(net "PHY_CONN_TO_EXP_C_9_DP")
	)
	(segment
		(start 132.88264 -75.774296)
		(end 132.88264 -75.379072)
		(width 0.12446)
		(layer "B.Cu")
		(net "PHY_CONN_TO_EXP_C_9_DP")
	)
	(segment
		(start 129.45618 -75.24623)
		(end 129.299716 -75.402694)
		(width 0.0889)
		(layer "B.Cu")
		(net "PHY_CONN_TO_EXP_C_9_DP")
	)
	(segment
		(start 132.88264 -75.379072)
		(end 132.61848 -75.114912)
		(width 0.12446)
		(layer "B.Cu")
		(net "PHY_CONN_TO_EXP_C_9_DP")
	)
	(segment
		(start 129.478278 -75.24623)
		(end 129.45618 -75.24623)
		(width 0.0889)
		(layer "B.Cu")
		(net "PHY_CONN_TO_EXP_C_9_DP")
	)
	(segment
		(start 135.9154 -77.4954)
		(end 135.536432 -77.4954)
		(width 0.12446)
		(layer "B.Cu")
		(net "PHY_CONN_TO_EXP_C_9_DP")
	)
	(segment
		(start 130.424428 -74.673968)
		(end 129.852166 -75.24623)
		(width 0.12446)
		(layer "B.Cu")
		(net "PHY_CONN_TO_EXP_C_9_DP")
	)
	(arc
		(start 126.595124 -75.089004)
		(mid 126.621162 -75.026142)
		(end 126.684024 -75.000104)
		(width 0.0889)
		(layer "B.Cu")
		(net "PHY_CONN_TO_EXP_C_9_DP")
	)
	(arc
		(start 126.772924 -75.402694)
		(mid 126.6472 -75.350618)
		(end 126.595124 -75.224894)
		(width 0.0889)
		(layer "B.Cu")
		(net "PHY_CONN_TO_EXP_C_9_DP")
	)
	(segment
		(start 125.50013 -74.500232)
		(end 126.000002 -75.000104)
		(width 0.104902)
		(layer "F.Cu")
		(net "PHY_CONN_TO_EXP_C_9_DN")
	)
	(via
		(at 126.000002 -75.000104)
		(size 0.4572)
		(drill 0.2032)
		(layers "F.Cu" "B.Cu")
		(net "PHY_CONN_TO_EXP_C_9_DN")
	)
	(segment
		(start 135.536432 -78.0542)
		(end 135.488934 -78.006702)
		(width 0.12446)
		(layer "B.Cu")
		(net "PHY_CONN_TO_EXP_C_9_DN")
	)
	(segment
		(start 131.61391 -75.080368)
		(end 130.59283 -75.080368)
		(width 0.12446)
		(layer "B.Cu")
		(net "PHY_CONN_TO_EXP_C_9_DN")
	)
	(segment
		(start 135.9154 -78.0542)
		(end 135.536432 -78.0542)
		(width 0.12446)
		(layer "B.Cu")
		(net "PHY_CONN_TO_EXP_C_9_DN")
	)
	(segment
		(start 126.404624 -75.224894)
		(end 126.404624 -75.089004)
		(width 0.0889)
		(layer "B.Cu")
		(net "PHY_CONN_TO_EXP_C_9_DN")
	)
	(segment
		(start 126.315724 -75.000104)
		(end 126.000002 -75.000104)
		(width 0.0889)
		(layer "B.Cu")
		(net "PHY_CONN_TO_EXP_C_9_DN")
	)
	(segment
		(start 129.45618 -75.65263)
		(end 129.396744 -75.593194)
		(width 0.0889)
		(layer "B.Cu")
		(net "PHY_CONN_TO_EXP_C_9_DN")
	)
	(segment
		(start 134.540244 -78.006702)
		(end 131.61391 -75.080368)
		(width 0.12446)
		(layer "B.Cu")
		(net "PHY_CONN_TO_EXP_C_9_DN")
	)
	(segment
		(start 135.488934 -78.006702)
		(end 134.540244 -78.006702)
		(width 0.12446)
		(layer "B.Cu")
		(net "PHY_CONN_TO_EXP_C_9_DN")
	)
	(segment
		(start 129.478278 -75.65263)
		(end 129.45618 -75.65263)
		(width 0.0889)
		(layer "B.Cu")
		(net "PHY_CONN_TO_EXP_C_9_DN")
	)
	(segment
		(start 130.59283 -75.080368)
		(end 130.020568 -75.65263)
		(width 0.12446)
		(layer "B.Cu")
		(net "PHY_CONN_TO_EXP_C_9_DN")
	)
	(segment
		(start 129.396744 -75.593194)
		(end 126.772924 -75.593194)
		(width 0.0889)
		(layer "B.Cu")
		(net "PHY_CONN_TO_EXP_C_9_DN")
	)
	(segment
		(start 130.020568 -75.65263)
		(end 129.478278 -75.65263)
		(width 0.12446)
		(layer "B.Cu")
		(net "PHY_CONN_TO_EXP_C_9_DN")
	)
	(arc
		(start 126.404624 -75.089004)
		(mid 126.378586 -75.026142)
		(end 126.315724 -75.000104)
		(width 0.0889)
		(layer "B.Cu")
		(net "PHY_CONN_TO_EXP_C_9_DN")
	)
	(arc
		(start 126.772924 -75.593194)
		(mid 126.512497 -75.485321)
		(end 126.404624 -75.224894)
		(width 0.0889)
		(layer "B.Cu")
		(net "PHY_CONN_TO_EXP_C_9_DN")
	)
	(segment
		(start 126.500128 -73.500234)
		(end 127 -74.000106)
		(width 0.104902)
		(layer "F.Cu")
		(net "PHY_CONN_TO_EXP_C_8_DP")
	)
	(via
		(at 127 -74.000106)
		(size 0.4572)
		(drill 0.2032)
		(layers "F.Cu" "B.Cu")
		(net "PHY_CONN_TO_EXP_C_8_DP")
	)
	(segment
		(start 128.406144 -74.405744)
		(end 126.822962 -74.405744)
		(width 0.0889)
		(layer "B.Cu")
		(net "PHY_CONN_TO_EXP_C_8_DP")
	)
	(segment
		(start 135.89 -75.5904)
		(end 135.511032 -75.5904)
		(width 0.12446)
		(layer "B.Cu")
		(net "PHY_CONN_TO_EXP_C_8_DP")
	)
	(segment
		(start 130.98272 -73.948798)
		(end 130.70332 -73.669398)
		(width 0.12446)
		(layer "B.Cu")
		(net "PHY_CONN_TO_EXP_C_8_DP")
	)
	(segment
		(start 134.530592 -75.693778)
		(end 132.785612 -73.948798)
		(width 0.12446)
		(layer "B.Cu")
		(net "PHY_CONN_TO_EXP_C_8_DP")
	)
	(segment
		(start 135.511032 -75.5904)
		(end 135.407654 -75.693778)
		(width 0.12446)
		(layer "B.Cu")
		(net "PHY_CONN_TO_EXP_C_8_DP")
	)
	(segment
		(start 130.05054 -73.948798)
		(end 129.67716 -73.948798)
		(width 0.12446)
		(layer "B.Cu")
		(net "PHY_CONN_TO_EXP_C_8_DP")
	)
	(segment
		(start 132.785612 -73.948798)
		(end 130.98272 -73.948798)
		(width 0.12446)
		(layer "B.Cu")
		(net "PHY_CONN_TO_EXP_C_8_DP")
	)
	(segment
		(start 135.407654 -75.693778)
		(end 134.530592 -75.693778)
		(width 0.12446)
		(layer "B.Cu")
		(net "PHY_CONN_TO_EXP_C_8_DP")
	)
	(segment
		(start 129.67716 -73.948798)
		(end 129.655062 -73.948798)
		(width 0.0889)
		(layer "B.Cu")
		(net "PHY_CONN_TO_EXP_C_8_DP")
	)
	(segment
		(start 126.684024 -74.000106)
		(end 127 -74.000106)
		(width 0.0889)
		(layer "B.Cu")
		(net "PHY_CONN_TO_EXP_C_8_DP")
	)
	(segment
		(start 130.32994 -73.669398)
		(end 130.05054 -73.948798)
		(width 0.12446)
		(layer "B.Cu")
		(net "PHY_CONN_TO_EXP_C_8_DP")
	)
	(segment
		(start 128.70307 -74.108818)
		(end 128.406144 -74.405744)
		(width 0.0889)
		(layer "B.Cu")
		(net "PHY_CONN_TO_EXP_C_8_DP")
	)
	(segment
		(start 129.495042 -74.108818)
		(end 128.70307 -74.108818)
		(width 0.0889)
		(layer "B.Cu")
		(net "PHY_CONN_TO_EXP_C_8_DP")
	)
	(segment
		(start 126.595124 -74.177906)
		(end 126.595124 -74.089006)
		(width 0.0889)
		(layer "B.Cu")
		(net "PHY_CONN_TO_EXP_C_8_DP")
	)
	(segment
		(start 130.70332 -73.669398)
		(end 130.32994 -73.669398)
		(width 0.12446)
		(layer "B.Cu")
		(net "PHY_CONN_TO_EXP_C_8_DP")
	)
	(segment
		(start 129.655062 -73.948798)
		(end 129.495042 -74.108818)
		(width 0.0889)
		(layer "B.Cu")
		(net "PHY_CONN_TO_EXP_C_8_DP")
	)
	(arc
		(start 126.822962 -74.405744)
		(mid 126.661856 -74.339012)
		(end 126.595124 -74.177906)
		(width 0.0889)
		(layer "B.Cu")
		(net "PHY_CONN_TO_EXP_C_8_DP")
	)
	(arc
		(start 126.595124 -74.089006)
		(mid 126.621162 -74.026144)
		(end 126.684024 -74.000106)
		(width 0.0889)
		(layer "B.Cu")
		(net "PHY_CONN_TO_EXP_C_8_DP")
	)
	(segment
		(start 125.50013 -73.500234)
		(end 126.000002 -74.000106)
		(width 0.104902)
		(layer "F.Cu")
		(net "PHY_CONN_TO_EXP_C_8_DN")
	)
	(via
		(at 126.000002 -74.000106)
		(size 0.4572)
		(drill 0.2032)
		(layers "F.Cu" "B.Cu")
		(net "PHY_CONN_TO_EXP_C_8_DN")
	)
	(segment
		(start 135.46201 -76.100178)
		(end 134.36219 -76.100178)
		(width 0.12446)
		(layer "B.Cu")
		(net "PHY_CONN_TO_EXP_C_8_DN")
	)
	(segment
		(start 129.67716 -74.355198)
		(end 129.655062 -74.355198)
		(width 0.0889)
		(layer "B.Cu")
		(net "PHY_CONN_TO_EXP_C_8_DN")
	)
	(segment
		(start 126.404624 -74.177906)
		(end 126.404624 -74.089006)
		(width 0.0889)
		(layer "B.Cu")
		(net "PHY_CONN_TO_EXP_C_8_DN")
	)
	(segment
		(start 128.485138 -74.596244)
		(end 126.822962 -74.596244)
		(width 0.0889)
		(layer "B.Cu")
		(net "PHY_CONN_TO_EXP_C_8_DN")
	)
	(segment
		(start 128.782064 -74.299318)
		(end 128.485138 -74.596244)
		(width 0.0889)
		(layer "B.Cu")
		(net "PHY_CONN_TO_EXP_C_8_DN")
	)
	(segment
		(start 135.511032 -76.1492)
		(end 135.46201 -76.100178)
		(width 0.12446)
		(layer "B.Cu")
		(net "PHY_CONN_TO_EXP_C_8_DN")
	)
	(segment
		(start 129.599182 -74.299318)
		(end 128.782064 -74.299318)
		(width 0.0889)
		(layer "B.Cu")
		(net "PHY_CONN_TO_EXP_C_8_DN")
	)
	(segment
		(start 132.61721 -74.355198)
		(end 129.67716 -74.355198)
		(width 0.12446)
		(layer "B.Cu")
		(net "PHY_CONN_TO_EXP_C_8_DN")
	)
	(segment
		(start 134.36219 -76.100178)
		(end 132.61721 -74.355198)
		(width 0.12446)
		(layer "B.Cu")
		(net "PHY_CONN_TO_EXP_C_8_DN")
	)
	(segment
		(start 129.655062 -74.355198)
		(end 129.599182 -74.299318)
		(width 0.0889)
		(layer "B.Cu")
		(net "PHY_CONN_TO_EXP_C_8_DN")
	)
	(segment
		(start 126.315724 -74.000106)
		(end 126.000002 -74.000106)
		(width 0.0889)
		(layer "B.Cu")
		(net "PHY_CONN_TO_EXP_C_8_DN")
	)
	(segment
		(start 135.89 -76.1492)
		(end 135.511032 -76.1492)
		(width 0.12446)
		(layer "B.Cu")
		(net "PHY_CONN_TO_EXP_C_8_DN")
	)
	(arc
		(start 126.404624 -74.089006)
		(mid 126.378586 -74.026144)
		(end 126.315724 -74.000106)
		(width 0.0889)
		(layer "B.Cu")
		(net "PHY_CONN_TO_EXP_C_8_DN")
	)
	(arc
		(start 126.822962 -74.596244)
		(mid 126.527152 -74.473716)
		(end 126.404624 -74.177906)
		(width 0.0889)
		(layer "B.Cu")
		(net "PHY_CONN_TO_EXP_C_8_DN")
	)
	(segment
		(start 126.500128 -76.500228)
		(end 127 -77.0001)
		(width 0.104902)
		(layer "F.Cu")
		(net "PHY_CONN_TO_EXP_C_11_DP")
	)
	(via
		(at 127 -77.0001)
		(size 0.4572)
		(drill 0.2032)
		(layers "F.Cu" "B.Cu")
		(net "PHY_CONN_TO_EXP_C_11_DP")
	)
	(segment
		(start 135.48106 -80.674972)
		(end 134.03453 -80.674972)
		(width 0.12446)
		(layer "B.Cu")
		(net "PHY_CONN_TO_EXP_C_11_DP")
	)
	(segment
		(start 129.144268 -77.405484)
		(end 126.714504 -77.405484)
		(width 0.0889)
		(layer "B.Cu")
		(net "PHY_CONN_TO_EXP_C_11_DP")
	)
	(segment
		(start 135.9662 -80.5688)
		(end 135.587232 -80.5688)
		(width 0.12446)
		(layer "B.Cu")
		(net "PHY_CONN_TO_EXP_C_11_DP")
	)
	(segment
		(start 129.645156 -77.145642)
		(end 129.623058 -77.145642)
		(width 0.0889)
		(layer "B.Cu")
		(net "PHY_CONN_TO_EXP_C_11_DP")
	)
	(segment
		(start 131.811268 -78.45171)
		(end 131.811268 -77.681328)
		(width 0.12446)
		(layer "B.Cu")
		(net "PHY_CONN_TO_EXP_C_11_DP")
	)
	(segment
		(start 132.734558 -79.375)
		(end 132.734558 -78.979776)
		(width 0.12446)
		(layer "B.Cu")
		(net "PHY_CONN_TO_EXP_C_11_DP")
	)
	(segment
		(start 131.811268 -77.681328)
		(end 131.275582 -77.145642)
		(width 0.12446)
		(layer "B.Cu")
		(net "PHY_CONN_TO_EXP_C_11_DP")
	)
	(segment
		(start 134.03453 -80.674972)
		(end 132.734558 -79.375)
		(width 0.12446)
		(layer "B.Cu")
		(net "PHY_CONN_TO_EXP_C_11_DP")
	)
	(segment
		(start 126.595124 -77.286104)
		(end 126.595124 -77.089)
		(width 0.0889)
		(layer "B.Cu")
		(net "PHY_CONN_TO_EXP_C_11_DP")
	)
	(segment
		(start 132.075174 -78.715616)
		(end 131.811268 -78.45171)
		(width 0.12446)
		(layer "B.Cu")
		(net "PHY_CONN_TO_EXP_C_11_DP")
	)
	(segment
		(start 129.623058 -77.145642)
		(end 129.466594 -77.302106)
		(width 0.0889)
		(layer "B.Cu")
		(net "PHY_CONN_TO_EXP_C_11_DP")
	)
	(segment
		(start 132.470398 -78.715616)
		(end 132.075174 -78.715616)
		(width 0.12446)
		(layer "B.Cu")
		(net "PHY_CONN_TO_EXP_C_11_DP")
	)
	(segment
		(start 129.466594 -77.302106)
		(end 129.247646 -77.302106)
		(width 0.0889)
		(layer "B.Cu")
		(net "PHY_CONN_TO_EXP_C_11_DP")
	)
	(segment
		(start 132.734558 -78.979776)
		(end 132.470398 -78.715616)
		(width 0.12446)
		(layer "B.Cu")
		(net "PHY_CONN_TO_EXP_C_11_DP")
	)
	(segment
		(start 131.275582 -77.145642)
		(end 129.645156 -77.145642)
		(width 0.12446)
		(layer "B.Cu")
		(net "PHY_CONN_TO_EXP_C_11_DP")
	)
	(segment
		(start 135.587232 -80.5688)
		(end 135.48106 -80.674972)
		(width 0.12446)
		(layer "B.Cu")
		(net "PHY_CONN_TO_EXP_C_11_DP")
	)
	(segment
		(start 129.247646 -77.302106)
		(end 129.144268 -77.405484)
		(width 0.0889)
		(layer "B.Cu")
		(net "PHY_CONN_TO_EXP_C_11_DP")
	)
	(segment
		(start 126.684024 -77.0001)
		(end 127 -77.0001)
		(width 0.0889)
		(layer "B.Cu")
		(net "PHY_CONN_TO_EXP_C_11_DP")
	)
	(arc
		(start 126.595124 -77.089)
		(mid 126.621162 -77.026138)
		(end 126.684024 -77.0001)
		(width 0.0889)
		(layer "B.Cu")
		(net "PHY_CONN_TO_EXP_C_11_DP")
	)
	(arc
		(start 126.714504 -77.405484)
		(mid 126.63009 -77.370518)
		(end 126.595124 -77.286104)
		(width 0.0889)
		(layer "B.Cu")
		(net "PHY_CONN_TO_EXP_C_11_DP")
	)
	(segment
		(start 125.50013 -76.500228)
		(end 126.000002 -77.0001)
		(width 0.104902)
		(layer "F.Cu")
		(net "PHY_CONN_TO_EXP_C_11_DN")
	)
	(via
		(at 126.000002 -77.0001)
		(size 0.4572)
		(drill 0.2032)
		(layers "F.Cu" "B.Cu")
		(net "PHY_CONN_TO_EXP_C_11_DN")
	)
	(segment
		(start 131.404868 -77.84973)
		(end 131.10718 -77.552042)
		(width 0.12446)
		(layer "B.Cu")
		(net "PHY_CONN_TO_EXP_C_11_DN")
	)
	(segment
		(start 133.866128 -81.081372)
		(end 131.404868 -78.620112)
		(width 0.12446)
		(layer "B.Cu")
		(net "PHY_CONN_TO_EXP_C_11_DN")
	)
	(segment
		(start 129.223262 -77.595984)
		(end 126.714504 -77.595984)
		(width 0.0889)
		(layer "B.Cu")
		(net "PHY_CONN_TO_EXP_C_11_DN")
	)
	(segment
		(start 129.645156 -77.552042)
		(end 129.623058 -77.552042)
		(width 0.0889)
		(layer "B.Cu")
		(net "PHY_CONN_TO_EXP_C_11_DN")
	)
	(segment
		(start 129.563622 -77.492606)
		(end 129.32664 -77.492606)
		(width 0.0889)
		(layer "B.Cu")
		(net "PHY_CONN_TO_EXP_C_11_DN")
	)
	(segment
		(start 135.9662 -81.1276)
		(end 135.587232 -81.1276)
		(width 0.12446)
		(layer "B.Cu")
		(net "PHY_CONN_TO_EXP_C_11_DN")
	)
	(segment
		(start 135.541004 -81.081372)
		(end 133.866128 -81.081372)
		(width 0.12446)
		(layer "B.Cu")
		(net "PHY_CONN_TO_EXP_C_11_DN")
	)
	(segment
		(start 126.315724 -77.0001)
		(end 126.000002 -77.0001)
		(width 0.0889)
		(layer "B.Cu")
		(net "PHY_CONN_TO_EXP_C_11_DN")
	)
	(segment
		(start 131.404868 -78.620112)
		(end 131.404868 -77.84973)
		(width 0.12446)
		(layer "B.Cu")
		(net "PHY_CONN_TO_EXP_C_11_DN")
	)
	(segment
		(start 129.623058 -77.552042)
		(end 129.563622 -77.492606)
		(width 0.0889)
		(layer "B.Cu")
		(net "PHY_CONN_TO_EXP_C_11_DN")
	)
	(segment
		(start 135.587232 -81.1276)
		(end 135.541004 -81.081372)
		(width 0.12446)
		(layer "B.Cu")
		(net "PHY_CONN_TO_EXP_C_11_DN")
	)
	(segment
		(start 126.404624 -77.286104)
		(end 126.404624 -77.089)
		(width 0.0889)
		(layer "B.Cu")
		(net "PHY_CONN_TO_EXP_C_11_DN")
	)
	(segment
		(start 129.32664 -77.492606)
		(end 129.223262 -77.595984)
		(width 0.0889)
		(layer "B.Cu")
		(net "PHY_CONN_TO_EXP_C_11_DN")
	)
	(segment
		(start 131.10718 -77.552042)
		(end 129.645156 -77.552042)
		(width 0.12446)
		(layer "B.Cu")
		(net "PHY_CONN_TO_EXP_C_11_DN")
	)
	(arc
		(start 126.714504 -77.595984)
		(mid 126.495386 -77.505222)
		(end 126.404624 -77.286104)
		(width 0.0889)
		(layer "B.Cu")
		(net "PHY_CONN_TO_EXP_C_11_DN")
	)
	(arc
		(start 126.404624 -77.089)
		(mid 126.378586 -77.026138)
		(end 126.315724 -77.0001)
		(width 0.0889)
		(layer "B.Cu")
		(net "PHY_CONN_TO_EXP_C_11_DN")
	)
	(segment
		(start 126.500128 -75.50023)
		(end 127 -76.000102)
		(width 0.104902)
		(layer "F.Cu")
		(net "PHY_CONN_TO_EXP_C_10_DP")
	)
	(via
		(at 127 -76.000102)
		(size 0.4572)
		(drill 0.2032)
		(layers "F.Cu" "B.Cu")
		(net "PHY_CONN_TO_EXP_C_10_DP")
	)
	(segment
		(start 127 -76.000102)
		(end 126.684024 -76.000102)
		(width 0.0889)
		(layer "B.Cu")
		(net "PHY_CONN_TO_EXP_C_10_DP")
	)
	(segment
		(start 135.455914 -79.150718)
		(end 135.561832 -79.0448)
		(width 0.12446)
		(layer "B.Cu")
		(net "PHY_CONN_TO_EXP_C_10_DP")
	)
	(segment
		(start 131.471416 -76.248768)
		(end 131.780026 -76.557378)
		(width 0.12446)
		(layer "B.Cu")
		(net "PHY_CONN_TO_EXP_C_10_DP")
	)
	(segment
		(start 131.780026 -76.557378)
		(end 132.17525 -76.557378)
		(width 0.12446)
		(layer "B.Cu")
		(net "PHY_CONN_TO_EXP_C_10_DP")
	)
	(segment
		(start 135.561832 -79.0448)
		(end 135.9408 -79.0448)
		(width 0.12446)
		(layer "B.Cu")
		(net "PHY_CONN_TO_EXP_C_10_DP")
	)
	(segment
		(start 129.388362 -76.248768)
		(end 129.41046 -76.248768)
		(width 0.0889)
		(layer "B.Cu")
		(net "PHY_CONN_TO_EXP_C_10_DP")
	)
	(segment
		(start 132.43941 -77.216762)
		(end 134.373366 -79.150718)
		(width 0.12446)
		(layer "B.Cu")
		(net "PHY_CONN_TO_EXP_C_10_DP")
	)
	(segment
		(start 132.43941 -76.821538)
		(end 132.43941 -77.216762)
		(width 0.12446)
		(layer "B.Cu")
		(net "PHY_CONN_TO_EXP_C_10_DP")
	)
	(segment
		(start 126.771654 -76.401422)
		(end 129.235708 -76.401422)
		(width 0.0889)
		(layer "B.Cu")
		(net "PHY_CONN_TO_EXP_C_10_DP")
	)
	(segment
		(start 126.595124 -76.089002)
		(end 126.595124 -76.224892)
		(width 0.0889)
		(layer "B.Cu")
		(net "PHY_CONN_TO_EXP_C_10_DP")
	)
	(segment
		(start 129.235708 -76.401422)
		(end 129.388362 -76.248768)
		(width 0.0889)
		(layer "B.Cu")
		(net "PHY_CONN_TO_EXP_C_10_DP")
	)
	(segment
		(start 132.17525 -76.557378)
		(end 132.43941 -76.821538)
		(width 0.12446)
		(layer "B.Cu")
		(net "PHY_CONN_TO_EXP_C_10_DP")
	)
	(segment
		(start 129.41046 -76.248768)
		(end 131.471416 -76.248768)
		(width 0.12446)
		(layer "B.Cu")
		(net "PHY_CONN_TO_EXP_C_10_DP")
	)
	(segment
		(start 134.373366 -79.150718)
		(end 135.455914 -79.150718)
		(width 0.12446)
		(layer "B.Cu")
		(net "PHY_CONN_TO_EXP_C_10_DP")
	)
	(arc
		(start 126.684024 -76.000102)
		(mid 126.621162 -76.02614)
		(end 126.595124 -76.089002)
		(width 0.0889)
		(layer "B.Cu")
		(net "PHY_CONN_TO_EXP_C_10_DP")
	)
	(arc
		(start 126.595124 -76.224892)
		(mid 126.646828 -76.349718)
		(end 126.771654 -76.401422)
		(width 0.0889)
		(layer "B.Cu")
		(net "PHY_CONN_TO_EXP_C_10_DP")
	)
	(segment
		(start 125.50013 -75.50023)
		(end 126.000002 -76.000102)
		(width 0.104902)
		(layer "F.Cu")
		(net "PHY_CONN_TO_EXP_C_10_DN")
	)
	(via
		(at 126.000002 -76.000102)
		(size 0.4572)
		(drill 0.2032)
		(layers "F.Cu" "B.Cu")
		(net "PHY_CONN_TO_EXP_C_10_DN")
	)
	(segment
		(start 126.000002 -76.000102)
		(end 126.315724 -76.000102)
		(width 0.0889)
		(layer "B.Cu")
		(net "PHY_CONN_TO_EXP_C_10_DN")
	)
	(segment
		(start 129.325116 -76.591922)
		(end 129.388362 -76.655168)
		(width 0.0889)
		(layer "B.Cu")
		(net "PHY_CONN_TO_EXP_C_10_DN")
	)
	(segment
		(start 126.404624 -76.089002)
		(end 126.404624 -76.224892)
		(width 0.0889)
		(layer "B.Cu")
		(net "PHY_CONN_TO_EXP_C_10_DN")
	)
	(segment
		(start 135.51535 -79.557118)
		(end 135.561832 -79.6036)
		(width 0.12446)
		(layer "B.Cu")
		(net "PHY_CONN_TO_EXP_C_10_DN")
	)
	(segment
		(start 131.303014 -76.655168)
		(end 134.204964 -79.557118)
		(width 0.12446)
		(layer "B.Cu")
		(net "PHY_CONN_TO_EXP_C_10_DN")
	)
	(segment
		(start 129.41046 -76.655168)
		(end 131.303014 -76.655168)
		(width 0.12446)
		(layer "B.Cu")
		(net "PHY_CONN_TO_EXP_C_10_DN")
	)
	(segment
		(start 135.561832 -79.6036)
		(end 135.9408 -79.6036)
		(width 0.12446)
		(layer "B.Cu")
		(net "PHY_CONN_TO_EXP_C_10_DN")
	)
	(segment
		(start 126.771654 -76.591922)
		(end 129.325116 -76.591922)
		(width 0.0889)
		(layer "B.Cu")
		(net "PHY_CONN_TO_EXP_C_10_DN")
	)
	(segment
		(start 129.388362 -76.655168)
		(end 129.41046 -76.655168)
		(width 0.0889)
		(layer "B.Cu")
		(net "PHY_CONN_TO_EXP_C_10_DN")
	)
	(segment
		(start 134.204964 -79.557118)
		(end 135.51535 -79.557118)
		(width 0.12446)
		(layer "B.Cu")
		(net "PHY_CONN_TO_EXP_C_10_DN")
	)
	(arc
		(start 126.315724 -76.000102)
		(mid 126.378586 -76.02614)
		(end 126.404624 -76.089002)
		(width 0.0889)
		(layer "B.Cu")
		(net "PHY_CONN_TO_EXP_C_10_DN")
	)
	(arc
		(start 126.404624 -76.224892)
		(mid 126.512125 -76.484421)
		(end 126.771654 -76.591922)
		(width 0.0889)
		(layer "B.Cu")
		(net "PHY_CONN_TO_EXP_C_10_DN")
	)
	(segment
		(start 103.066088 -115.287044)
		(end 103.102918 -115.306856)
		(width 0.12446)
		(layer "B.Cu")
		(net "PHY_CONN_TO_EXP_9_DP")
	)
	(segment
		(start 145.416016 -81.674716)
		(end 146.723354 -87.825834)
		(width 0.12446)
		(layer "B.Cu")
		(net "PHY_CONN_TO_EXP_9_DP")
	)
	(segment
		(start 136.853168 -77.4954)
		(end 136.929368 -77.5716)
		(width 0.12446)
		(layer "B.Cu")
		(net "PHY_CONN_TO_EXP_9_DP")
	)
	(segment
		(start 103.011732 -115.237768)
		(end 103.042212 -115.268756)
		(width 0.12446)
		(layer "B.Cu")
		(net "PHY_CONN_TO_EXP_9_DP")
	)
	(segment
		(start 136.929368 -77.5716)
		(end 140.96238 -77.5716)
		(width 0.12446)
		(layer "B.Cu")
		(net "PHY_CONN_TO_EXP_9_DP")
	)
	(segment
		(start 102.819962 -114.273584)
		(end 102.751636 -114.595656)
		(width 0.12446)
		(layer "B.Cu")
		(net "PHY_CONN_TO_EXP_9_DP")
	)
	(segment
		(start 104.139238 -113.468404)
		(end 103.585772 -113.58626)
		(width 0.12446)
		(layer "B.Cu")
		(net "PHY_CONN_TO_EXP_9_DP")
	)
	(segment
		(start 102.751636 -114.595656)
		(end 102.827074 -114.953796)
		(width 0.12446)
		(layer "B.Cu")
		(net "PHY_CONN_TO_EXP_9_DP")
	)
	(segment
		(start 142.28445 -97.130616)
		(end 121.628408 -110.54461)
		(width 0.12446)
		(layer "B.Cu")
		(net "PHY_CONN_TO_EXP_9_DP")
	)
	(segment
		(start 102.827074 -114.953796)
		(end 103.011732 -115.237768)
		(width 0.12446)
		(layer "B.Cu")
		(net "PHY_CONN_TO_EXP_9_DP")
	)
	(segment
		(start 146.723354 -87.825834)
		(end 145.943574 -91.495372)
		(width 0.12446)
		(layer "B.Cu")
		(net "PHY_CONN_TO_EXP_9_DP")
	)
	(segment
		(start 103.585772 -113.58626)
		(end 103.033576 -113.9444)
		(width 0.12446)
		(layer "B.Cu")
		(net "PHY_CONN_TO_EXP_9_DP")
	)
	(segment
		(start 143.707358 -79.043276)
		(end 145.416016 -81.674716)
		(width 0.12446)
		(layer "B.Cu")
		(net "PHY_CONN_TO_EXP_9_DP")
	)
	(segment
		(start 103.110538 -115.31092)
		(end 103.1113 -115.311428)
		(width 0.12446)
		(layer "B.Cu")
		(net "PHY_CONN_TO_EXP_9_DP")
	)
	(segment
		(start 136.4742 -77.4954)
		(end 136.853168 -77.4954)
		(width 0.12446)
		(layer "B.Cu")
		(net "PHY_CONN_TO_EXP_9_DP")
	)
	(segment
		(start 107.870244 -113.468404)
		(end 104.139238 -113.468404)
		(width 0.12446)
		(layer "B.Cu")
		(net "PHY_CONN_TO_EXP_9_DP")
	)
	(segment
		(start 145.943574 -91.495372)
		(end 142.28445 -97.130616)
		(width 0.12446)
		(layer "B.Cu")
		(net "PHY_CONN_TO_EXP_9_DP")
	)
	(segment
		(start 103.105966 -115.30838)
		(end 103.10749 -115.309396)
		(width 0.12446)
		(layer "B.Cu")
		(net "PHY_CONN_TO_EXP_9_DP")
	)
	(segment
		(start 103.033576 -113.9444)
		(end 102.819962 -114.273584)
		(width 0.12446)
		(layer "B.Cu")
		(net "PHY_CONN_TO_EXP_9_DP")
	)
	(segment
		(start 141.674596 -77.722984)
		(end 143.707358 -79.043276)
		(width 0.12446)
		(layer "B.Cu")
		(net "PHY_CONN_TO_EXP_9_DP")
	)
	(segment
		(start 103.10749 -115.309396)
		(end 103.110538 -115.31092)
		(width 0.12446)
		(layer "B.Cu")
		(net "PHY_CONN_TO_EXP_9_DP")
	)
	(segment
		(start 103.102918 -115.306856)
		(end 103.105966 -115.30838)
		(width 0.12446)
		(layer "B.Cu")
		(net "PHY_CONN_TO_EXP_9_DP")
	)
	(segment
		(start 121.628408 -110.54461)
		(end 107.870244 -113.468404)
		(width 0.12446)
		(layer "B.Cu")
		(net "PHY_CONN_TO_EXP_9_DP")
	)
	(segment
		(start 103.279956 -115.260628)
		(end 103.49992 -114.84991)
		(width 0.12446)
		(layer "B.Cu")
		(net "PHY_CONN_TO_EXP_9_DP")
	)
	(segment
		(start 140.96238 -77.5716)
		(end 141.674596 -77.722984)
		(width 0.12446)
		(layer "B.Cu")
		(net "PHY_CONN_TO_EXP_9_DP")
	)
	(arc
		(start 103.1113 -115.311428)
		(mid 103.206149 -115.320958)
		(end 103.279956 -115.260628)
		(width 0.12446)
		(layer "B.Cu")
		(net "PHY_CONN_TO_EXP_9_DP")
	)
	(arc
		(start 103.042212 -115.268756)
		(mid 103.053604 -115.278611)
		(end 103.066088 -115.287044)
		(width 0.12446)
		(layer "B.Cu")
		(net "PHY_CONN_TO_EXP_9_DP")
	)
	(segment
		(start 145.375376 -83.439508)
		(end 146.30781 -87.825834)
		(width 0.12446)
		(layer "B.Cu")
		(net "PHY_CONN_TO_EXP_9_DN")
	)
	(segment
		(start 102.91064 -115.66525)
		(end 102.912418 -115.666266)
		(width 0.12446)
		(layer "B.Cu")
		(net "PHY_CONN_TO_EXP_9_DN")
	)
	(segment
		(start 145.034 -81.832958)
		(end 145.185892 -82.547714)
		(width 0.12446)
		(layer "B.Cu")
		(net "PHY_CONN_TO_EXP_9_DN")
	)
	(segment
		(start 145.056098 -83.232244)
		(end 145.375376 -83.439508)
		(width 0.12446)
		(layer "B.Cu")
		(net "PHY_CONN_TO_EXP_9_DN")
	)
	(segment
		(start 102.69474 -115.495832)
		(end 102.754684 -115.55603)
		(width 0.12446)
		(layer "B.Cu")
		(net "PHY_CONN_TO_EXP_9_DN")
	)
	(segment
		(start 121.47042 -110.16234)
		(end 107.827318 -113.062004)
		(width 0.12446)
		(layer "B.Cu")
		(net "PHY_CONN_TO_EXP_9_DN")
	)
	(segment
		(start 102.916482 -115.668552)
		(end 102.91953 -115.670076)
		(width 0.12446)
		(layer "B.Cu")
		(net "PHY_CONN_TO_EXP_9_DN")
	)
	(segment
		(start 102.437946 -114.115596)
		(end 102.336092 -114.595402)
		(width 0.12446)
		(layer "B.Cu")
		(net "PHY_CONN_TO_EXP_9_DN")
	)
	(segment
		(start 107.827318 -113.062004)
		(end 104.096312 -113.062004)
		(width 0.12446)
		(layer "B.Cu")
		(net "PHY_CONN_TO_EXP_9_DN")
	)
	(segment
		(start 141.990572 -96.836738)
		(end 121.47042 -110.16234)
		(width 0.12446)
		(layer "B.Cu")
		(net "PHY_CONN_TO_EXP_9_DN")
	)
	(segment
		(start 102.866698 -115.641628)
		(end 102.873048 -115.64493)
		(width 0.12446)
		(layer "B.Cu")
		(net "PHY_CONN_TO_EXP_9_DN")
	)
	(segment
		(start 102.91953 -115.670076)
		(end 102.919784 -115.670076)
		(width 0.12446)
		(layer "B.Cu")
		(net "PHY_CONN_TO_EXP_9_DN")
	)
	(segment
		(start 102.873048 -115.64493)
		(end 102.909624 -115.664742)
		(width 0.12446)
		(layer "B.Cu")
		(net "PHY_CONN_TO_EXP_9_DN")
	)
	(segment
		(start 136.853168 -78.0542)
		(end 136.929368 -77.978)
		(width 0.12446)
		(layer "B.Cu")
		(net "PHY_CONN_TO_EXP_9_DN")
	)
	(segment
		(start 141.5161 -78.105)
		(end 143.41348 -79.337154)
		(width 0.12446)
		(layer "B.Cu")
		(net "PHY_CONN_TO_EXP_9_DN")
	)
	(segment
		(start 103.42753 -113.204244)
		(end 102.739698 -113.650522)
		(width 0.12446)
		(layer "B.Cu")
		(net "PHY_CONN_TO_EXP_9_DN")
	)
	(segment
		(start 104.096312 -113.062004)
		(end 103.42753 -113.204244)
		(width 0.12446)
		(layer "B.Cu")
		(net "PHY_CONN_TO_EXP_9_DN")
	)
	(segment
		(start 145.561558 -91.33713)
		(end 141.990572 -96.836738)
		(width 0.12446)
		(layer "B.Cu")
		(net "PHY_CONN_TO_EXP_9_DN")
	)
	(segment
		(start 146.30781 -87.825834)
		(end 145.561558 -91.33713)
		(width 0.12446)
		(layer "B.Cu")
		(net "PHY_CONN_TO_EXP_9_DN")
	)
	(segment
		(start 102.912418 -115.666266)
		(end 102.913434 -115.666774)
		(width 0.12446)
		(layer "B.Cu")
		(net "PHY_CONN_TO_EXP_9_DN")
	)
	(segment
		(start 136.929368 -77.978)
		(end 140.919454 -77.978)
		(width 0.12446)
		(layer "B.Cu")
		(net "PHY_CONN_TO_EXP_9_DN")
	)
	(segment
		(start 145.185892 -82.547714)
		(end 144.978628 -82.866992)
		(width 0.12446)
		(layer "B.Cu")
		(net "PHY_CONN_TO_EXP_9_DN")
	)
	(segment
		(start 102.913434 -115.666774)
		(end 102.914704 -115.667536)
		(width 0.12446)
		(layer "B.Cu")
		(net "PHY_CONN_TO_EXP_9_DN")
	)
	(segment
		(start 140.919454 -77.978)
		(end 141.5161 -78.105)
		(width 0.12446)
		(layer "B.Cu")
		(net "PHY_CONN_TO_EXP_9_DN")
	)
	(segment
		(start 143.41348 -79.337154)
		(end 145.034 -81.832958)
		(width 0.12446)
		(layer "B.Cu")
		(net "PHY_CONN_TO_EXP_9_DN")
	)
	(segment
		(start 136.4742 -78.0542)
		(end 136.853168 -78.0542)
		(width 0.12446)
		(layer "B.Cu")
		(net "PHY_CONN_TO_EXP_9_DN")
	)
	(segment
		(start 102.970584 -115.838732)
		(end 102.750112 -116.249958)
		(width 0.12446)
		(layer "B.Cu")
		(net "PHY_CONN_TO_EXP_9_DN")
	)
	(segment
		(start 102.914704 -115.667536)
		(end 102.916482 -115.668552)
		(width 0.12446)
		(layer "B.Cu")
		(net "PHY_CONN_TO_EXP_9_DN")
	)
	(segment
		(start 144.978628 -82.866992)
		(end 145.056098 -83.232244)
		(width 0.12446)
		(layer "B.Cu")
		(net "PHY_CONN_TO_EXP_9_DN")
	)
	(segment
		(start 102.445058 -115.112038)
		(end 102.69474 -115.495832)
		(width 0.12446)
		(layer "B.Cu")
		(net "PHY_CONN_TO_EXP_9_DN")
	)
	(segment
		(start 102.739698 -113.650522)
		(end 102.437946 -114.115596)
		(width 0.12446)
		(layer "B.Cu")
		(net "PHY_CONN_TO_EXP_9_DN")
	)
	(segment
		(start 102.336092 -114.595402)
		(end 102.445058 -115.112038)
		(width 0.12446)
		(layer "B.Cu")
		(net "PHY_CONN_TO_EXP_9_DN")
	)
	(segment
		(start 102.909624 -115.664742)
		(end 102.91064 -115.66525)
		(width 0.12446)
		(layer "B.Cu")
		(net "PHY_CONN_TO_EXP_9_DN")
	)
	(arc
		(start 102.754684 -115.55603)
		(mid 102.807848 -115.602547)
		(end 102.866698 -115.641628)
		(width 0.12446)
		(layer "B.Cu")
		(net "PHY_CONN_TO_EXP_9_DN")
	)
	(arc
		(start 102.919784 -115.670076)
		(mid 102.980114 -115.743883)
		(end 102.970584 -115.838732)
		(width 0.12446)
		(layer "B.Cu")
		(net "PHY_CONN_TO_EXP_9_DN")
	)
	(segment
		(start 136.827768 -75.5904)
		(end 136.903968 -75.6666)
		(width 0.12446)
		(layer "B.Cu")
		(net "PHY_CONN_TO_EXP_8_DP")
	)
	(segment
		(start 147.106894 -91.970606)
		(end 143.169386 -98.034856)
		(width 0.12446)
		(layer "B.Cu")
		(net "PHY_CONN_TO_EXP_8_DP")
	)
	(segment
		(start 136.4488 -75.5904)
		(end 136.827768 -75.5904)
		(width 0.12446)
		(layer "B.Cu")
		(net "PHY_CONN_TO_EXP_8_DP")
	)
	(segment
		(start 105.357422 -115.309396)
		(end 105.36047 -115.31092)
		(width 0.12446)
		(layer "B.Cu")
		(net "PHY_CONN_TO_EXP_8_DP")
	)
	(segment
		(start 110.483904 -114.233452)
		(end 105.694226 -114.233452)
		(width 0.12446)
		(layer "B.Cu")
		(net "PHY_CONN_TO_EXP_8_DP")
	)
	(segment
		(start 105.355898 -115.30838)
		(end 105.357422 -115.309396)
		(width 0.12446)
		(layer "B.Cu")
		(net "PHY_CONN_TO_EXP_8_DP")
	)
	(segment
		(start 105.694226 -114.233452)
		(end 105.437686 -114.288062)
		(width 0.12446)
		(layer "B.Cu")
		(net "PHY_CONN_TO_EXP_8_DP")
	)
	(segment
		(start 105.437686 -114.288062)
		(end 105.281476 -114.389408)
		(width 0.12446)
		(layer "B.Cu")
		(net "PHY_CONN_TO_EXP_8_DP")
	)
	(segment
		(start 105.35285 -115.306856)
		(end 105.355898 -115.30838)
		(width 0.12446)
		(layer "B.Cu")
		(net "PHY_CONN_TO_EXP_8_DP")
	)
	(segment
		(start 145.668746 -79.758794)
		(end 147.059904 -81.900776)
		(width 0.12446)
		(layer "B.Cu")
		(net "PHY_CONN_TO_EXP_8_DP")
	)
	(segment
		(start 105.247694 -115.223036)
		(end 105.292398 -115.26901)
		(width 0.12446)
		(layer "B.Cu")
		(net "PHY_CONN_TO_EXP_8_DP")
	)
	(segment
		(start 105.36047 -115.31092)
		(end 105.361232 -115.311428)
		(width 0.12446)
		(layer "B.Cu")
		(net "PHY_CONN_TO_EXP_8_DP")
	)
	(segment
		(start 144.271492 -77.607668)
		(end 145.668746 -79.758794)
		(width 0.12446)
		(layer "B.Cu")
		(net "PHY_CONN_TO_EXP_8_DP")
	)
	(segment
		(start 105.31602 -115.287044)
		(end 105.35285 -115.306856)
		(width 0.12446)
		(layer "B.Cu")
		(net "PHY_CONN_TO_EXP_8_DP")
	)
	(segment
		(start 141.492224 -75.801728)
		(end 144.271492 -77.607668)
		(width 0.12446)
		(layer "B.Cu")
		(net "PHY_CONN_TO_EXP_8_DP")
	)
	(segment
		(start 121.992644 -111.787686)
		(end 110.483904 -114.233452)
		(width 0.12446)
		(layer "B.Cu")
		(net "PHY_CONN_TO_EXP_8_DP")
	)
	(segment
		(start 105.281476 -114.389408)
		(end 105.092754 -114.681508)
		(width 0.12446)
		(layer "B.Cu")
		(net "PHY_CONN_TO_EXP_8_DP")
	)
	(segment
		(start 148.152866 -87.045546)
		(end 147.106894 -91.970606)
		(width 0.12446)
		(layer "B.Cu")
		(net "PHY_CONN_TO_EXP_8_DP")
	)
	(segment
		(start 136.903968 -75.6666)
		(end 140.8557 -75.6666)
		(width 0.12446)
		(layer "B.Cu")
		(net "PHY_CONN_TO_EXP_8_DP")
	)
	(segment
		(start 105.529888 -115.260628)
		(end 105.750106 -114.84991)
		(width 0.12446)
		(layer "B.Cu")
		(net "PHY_CONN_TO_EXP_8_DP")
	)
	(segment
		(start 143.169386 -98.034856)
		(end 121.992644 -111.787686)
		(width 0.12446)
		(layer "B.Cu")
		(net "PHY_CONN_TO_EXP_8_DP")
	)
	(segment
		(start 140.8557 -75.6666)
		(end 141.492224 -75.801728)
		(width 0.12446)
		(layer "B.Cu")
		(net "PHY_CONN_TO_EXP_8_DP")
	)
	(segment
		(start 105.094532 -114.9858)
		(end 105.247694 -115.223036)
		(width 0.12446)
		(layer "B.Cu")
		(net "PHY_CONN_TO_EXP_8_DP")
	)
	(segment
		(start 105.092754 -114.681508)
		(end 105.061258 -114.829336)
		(width 0.12446)
		(layer "B.Cu")
		(net "PHY_CONN_TO_EXP_8_DP")
	)
	(segment
		(start 105.061258 -114.829336)
		(end 105.094532 -114.9858)
		(width 0.12446)
		(layer "B.Cu")
		(net "PHY_CONN_TO_EXP_8_DP")
	)
	(segment
		(start 147.059904 -81.900776)
		(end 148.152866 -87.045546)
		(width 0.12446)
		(layer "B.Cu")
		(net "PHY_CONN_TO_EXP_8_DP")
	)
	(arc
		(start 105.292398 -115.26901)
		(mid 105.303676 -115.278724)
		(end 105.31602 -115.287044)
		(width 0.12446)
		(layer "B.Cu")
		(net "PHY_CONN_TO_EXP_8_DP")
	)
	(arc
		(start 105.361232 -115.311428)
		(mid 105.456081 -115.320958)
		(end 105.529888 -115.260628)
		(width 0.12446)
		(layer "B.Cu")
		(net "PHY_CONN_TO_EXP_8_DP")
	)
	(segment
		(start 105.11663 -115.641628)
		(end 105.12298 -115.64493)
		(width 0.12446)
		(layer "B.Cu")
		(net "PHY_CONN_TO_EXP_8_DN")
	)
	(segment
		(start 105.169462 -115.670076)
		(end 105.169716 -115.670076)
		(width 0.12446)
		(layer "B.Cu")
		(net "PHY_CONN_TO_EXP_8_DN")
	)
	(segment
		(start 105.16235 -115.666266)
		(end 105.163366 -115.666774)
		(width 0.12446)
		(layer "B.Cu")
		(net "PHY_CONN_TO_EXP_8_DN")
	)
	(segment
		(start 142.875508 -97.740978)
		(end 121.834402 -111.405416)
		(width 0.12446)
		(layer "B.Cu")
		(net "PHY_CONN_TO_EXP_8_DN")
	)
	(segment
		(start 136.4488 -76.1492)
		(end 136.827768 -76.1492)
		(width 0.12446)
		(layer "B.Cu")
		(net "PHY_CONN_TO_EXP_8_DN")
	)
	(segment
		(start 105.163366 -115.666774)
		(end 105.164636 -115.667536)
		(width 0.12446)
		(layer "B.Cu")
		(net "PHY_CONN_TO_EXP_8_DN")
	)
	(segment
		(start 140.812774 -76.073)
		(end 141.333982 -76.183744)
		(width 0.12446)
		(layer "B.Cu")
		(net "PHY_CONN_TO_EXP_8_DN")
	)
	(segment
		(start 104.64546 -114.829082)
		(end 104.712516 -115.144042)
		(width 0.12446)
		(layer "B.Cu")
		(net "PHY_CONN_TO_EXP_8_DN")
	)
	(segment
		(start 105.164636 -115.667536)
		(end 105.166414 -115.668552)
		(width 0.12446)
		(layer "B.Cu")
		(net "PHY_CONN_TO_EXP_8_DN")
	)
	(segment
		(start 147.048982 -85.101176)
		(end 147.36826 -85.30844)
		(width 0.12446)
		(layer "B.Cu")
		(net "PHY_CONN_TO_EXP_8_DN")
	)
	(segment
		(start 105.279444 -113.906046)
		(end 104.987344 -114.095784)
		(width 0.12446)
		(layer "B.Cu")
		(net "PHY_CONN_TO_EXP_8_DN")
	)
	(segment
		(start 104.710738 -114.52352)
		(end 104.64546 -114.829082)
		(width 0.12446)
		(layer "B.Cu")
		(net "PHY_CONN_TO_EXP_8_DN")
	)
	(segment
		(start 143.977614 -77.901546)
		(end 146.677888 -82.059018)
		(width 0.12446)
		(layer "B.Cu")
		(net "PHY_CONN_TO_EXP_8_DN")
	)
	(segment
		(start 105.160572 -115.66525)
		(end 105.16235 -115.666266)
		(width 0.12446)
		(layer "B.Cu")
		(net "PHY_CONN_TO_EXP_8_DN")
	)
	(segment
		(start 105.166414 -115.668552)
		(end 105.169462 -115.670076)
		(width 0.12446)
		(layer "B.Cu")
		(net "PHY_CONN_TO_EXP_8_DN")
	)
	(segment
		(start 121.834402 -111.405416)
		(end 110.440978 -113.827052)
		(width 0.12446)
		(layer "B.Cu")
		(net "PHY_CONN_TO_EXP_8_DN")
	)
	(segment
		(start 141.333982 -76.183744)
		(end 143.977614 -77.901546)
		(width 0.12446)
		(layer "B.Cu")
		(net "PHY_CONN_TO_EXP_8_DN")
	)
	(segment
		(start 104.987344 -114.095784)
		(end 104.710738 -114.52352)
		(width 0.12446)
		(layer "B.Cu")
		(net "PHY_CONN_TO_EXP_8_DN")
	)
	(segment
		(start 105.651554 -113.827052)
		(end 105.279444 -113.906046)
		(width 0.12446)
		(layer "B.Cu")
		(net "PHY_CONN_TO_EXP_8_DN")
	)
	(segment
		(start 147.737322 -87.045546)
		(end 146.724878 -91.812364)
		(width 0.12446)
		(layer "B.Cu")
		(net "PHY_CONN_TO_EXP_8_DN")
	)
	(segment
		(start 136.827768 -76.1492)
		(end 136.903968 -76.073)
		(width 0.12446)
		(layer "B.Cu")
		(net "PHY_CONN_TO_EXP_8_DN")
	)
	(segment
		(start 146.724878 -91.812364)
		(end 142.875508 -97.740978)
		(width 0.12446)
		(layer "B.Cu")
		(net "PHY_CONN_TO_EXP_8_DN")
	)
	(segment
		(start 147.36826 -85.30844)
		(end 147.737322 -87.045546)
		(width 0.12446)
		(layer "B.Cu")
		(net "PHY_CONN_TO_EXP_8_DN")
	)
	(segment
		(start 104.930956 -115.482116)
		(end 105.004616 -115.55603)
		(width 0.12446)
		(layer "B.Cu")
		(net "PHY_CONN_TO_EXP_8_DN")
	)
	(segment
		(start 146.677888 -82.059018)
		(end 147.178776 -84.416646)
		(width 0.12446)
		(layer "B.Cu")
		(net "PHY_CONN_TO_EXP_8_DN")
	)
	(segment
		(start 136.903968 -76.073)
		(end 140.812774 -76.073)
		(width 0.12446)
		(layer "B.Cu")
		(net "PHY_CONN_TO_EXP_8_DN")
	)
	(segment
		(start 104.712516 -115.144042)
		(end 104.930956 -115.482116)
		(width 0.12446)
		(layer "B.Cu")
		(net "PHY_CONN_TO_EXP_8_DN")
	)
	(segment
		(start 147.178776 -84.416646)
		(end 146.971258 -84.735924)
		(width 0.12446)
		(layer "B.Cu")
		(net "PHY_CONN_TO_EXP_8_DN")
	)
	(segment
		(start 105.12298 -115.64493)
		(end 105.159556 -115.664742)
		(width 0.12446)
		(layer "B.Cu")
		(net "PHY_CONN_TO_EXP_8_DN")
	)
	(segment
		(start 110.440978 -113.827052)
		(end 105.651554 -113.827052)
		(width 0.12446)
		(layer "B.Cu")
		(net "PHY_CONN_TO_EXP_8_DN")
	)
	(segment
		(start 105.220516 -115.838732)
		(end 105.000044 -116.249958)
		(width 0.12446)
		(layer "B.Cu")
		(net "PHY_CONN_TO_EXP_8_DN")
	)
	(segment
		(start 105.159556 -115.664742)
		(end 105.160572 -115.66525)
		(width 0.12446)
		(layer "B.Cu")
		(net "PHY_CONN_TO_EXP_8_DN")
	)
	(segment
		(start 146.971258 -84.735924)
		(end 147.048982 -85.101176)
		(width 0.12446)
		(layer "B.Cu")
		(net "PHY_CONN_TO_EXP_8_DN")
	)
	(arc
		(start 105.004616 -115.55603)
		(mid 105.05778 -115.602547)
		(end 105.11663 -115.641628)
		(width 0.12446)
		(layer "B.Cu")
		(net "PHY_CONN_TO_EXP_8_DN")
	)
	(arc
		(start 105.169716 -115.670076)
		(mid 105.230046 -115.743883)
		(end 105.220516 -115.838732)
		(width 0.12446)
		(layer "B.Cu")
		(net "PHY_CONN_TO_EXP_8_DN")
	)
	(segment
		(start 140.411454 -95.415862)
		(end 121.352056 -107.793536)
		(width 0.12446)
		(layer "B.Cu")
		(net "PHY_CONN_TO_EXP_11_DP")
	)
	(segment
		(start 103.006652 -111.433102)
		(end 103.04272 -111.46917)
		(width 0.12446)
		(layer "B.Cu")
		(net "PHY_CONN_TO_EXP_11_DP")
	)
	(segment
		(start 103.102918 -111.507016)
		(end 103.105966 -111.50854)
		(width 0.12446)
		(layer "B.Cu")
		(net "PHY_CONN_TO_EXP_11_DP")
	)
	(segment
		(start 103.110538 -111.51108)
		(end 103.1113 -111.511588)
		(width 0.12446)
		(layer "B.Cu")
		(net "PHY_CONN_TO_EXP_11_DP")
	)
	(segment
		(start 142.464282 -82.436716)
		(end 143.719296 -88.338914)
		(width 0.12446)
		(layer "B.Cu")
		(net "PHY_CONN_TO_EXP_11_DP")
	)
	(segment
		(start 121.352056 -107.793536)
		(end 112.493298 -109.676946)
		(width 0.12446)
		(layer "B.Cu")
		(net "PHY_CONN_TO_EXP_11_DP")
	)
	(segment
		(start 104.099868 -109.676946)
		(end 103.585518 -109.78642)
		(width 0.12446)
		(layer "B.Cu")
		(net "PHY_CONN_TO_EXP_11_DP")
	)
	(segment
		(start 103.10749 -111.509556)
		(end 103.110538 -111.51108)
		(width 0.12446)
		(layer "B.Cu")
		(net "PHY_CONN_TO_EXP_11_DP")
	)
	(segment
		(start 103.585518 -109.78642)
		(end 102.991666 -110.171992)
		(width 0.12446)
		(layer "B.Cu")
		(net "PHY_CONN_TO_EXP_11_DP")
	)
	(segment
		(start 103.066088 -111.487204)
		(end 103.102918 -111.507016)
		(width 0.12446)
		(layer "B.Cu")
		(net "PHY_CONN_TO_EXP_11_DP")
	)
	(segment
		(start 103.105966 -111.50854)
		(end 103.10749 -111.509556)
		(width 0.12446)
		(layer "B.Cu")
		(net "PHY_CONN_TO_EXP_11_DP")
	)
	(segment
		(start 136.903968 -80.5688)
		(end 136.980168 -80.645)
		(width 0.12446)
		(layer "B.Cu")
		(net "PHY_CONN_TO_EXP_11_DP")
	)
	(segment
		(start 136.980168 -80.645)
		(end 140.160756 -80.645)
		(width 0.12446)
		(layer "B.Cu")
		(net "PHY_CONN_TO_EXP_11_DP")
	)
	(segment
		(start 112.493298 -109.676946)
		(end 104.099868 -109.676946)
		(width 0.12446)
		(layer "B.Cu")
		(net "PHY_CONN_TO_EXP_11_DP")
	)
	(segment
		(start 102.817168 -110.440724)
		(end 102.733348 -110.838742)
		(width 0.12446)
		(layer "B.Cu")
		(net "PHY_CONN_TO_EXP_11_DP")
	)
	(segment
		(start 143.092678 -91.287854)
		(end 140.411454 -95.415862)
		(width 0.12446)
		(layer "B.Cu")
		(net "PHY_CONN_TO_EXP_11_DP")
	)
	(segment
		(start 140.160756 -80.645)
		(end 140.996924 -80.822546)
		(width 0.12446)
		(layer "B.Cu")
		(net "PHY_CONN_TO_EXP_11_DP")
	)
	(segment
		(start 102.787196 -111.09579)
		(end 103.006652 -111.433102)
		(width 0.12446)
		(layer "B.Cu")
		(net "PHY_CONN_TO_EXP_11_DP")
	)
	(segment
		(start 103.279956 -111.460788)
		(end 103.49992 -111.05007)
		(width 0.12446)
		(layer "B.Cu")
		(net "PHY_CONN_TO_EXP_11_DP")
	)
	(segment
		(start 143.093186 -91.287854)
		(end 143.092678 -91.287854)
		(width 0.12446)
		(layer "B.Cu")
		(net "PHY_CONN_TO_EXP_11_DP")
	)
	(segment
		(start 136.525 -80.5688)
		(end 136.903968 -80.5688)
		(width 0.12446)
		(layer "B.Cu")
		(net "PHY_CONN_TO_EXP_11_DP")
	)
	(segment
		(start 141.721586 -81.293462)
		(end 142.464282 -82.436716)
		(width 0.12446)
		(layer "B.Cu")
		(net "PHY_CONN_TO_EXP_11_DP")
	)
	(segment
		(start 102.991666 -110.171992)
		(end 102.817168 -110.440724)
		(width 0.12446)
		(layer "B.Cu")
		(net "PHY_CONN_TO_EXP_11_DP")
	)
	(segment
		(start 140.996924 -80.822546)
		(end 141.721586 -81.293462)
		(width 0.12446)
		(layer "B.Cu")
		(net "PHY_CONN_TO_EXP_11_DP")
	)
	(segment
		(start 102.733348 -110.838742)
		(end 102.787196 -111.09579)
		(width 0.12446)
		(layer "B.Cu")
		(net "PHY_CONN_TO_EXP_11_DP")
	)
	(segment
		(start 143.719296 -88.338914)
		(end 143.093186 -91.287854)
		(width 0.12446)
		(layer "B.Cu")
		(net "PHY_CONN_TO_EXP_11_DP")
	)
	(arc
		(start 103.04272 -111.46917)
		(mid 103.053863 -111.478888)
		(end 103.066088 -111.487204)
		(width 0.12446)
		(layer "B.Cu")
		(net "PHY_CONN_TO_EXP_11_DP")
	)
	(arc
		(start 103.1113 -111.511588)
		(mid 103.206149 -111.521118)
		(end 103.279956 -111.460788)
		(width 0.12446)
		(layer "B.Cu")
		(net "PHY_CONN_TO_EXP_11_DP")
	)
	(segment
		(start 102.914704 -111.867696)
		(end 102.916482 -111.868712)
		(width 0.12446)
		(layer "B.Cu")
		(net "PHY_CONN_TO_EXP_11_DN")
	)
	(segment
		(start 112.450372 -109.270546)
		(end 104.056942 -109.270546)
		(width 0.12446)
		(layer "B.Cu")
		(net "PHY_CONN_TO_EXP_11_DN")
	)
	(segment
		(start 102.404926 -111.253778)
		(end 102.689152 -111.690404)
		(width 0.12446)
		(layer "B.Cu")
		(net "PHY_CONN_TO_EXP_11_DN")
	)
	(segment
		(start 142.402306 -84.100924)
		(end 143.303752 -88.338914)
		(width 0.12446)
		(layer "B.Cu")
		(net "PHY_CONN_TO_EXP_11_DN")
	)
	(segment
		(start 142.212568 -83.208876)
		(end 142.005304 -83.528154)
		(width 0.12446)
		(layer "B.Cu")
		(net "PHY_CONN_TO_EXP_11_DN")
	)
	(segment
		(start 140.11783 -81.0514)
		(end 140.838682 -81.204562)
		(width 0.12446)
		(layer "B.Cu")
		(net "PHY_CONN_TO_EXP_11_DN")
	)
	(segment
		(start 103.42753 -109.404404)
		(end 102.697788 -109.878114)
		(width 0.12446)
		(layer "B.Cu")
		(net "PHY_CONN_TO_EXP_11_DN")
	)
	(segment
		(start 102.970584 -112.038892)
		(end 102.750112 -112.450118)
		(width 0.12446)
		(layer "B.Cu")
		(net "PHY_CONN_TO_EXP_11_DN")
	)
	(segment
		(start 102.317804 -110.838488)
		(end 102.404926 -111.253778)
		(width 0.12446)
		(layer "B.Cu")
		(net "PHY_CONN_TO_EXP_11_DN")
	)
	(segment
		(start 104.056942 -109.270546)
		(end 103.42753 -109.404404)
		(width 0.12446)
		(layer "B.Cu")
		(net "PHY_CONN_TO_EXP_11_DN")
	)
	(segment
		(start 142.711424 -91.128596)
		(end 142.710662 -91.129612)
		(width 0.12446)
		(layer "B.Cu")
		(net "PHY_CONN_TO_EXP_11_DN")
	)
	(segment
		(start 102.909624 -111.864902)
		(end 102.91064 -111.86541)
		(width 0.12446)
		(layer "B.Cu")
		(net "PHY_CONN_TO_EXP_11_DN")
	)
	(segment
		(start 102.91064 -111.86541)
		(end 102.912418 -111.866426)
		(width 0.12446)
		(layer "B.Cu")
		(net "PHY_CONN_TO_EXP_11_DN")
	)
	(segment
		(start 140.838682 -81.204562)
		(end 141.427708 -81.58734)
		(width 0.12446)
		(layer "B.Cu")
		(net "PHY_CONN_TO_EXP_11_DN")
	)
	(segment
		(start 102.91953 -111.870236)
		(end 102.919784 -111.870236)
		(width 0.12446)
		(layer "B.Cu")
		(net "PHY_CONN_TO_EXP_11_DN")
	)
	(segment
		(start 141.427708 -81.58734)
		(end 142.082012 -82.59445)
		(width 0.12446)
		(layer "B.Cu")
		(net "PHY_CONN_TO_EXP_11_DN")
	)
	(segment
		(start 102.697788 -109.878114)
		(end 102.435152 -110.282736)
		(width 0.12446)
		(layer "B.Cu")
		(net "PHY_CONN_TO_EXP_11_DN")
	)
	(segment
		(start 140.117576 -95.121984)
		(end 121.193814 -107.41152)
		(width 0.12446)
		(layer "B.Cu")
		(net "PHY_CONN_TO_EXP_11_DN")
	)
	(segment
		(start 136.980168 -81.0514)
		(end 140.11783 -81.0514)
		(width 0.12446)
		(layer "B.Cu")
		(net "PHY_CONN_TO_EXP_11_DN")
	)
	(segment
		(start 102.873048 -111.84509)
		(end 102.909624 -111.864902)
		(width 0.12446)
		(layer "B.Cu")
		(net "PHY_CONN_TO_EXP_11_DN")
	)
	(segment
		(start 143.303752 -88.338914)
		(end 142.711424 -91.128596)
		(width 0.12446)
		(layer "B.Cu")
		(net "PHY_CONN_TO_EXP_11_DN")
	)
	(segment
		(start 102.689152 -111.690404)
		(end 102.754684 -111.75619)
		(width 0.12446)
		(layer "B.Cu")
		(net "PHY_CONN_TO_EXP_11_DN")
	)
	(segment
		(start 121.193814 -107.41152)
		(end 112.450372 -109.270546)
		(width 0.12446)
		(layer "B.Cu")
		(net "PHY_CONN_TO_EXP_11_DN")
	)
	(segment
		(start 102.913434 -111.866934)
		(end 102.914704 -111.867696)
		(width 0.12446)
		(layer "B.Cu")
		(net "PHY_CONN_TO_EXP_11_DN")
	)
	(segment
		(start 136.903968 -81.1276)
		(end 136.980168 -81.0514)
		(width 0.12446)
		(layer "B.Cu")
		(net "PHY_CONN_TO_EXP_11_DN")
	)
	(segment
		(start 136.525 -81.1276)
		(end 136.903968 -81.1276)
		(width 0.12446)
		(layer "B.Cu")
		(net "PHY_CONN_TO_EXP_11_DN")
	)
	(segment
		(start 142.005304 -83.528154)
		(end 142.083028 -83.893406)
		(width 0.12446)
		(layer "B.Cu")
		(net "PHY_CONN_TO_EXP_11_DN")
	)
	(segment
		(start 142.083028 -83.893406)
		(end 142.402306 -84.100924)
		(width 0.12446)
		(layer "B.Cu")
		(net "PHY_CONN_TO_EXP_11_DN")
	)
	(segment
		(start 102.435152 -110.282736)
		(end 102.317804 -110.838488)
		(width 0.12446)
		(layer "B.Cu")
		(net "PHY_CONN_TO_EXP_11_DN")
	)
	(segment
		(start 142.082012 -82.59445)
		(end 142.212568 -83.208876)
		(width 0.12446)
		(layer "B.Cu")
		(net "PHY_CONN_TO_EXP_11_DN")
	)
	(segment
		(start 102.912418 -111.866426)
		(end 102.913434 -111.866934)
		(width 0.12446)
		(layer "B.Cu")
		(net "PHY_CONN_TO_EXP_11_DN")
	)
	(segment
		(start 102.916482 -111.868712)
		(end 102.91953 -111.870236)
		(width 0.12446)
		(layer "B.Cu")
		(net "PHY_CONN_TO_EXP_11_DN")
	)
	(segment
		(start 142.710662 -91.129612)
		(end 140.117576 -95.121984)
		(width 0.12446)
		(layer "B.Cu")
		(net "PHY_CONN_TO_EXP_11_DN")
	)
	(segment
		(start 102.866698 -111.841788)
		(end 102.873048 -111.84509)
		(width 0.12446)
		(layer "B.Cu")
		(net "PHY_CONN_TO_EXP_11_DN")
	)
	(arc
		(start 102.754684 -111.75619)
		(mid 102.807848 -111.802707)
		(end 102.866698 -111.841788)
		(width 0.12446)
		(layer "B.Cu")
		(net "PHY_CONN_TO_EXP_11_DN")
	)
	(arc
		(start 102.919784 -111.870236)
		(mid 102.980114 -111.944043)
		(end 102.970584 -112.038892)
		(width 0.12446)
		(layer "B.Cu")
		(net "PHY_CONN_TO_EXP_11_DN")
	)
	(segment
		(start 113.450878 -110.923832)
		(end 109.007148 -110.923832)
		(width 0.12446)
		(layer "B.Cu")
		(net "PHY_CONN_TO_EXP_10_DP")
	)
	(segment
		(start 105.529888 -111.460788)
		(end 105.750106 -111.05007)
		(width 0.12446)
		(layer "B.Cu")
		(net "PHY_CONN_TO_EXP_10_DP")
	)
	(segment
		(start 136.878568 -79.0448)
		(end 136.954768 -79.121)
		(width 0.12446)
		(layer "B.Cu")
		(net "PHY_CONN_TO_EXP_10_DP")
	)
	(segment
		(start 105.36047 -111.51108)
		(end 105.361232 -111.511588)
		(width 0.12446)
		(layer "B.Cu")
		(net "PHY_CONN_TO_EXP_10_DP")
	)
	(segment
		(start 105.437686 -110.488222)
		(end 105.19283 -110.647226)
		(width 0.12446)
		(layer "B.Cu")
		(net "PHY_CONN_TO_EXP_10_DP")
	)
	(segment
		(start 121.38787 -109.237272)
		(end 113.450878 -110.923832)
		(width 0.12446)
		(layer "B.Cu")
		(net "PHY_CONN_TO_EXP_10_DP")
	)
	(segment
		(start 108.507276 -110.42396)
		(end 105.739692 -110.42396)
		(width 0.12446)
		(layer "B.Cu")
		(net "PHY_CONN_TO_EXP_10_DP")
	)
	(segment
		(start 143.10106 -80.831944)
		(end 143.91132 -82.079338)
		(width 0.12446)
		(layer "B.Cu")
		(net "PHY_CONN_TO_EXP_10_DP")
	)
	(segment
		(start 105.19283 -110.647226)
		(end 105.072942 -110.83163)
		(width 0.12446)
		(layer "B.Cu")
		(net "PHY_CONN_TO_EXP_10_DP")
	)
	(segment
		(start 105.256076 -111.431832)
		(end 105.292398 -111.46917)
		(width 0.12446)
		(layer "B.Cu")
		(net "PHY_CONN_TO_EXP_10_DP")
	)
	(segment
		(start 143.91132 -82.079338)
		(end 145.159222 -87.954866)
		(width 0.12446)
		(layer "B.Cu")
		(net "PHY_CONN_TO_EXP_10_DP")
	)
	(segment
		(start 105.037128 -111.000794)
		(end 105.066338 -111.138208)
		(width 0.12446)
		(layer "B.Cu")
		(net "PHY_CONN_TO_EXP_10_DP")
	)
	(segment
		(start 105.355898 -111.50854)
		(end 105.357422 -111.509556)
		(width 0.12446)
		(layer "B.Cu")
		(net "PHY_CONN_TO_EXP_10_DP")
	)
	(segment
		(start 105.739692 -110.42396)
		(end 105.437686 -110.488222)
		(width 0.12446)
		(layer "B.Cu")
		(net "PHY_CONN_TO_EXP_10_DP")
	)
	(segment
		(start 145.159222 -87.954866)
		(end 144.388332 -91.584272)
		(width 0.12446)
		(layer "B.Cu")
		(net "PHY_CONN_TO_EXP_10_DP")
	)
	(segment
		(start 141.3383 -96.27997)
		(end 121.38787 -109.237272)
		(width 0.12446)
		(layer "B.Cu")
		(net "PHY_CONN_TO_EXP_10_DP")
	)
	(segment
		(start 109.007148 -110.923832)
		(end 108.507276 -110.42396)
		(width 0.12446)
		(layer "B.Cu")
		(net "PHY_CONN_TO_EXP_10_DP")
	)
	(segment
		(start 140.768578 -79.121)
		(end 141.558518 -79.289148)
		(width 0.12446)
		(layer "B.Cu")
		(net "PHY_CONN_TO_EXP_10_DP")
	)
	(segment
		(start 144.388332 -91.584272)
		(end 141.3383 -96.27997)
		(width 0.12446)
		(layer "B.Cu")
		(net "PHY_CONN_TO_EXP_10_DP")
	)
	(segment
		(start 136.4996 -79.0448)
		(end 136.878568 -79.0448)
		(width 0.12446)
		(layer "B.Cu")
		(net "PHY_CONN_TO_EXP_10_DP")
	)
	(segment
		(start 105.072942 -110.83163)
		(end 105.037128 -111.000794)
		(width 0.12446)
		(layer "B.Cu")
		(net "PHY_CONN_TO_EXP_10_DP")
	)
	(segment
		(start 105.35285 -111.507016)
		(end 105.355898 -111.50854)
		(width 0.12446)
		(layer "B.Cu")
		(net "PHY_CONN_TO_EXP_10_DP")
	)
	(segment
		(start 141.558518 -79.289148)
		(end 143.10106 -80.831944)
		(width 0.12446)
		(layer "B.Cu")
		(net "PHY_CONN_TO_EXP_10_DP")
	)
	(segment
		(start 136.954768 -79.121)
		(end 140.768578 -79.121)
		(width 0.12446)
		(layer "B.Cu")
		(net "PHY_CONN_TO_EXP_10_DP")
	)
	(segment
		(start 105.357422 -111.509556)
		(end 105.36047 -111.51108)
		(width 0.12446)
		(layer "B.Cu")
		(net "PHY_CONN_TO_EXP_10_DP")
	)
	(segment
		(start 105.066338 -111.138208)
		(end 105.256076 -111.431832)
		(width 0.12446)
		(layer "B.Cu")
		(net "PHY_CONN_TO_EXP_10_DP")
	)
	(segment
		(start 105.31602 -111.487204)
		(end 105.35285 -111.507016)
		(width 0.12446)
		(layer "B.Cu")
		(net "PHY_CONN_TO_EXP_10_DP")
	)
	(arc
		(start 105.361232 -111.511588)
		(mid 105.456081 -111.521118)
		(end 105.529888 -111.460788)
		(width 0.12446)
		(layer "B.Cu")
		(net "PHY_CONN_TO_EXP_10_DP")
	)
	(arc
		(start 105.292398 -111.46917)
		(mid 105.303676 -111.478884)
		(end 105.31602 -111.487204)
		(width 0.12446)
		(layer "B.Cu")
		(net "PHY_CONN_TO_EXP_10_DP")
	)
	(segment
		(start 105.220516 -112.038892)
		(end 105.000044 -112.450118)
		(width 0.12446)
		(layer "B.Cu")
		(net "PHY_CONN_TO_EXP_10_DN")
	)
	(segment
		(start 105.160572 -111.86541)
		(end 105.16235 -111.866426)
		(width 0.12446)
		(layer "B.Cu")
		(net "PHY_CONN_TO_EXP_10_DN")
	)
	(segment
		(start 144.006316 -91.42603)
		(end 141.044422 -95.986092)
		(width 0.12446)
		(layer "B.Cu")
		(net "PHY_CONN_TO_EXP_10_DN")
	)
	(segment
		(start 105.169462 -111.870236)
		(end 105.169716 -111.870236)
		(width 0.12446)
		(layer "B.Cu")
		(net "PHY_CONN_TO_EXP_10_DN")
	)
	(segment
		(start 136.954768 -79.5274)
		(end 140.725652 -79.5274)
		(width 0.12446)
		(layer "B.Cu")
		(net "PHY_CONN_TO_EXP_10_DN")
	)
	(segment
		(start 105.11663 -111.841788)
		(end 105.12298 -111.84509)
		(width 0.12446)
		(layer "B.Cu")
		(net "PHY_CONN_TO_EXP_10_DN")
	)
	(segment
		(start 105.166414 -111.868712)
		(end 105.169462 -111.870236)
		(width 0.12446)
		(layer "B.Cu")
		(net "PHY_CONN_TO_EXP_10_DN")
	)
	(segment
		(start 104.621584 -111.000794)
		(end 104.684322 -111.295942)
		(width 0.12446)
		(layer "B.Cu")
		(net "PHY_CONN_TO_EXP_10_DN")
	)
	(segment
		(start 104.939592 -111.690912)
		(end 105.004616 -111.75619)
		(width 0.12446)
		(layer "B.Cu")
		(net "PHY_CONN_TO_EXP_10_DN")
	)
	(segment
		(start 108.675678 -110.01756)
		(end 105.69702 -110.01756)
		(width 0.12446)
		(layer "B.Cu")
		(net "PHY_CONN_TO_EXP_10_DN")
	)
	(segment
		(start 136.4996 -79.6036)
		(end 136.878568 -79.6036)
		(width 0.12446)
		(layer "B.Cu")
		(net "PHY_CONN_TO_EXP_10_DN")
	)
	(segment
		(start 105.163366 -111.866934)
		(end 105.164636 -111.867696)
		(width 0.12446)
		(layer "B.Cu")
		(net "PHY_CONN_TO_EXP_10_DN")
	)
	(segment
		(start 140.725652 -79.5274)
		(end 141.35608 -79.661766)
		(width 0.12446)
		(layer "B.Cu")
		(net "PHY_CONN_TO_EXP_10_DN")
	)
	(segment
		(start 104.898952 -110.353348)
		(end 104.690926 -110.673642)
		(width 0.12446)
		(layer "B.Cu")
		(net "PHY_CONN_TO_EXP_10_DN")
	)
	(segment
		(start 105.69702 -110.01756)
		(end 105.279444 -110.106206)
		(width 0.12446)
		(layer "B.Cu")
		(net "PHY_CONN_TO_EXP_10_DN")
	)
	(segment
		(start 144.297146 -85.852762)
		(end 144.743678 -87.954866)
		(width 0.12446)
		(layer "B.Cu")
		(net "PHY_CONN_TO_EXP_10_DN")
	)
	(segment
		(start 104.684322 -111.295942)
		(end 104.939592 -111.690912)
		(width 0.12446)
		(layer "B.Cu")
		(net "PHY_CONN_TO_EXP_10_DN")
	)
	(segment
		(start 136.878568 -79.6036)
		(end 136.954768 -79.5274)
		(width 0.12446)
		(layer "B.Cu")
		(net "PHY_CONN_TO_EXP_10_DN")
	)
	(segment
		(start 121.229628 -108.855002)
		(end 113.407952 -110.517432)
		(width 0.12446)
		(layer "B.Cu")
		(net "PHY_CONN_TO_EXP_10_DN")
	)
	(segment
		(start 142.78356 -81.089246)
		(end 143.528796 -82.236564)
		(width 0.12446)
		(layer "B.Cu")
		(net "PHY_CONN_TO_EXP_10_DN")
	)
	(segment
		(start 113.407952 -110.517432)
		(end 109.17555 -110.517432)
		(width 0.12446)
		(layer "B.Cu")
		(net "PHY_CONN_TO_EXP_10_DN")
	)
	(segment
		(start 109.17555 -110.517432)
		(end 108.675678 -110.01756)
		(width 0.12446)
		(layer "B.Cu")
		(net "PHY_CONN_TO_EXP_10_DN")
	)
	(segment
		(start 143.529304 -82.23758)
		(end 144.107662 -84.960714)
		(width 0.12446)
		(layer "B.Cu")
		(net "PHY_CONN_TO_EXP_10_DN")
	)
	(segment
		(start 143.900398 -85.279992)
		(end 143.977868 -85.645244)
		(width 0.12446)
		(layer "B.Cu")
		(net "PHY_CONN_TO_EXP_10_DN")
	)
	(segment
		(start 143.528542 -82.236564)
		(end 143.529304 -82.23758)
		(width 0.12446)
		(layer "B.Cu")
		(net "PHY_CONN_TO_EXP_10_DN")
	)
	(segment
		(start 105.279444 -110.106206)
		(end 104.898952 -110.353348)
		(width 0.12446)
		(layer "B.Cu")
		(net "PHY_CONN_TO_EXP_10_DN")
	)
	(segment
		(start 144.743678 -87.954866)
		(end 144.006316 -91.42603)
		(width 0.12446)
		(layer "B.Cu")
		(net "PHY_CONN_TO_EXP_10_DN")
	)
	(segment
		(start 141.35608 -79.661766)
		(end 142.78356 -81.089246)
		(width 0.12446)
		(layer "B.Cu")
		(net "PHY_CONN_TO_EXP_10_DN")
	)
	(segment
		(start 105.16235 -111.866426)
		(end 105.163366 -111.866934)
		(width 0.12446)
		(layer "B.Cu")
		(net "PHY_CONN_TO_EXP_10_DN")
	)
	(segment
		(start 144.107662 -84.960714)
		(end 143.900398 -85.279992)
		(width 0.12446)
		(layer "B.Cu")
		(net "PHY_CONN_TO_EXP_10_DN")
	)
	(segment
		(start 143.977868 -85.645244)
		(end 144.297146 -85.852762)
		(width 0.12446)
		(layer "B.Cu")
		(net "PHY_CONN_TO_EXP_10_DN")
	)
	(segment
		(start 105.159556 -111.864902)
		(end 105.160572 -111.86541)
		(width 0.12446)
		(layer "B.Cu")
		(net "PHY_CONN_TO_EXP_10_DN")
	)
	(segment
		(start 143.528796 -82.236564)
		(end 143.528542 -82.236564)
		(width 0.12446)
		(layer "B.Cu")
		(net "PHY_CONN_TO_EXP_10_DN")
	)
	(segment
		(start 105.164636 -111.867696)
		(end 105.166414 -111.868712)
		(width 0.12446)
		(layer "B.Cu")
		(net "PHY_CONN_TO_EXP_10_DN")
	)
	(segment
		(start 141.044422 -95.986092)
		(end 121.229628 -108.855002)
		(width 0.12446)
		(layer "B.Cu")
		(net "PHY_CONN_TO_EXP_10_DN")
	)
	(segment
		(start 104.690926 -110.673642)
		(end 104.621584 -111.000794)
		(width 0.12446)
		(layer "B.Cu")
		(net "PHY_CONN_TO_EXP_10_DN")
	)
	(segment
		(start 105.12298 -111.84509)
		(end 105.159556 -111.864902)
		(width 0.12446)
		(layer "B.Cu")
		(net "PHY_CONN_TO_EXP_10_DN")
	)
	(arc
		(start 105.004616 -111.75619)
		(mid 105.05778 -111.802707)
		(end 105.11663 -111.841788)
		(width 0.12446)
		(layer "B.Cu")
		(net "PHY_CONN_TO_EXP_10_DN")
	)
	(arc
		(start 105.169716 -111.870236)
		(mid 105.230046 -111.944043)
		(end 105.220516 -112.038892)
		(width 0.12446)
		(layer "B.Cu")
		(net "PHY_CONN_TO_EXP_10_DN")
	)
	(segment
		(start 181.4576 -112.395)
		(end 181.1274 -112.0648)
		(width 0.127)
		(layer "F.Cu")
		(net "P1V8_C_PG_R_1")
	)
	(segment
		(start 180.3908 -110.35792)
		(end 179.35448 -110.35792)
		(width 0.127)
		(layer "F.Cu")
		(net "P1V8_C_PG_R_1")
	)
	(segment
		(start 181.56428 -112.395)
		(end 181.4576 -112.395)
		(width 0.127)
		(layer "F.Cu")
		(net "P1V8_C_PG_R_1")
	)
	(segment
		(start 181.1274 -112.0648)
		(end 181.1274 -111.09452)
		(width 0.127)
		(layer "F.Cu")
		(net "P1V8_C_PG_R_1")
	)
	(segment
		(start 181.1274 -111.09452)
		(end 180.3908 -110.35792)
		(width 0.127)
		(layer "F.Cu")
		(net "P1V8_C_PG_R_1")
	)
	(segment
		(start 182.8419 -111.11738)
		(end 181.56428 -112.395)
		(width 0.127)
		(layer "F.Cu")
		(net "P1V8_C_PG_R_1")
	)
	(via
		(at 181.4576 -112.395)
		(size 0.6604)
		(drill 0.3302)
		(layers "F.Cu" "B.Cu")
		(net "P1V8_C_PG_R_1")
	)
	(segment
		(start 171.7675 -103.505)
		(end 172.86224 -103.505)
		(width 0.127)
		(layer "F.Cu")
		(net "P1V8_C_G")
	)
	(segment
		(start 173.48073 -103.505)
		(end 174.50181 -104.52608)
		(width 0.127)
		(layer "F.Cu")
		(net "P1V8_C_G")
	)
	(segment
		(start 172.86224 -103.505)
		(end 173.48073 -103.505)
		(width 0.127)
		(layer "F.Cu")
		(net "P1V8_C_G")
	)
	(via
		(at 172.86224 -103.505)
		(size 0.6604)
		(drill 0.3302)
		(layers "F.Cu" "B.Cu")
		(net "P1V8_C_G")
	)
	(segment
		(start 107.499912 -75.50023)
		(end 107.00004 -75.000358)
		(width 0.127)
		(layer "F.Cu")
		(net "LED11")
	)
	(via
		(at 107.00004 -75.000358)
		(size 0.4572)
		(drill 0.2032)
		(layers "F.Cu" "B.Cu")
		(net "LED11")
	)
	(segment
		(start 107.00004 -75.000358)
		(end 106.500168 -75.50023)
		(width 0.127)
		(layer "B.Cu")
		(net "LED11")
	)
	(segment
		(start 102.499922 -63.5)
		(end 102.00005 -63.000128)
		(width 0.127)
		(layer "F.Cu")
		(net "DRIVE_15_ACT")
	)
	(segment
		(start 124.940822 -21.314664)
		(end 124.940822 -9.459468)
		(width 0.127)
		(layer "F.Cu")
		(net "DRIVE_15_ACT")
	)
	(segment
		(start 124.940822 -9.459468)
		(end 125.600206 -8.800084)
		(width 0.127)
		(layer "F.Cu")
		(net "DRIVE_15_ACT")
	)
	(segment
		(start 119.516398 -26.739088)
		(end 124.940822 -21.314664)
		(width 0.127)
		(layer "F.Cu")
		(net "DRIVE_15_ACT")
	)
	(segment
		(start 118.810024 -27.445462)
		(end 119.516398 -26.739088)
		(width 0.127)
		(layer "F.Cu")
		(net "DRIVE_15_ACT")
	)
	(segment
		(start 83.492594 -27.445462)
		(end 118.810024 -27.445462)
		(width 0.127)
		(layer "F.Cu")
		(net "DRIVE_15_ACT")
	)
	(via
		(at 83.492594 -27.445462)
		(size 0.508)
		(drill 0.254)
		(layers "F.Cu" "B.Cu")
		(net "DRIVE_15_ACT")
	)
	(via
		(at 119.516398 -26.739088)
		(size 0.6604)
		(drill 0.3302)
		(layers "F.Cu" "B.Cu")
		(net "DRIVE_15_ACT")
	)
	(via
		(at 102.00005 -63.000128)
		(size 0.4572)
		(drill 0.2032)
		(layers "F.Cu" "B.Cu")
		(net "DRIVE_15_ACT")
	)
	(segment
		(start 84.746846 -32.157162)
		(end 84.746846 -28.699714)
		(width 0.127)
		(layer "In5.Cu")
		(net "DRIVE_15_ACT")
	)
	(segment
		(start 102.00005 -63.000128)
		(end 101.638608 -63.36157)
		(width 0.127)
		(layer "In5.Cu")
		(net "DRIVE_15_ACT")
	)
	(segment
		(start 98.56597 -63.36157)
		(end 89.55278 -54.34838)
		(width 0.127)
		(layer "In5.Cu")
		(net "DRIVE_15_ACT")
	)
	(segment
		(start 85.22589 -37.378132)
		(end 85.22589 -32.636206)
		(width 0.127)
		(layer "In5.Cu")
		(net "DRIVE_15_ACT")
	)
	(segment
		(start 86.329266 -38.481508)
		(end 85.22589 -37.378132)
		(width 0.127)
		(layer "In5.Cu")
		(net "DRIVE_15_ACT")
	)
	(segment
		(start 85.22589 -32.636206)
		(end 84.746846 -32.157162)
		(width 0.127)
		(layer "In5.Cu")
		(net "DRIVE_15_ACT")
	)
	(segment
		(start 86.329266 -48.730662)
		(end 86.329266 -38.481508)
		(width 0.127)
		(layer "In5.Cu")
		(net "DRIVE_15_ACT")
	)
	(segment
		(start 101.638608 -63.36157)
		(end 98.56597 -63.36157)
		(width 0.127)
		(layer "In5.Cu")
		(net "DRIVE_15_ACT")
	)
	(segment
		(start 89.55278 -54.34838)
		(end 89.55278 -51.954176)
		(width 0.127)
		(layer "In5.Cu")
		(net "DRIVE_15_ACT")
	)
	(segment
		(start 84.746846 -28.699714)
		(end 83.492594 -27.445462)
		(width 0.127)
		(layer "In5.Cu")
		(net "DRIVE_15_ACT")
	)
	(segment
		(start 89.55278 -51.954176)
		(end 86.329266 -48.730662)
		(width 0.127)
		(layer "In5.Cu")
		(net "DRIVE_15_ACT")
	)
	(segment
		(start 100.106226 -63.1063)
		(end 100.499926 -63.5)
		(width 0.127)
		(layer "F.Cu")
		(net "DRIVE_14_ACT")
	)
	(segment
		(start 98.6917 -63.1063)
		(end 100.106226 -63.1063)
		(width 0.127)
		(layer "F.Cu")
		(net "DRIVE_14_ACT")
	)
	(segment
		(start 87.5284 -63.1952)
		(end 88.0618 -63.7286)
		(width 0.127)
		(layer "F.Cu")
		(net "DRIVE_14_ACT")
	)
	(segment
		(start 79.514954 -29.90215)
		(end 79.514954 -34.885376)
		(width 0.127)
		(layer "F.Cu")
		(net "DRIVE_14_ACT")
	)
	(segment
		(start 85.967824 -61.634624)
		(end 87.5284 -63.1952)
		(width 0.127)
		(layer "F.Cu")
		(net "DRIVE_14_ACT")
	)
	(segment
		(start 79.718154 -59.89193)
		(end 81.460848 -61.634624)
		(width 0.127)
		(layer "F.Cu")
		(net "DRIVE_14_ACT")
	)
	(segment
		(start 79.718154 -35.088576)
		(end 79.718154 -59.89193)
		(width 0.127)
		(layer "F.Cu")
		(net "DRIVE_14_ACT")
	)
	(segment
		(start 88.0618 -63.7286)
		(end 98.0694 -63.7286)
		(width 0.127)
		(layer "F.Cu")
		(net "DRIVE_14_ACT")
	)
	(segment
		(start 118.282466 -26.937462)
		(end 83.282028 -26.937462)
		(width 0.127)
		(layer "F.Cu")
		(net "DRIVE_14_ACT")
	)
	(segment
		(start 81.96707 -27.450034)
		(end 79.514954 -29.90215)
		(width 0.127)
		(layer "F.Cu")
		(net "DRIVE_14_ACT")
	)
	(segment
		(start 83.282028 -26.937462)
		(end 82.769456 -27.450034)
		(width 0.127)
		(layer "F.Cu")
		(net "DRIVE_14_ACT")
	)
	(segment
		(start 81.460848 -61.634624)
		(end 85.967824 -61.634624)
		(width 0.127)
		(layer "F.Cu")
		(net "DRIVE_14_ACT")
	)
	(segment
		(start 82.769456 -27.450034)
		(end 81.96707 -27.450034)
		(width 0.127)
		(layer "F.Cu")
		(net "DRIVE_14_ACT")
	)
	(segment
		(start 124.432822 -20.787106)
		(end 118.282466 -26.937462)
		(width 0.127)
		(layer "F.Cu")
		(net "DRIVE_14_ACT")
	)
	(segment
		(start 98.0694 -63.7286)
		(end 98.6917 -63.1063)
		(width 0.127)
		(layer "F.Cu")
		(net "DRIVE_14_ACT")
	)
	(segment
		(start 124.432822 -8.56742)
		(end 124.432822 -20.787106)
		(width 0.127)
		(layer "F.Cu")
		(net "DRIVE_14_ACT")
	)
	(segment
		(start 79.514954 -34.885376)
		(end 79.718154 -35.088576)
		(width 0.127)
		(layer "F.Cu")
		(net "DRIVE_14_ACT")
	)
	(segment
		(start 125.600206 -7.400036)
		(end 124.432822 -8.56742)
		(width 0.127)
		(layer "F.Cu")
		(net "DRIVE_14_ACT")
	)
	(via
		(at 87.5284 -63.1952)
		(size 0.6604)
		(drill 0.3302)
		(layers "F.Cu" "B.Cu")
		(net "DRIVE_14_ACT")
	)
	(segment
		(start 123.140724 -8.259572)
		(end 123.140724 -21.360638)
		(width 0.127)
		(layer "F.Cu")
		(net "DRIVE_13_ACT")
	)
	(segment
		(start 83.071462 -26.429462)
		(end 82.59699 -26.903934)
		(width 0.127)
		(layer "F.Cu")
		(net "DRIVE_13_ACT")
	)
	(segment
		(start 82.59699 -26.903934)
		(end 82.164936 -26.903934)
		(width 0.127)
		(layer "F.Cu")
		(net "DRIVE_13_ACT")
	)
	(segment
		(start 123.140724 -21.360638)
		(end 118.0719 -26.429462)
		(width 0.127)
		(layer "F.Cu")
		(net "DRIVE_13_ACT")
	)
	(segment
		(start 81.51749 -26.903934)
		(end 80.968342 -27.453082)
		(width 0.127)
		(layer "F.Cu")
		(net "DRIVE_13_ACT")
	)
	(segment
		(start 105.499916 -64.499998)
		(end 105.000044 -64.000126)
		(width 0.127)
		(layer "F.Cu")
		(net "DRIVE_13_ACT")
	)
	(segment
		(start 82.164936 -26.903934)
		(end 81.51749 -26.903934)
		(width 0.127)
		(layer "F.Cu")
		(net "DRIVE_13_ACT")
	)
	(segment
		(start 123.800108 -7.600188)
		(end 123.140724 -8.259572)
		(width 0.127)
		(layer "F.Cu")
		(net "DRIVE_13_ACT")
	)
	(segment
		(start 118.0719 -26.429462)
		(end 83.071462 -26.429462)
		(width 0.127)
		(layer "F.Cu")
		(net "DRIVE_13_ACT")
	)
	(via
		(at 80.968342 -27.453082)
		(size 0.508)
		(drill 0.254)
		(layers "F.Cu" "B.Cu")
		(net "DRIVE_13_ACT")
	)
	(via
		(at 82.164936 -26.903934)
		(size 0.6604)
		(drill 0.3302)
		(layers "F.Cu" "B.Cu")
		(net "DRIVE_13_ACT")
	)
	(via
		(at 105.000044 -64.000126)
		(size 0.4572)
		(drill 0.2032)
		(layers "F.Cu" "B.Cu")
		(net "DRIVE_13_ACT")
	)
	(segment
		(start 104.431846 -64.568324)
		(end 104.431846 -66.125344)
		(width 0.127)
		(layer "In5.Cu")
		(net "DRIVE_13_ACT")
	)
	(segment
		(start 80.968342 -27.847544)
		(end 80.968342 -27.453082)
		(width 0.127)
		(layer "In5.Cu")
		(net "DRIVE_13_ACT")
	)
	(segment
		(start 104.431846 -66.125344)
		(end 103.655368 -66.901822)
		(width 0.127)
		(layer "In5.Cu")
		(net "DRIVE_13_ACT")
	)
	(segment
		(start 82.637122 -30.65399)
		(end 81.681828 -29.698696)
		(width 0.127)
		(layer "In5.Cu")
		(net "DRIVE_13_ACT")
	)
	(segment
		(start 81.681828 -29.698696)
		(end 81.681828 -28.56103)
		(width 0.127)
		(layer "In5.Cu")
		(net "DRIVE_13_ACT")
	)
	(segment
		(start 105.000044 -64.000126)
		(end 104.431846 -64.568324)
		(width 0.127)
		(layer "In5.Cu")
		(net "DRIVE_13_ACT")
	)
	(segment
		(start 103.655368 -66.901822)
		(end 97.991422 -66.901822)
		(width 0.127)
		(layer "In5.Cu")
		(net "DRIVE_13_ACT")
	)
	(segment
		(start 83.1215 -33.40608)
		(end 82.637122 -32.921702)
		(width 0.127)
		(layer "In5.Cu")
		(net "DRIVE_13_ACT")
	)
	(segment
		(start 95.859854 -64.770254)
		(end 91.752674 -64.770254)
		(width 0.127)
		(layer "In5.Cu")
		(net "DRIVE_13_ACT")
	)
	(segment
		(start 83.906868 -38.933374)
		(end 83.1215 -38.148006)
		(width 0.127)
		(layer "In5.Cu")
		(net "DRIVE_13_ACT")
	)
	(segment
		(start 91.752674 -64.770254)
		(end 83.906868 -56.924448)
		(width 0.127)
		(layer "In5.Cu")
		(net "DRIVE_13_ACT")
	)
	(segment
		(start 83.906868 -56.924448)
		(end 83.906868 -38.933374)
		(width 0.127)
		(layer "In5.Cu")
		(net "DRIVE_13_ACT")
	)
	(segment
		(start 97.991422 -66.901822)
		(end 95.859854 -64.770254)
		(width 0.127)
		(layer "In5.Cu")
		(net "DRIVE_13_ACT")
	)
	(segment
		(start 82.637122 -32.921702)
		(end 82.637122 -30.65399)
		(width 0.127)
		(layer "In5.Cu")
		(net "DRIVE_13_ACT")
	)
	(segment
		(start 83.1215 -38.148006)
		(end 83.1215 -33.40608)
		(width 0.127)
		(layer "In5.Cu")
		(net "DRIVE_13_ACT")
	)
	(segment
		(start 81.681828 -28.56103)
		(end 80.968342 -27.847544)
		(width 0.127)
		(layer "In5.Cu")
		(net "DRIVE_13_ACT")
	)
	(segment
		(start 87.132414 -64.2366)
		(end 85.07476 -62.178946)
		(width 0.127)
		(layer "F.Cu")
		(net "DRIVE_12_ACT")
	)
	(segment
		(start 79.210154 -60.459112)
		(end 80.479138 -61.728096)
		(width 0.127)
		(layer "F.Cu")
		(net "DRIVE_12_ACT")
	)
	(segment
		(start 80.460088 -28.219146)
		(end 78.7908 -29.888434)
		(width 0.127)
		(layer "F.Cu")
		(net "DRIVE_12_ACT")
	)
	(segment
		(start 117.498622 -25.921462)
		(end 81.781396 -25.921462)
		(width 0.127)
		(layer "F.Cu")
		(net "DRIVE_12_ACT")
	)
	(segment
		(start 81.781396 -25.921462)
		(end 80.460088 -27.24277)
		(width 0.127)
		(layer "F.Cu")
		(net "DRIVE_12_ACT")
	)
	(segment
		(start 80.929988 -62.178946)
		(end 80.479138 -61.728096)
		(width 0.127)
		(layer "F.Cu")
		(net "DRIVE_12_ACT")
	)
	(segment
		(start 98.105214 -64.2366)
		(end 87.132414 -64.2366)
		(width 0.127)
		(layer "F.Cu")
		(net "DRIVE_12_ACT")
	)
	(segment
		(start 122.632724 -7.367524)
		(end 122.632724 -20.78736)
		(width 0.127)
		(layer "F.Cu")
		(net "DRIVE_12_ACT")
	)
	(segment
		(start 79.210154 -35.420554)
		(end 79.210154 -60.459112)
		(width 0.127)
		(layer "F.Cu")
		(net "DRIVE_12_ACT")
	)
	(segment
		(start 85.07476 -62.178946)
		(end 80.929988 -62.178946)
		(width 0.127)
		(layer "F.Cu")
		(net "DRIVE_12_ACT")
	)
	(segment
		(start 78.7908 -29.888434)
		(end 78.7908 -35.0012)
		(width 0.127)
		(layer "F.Cu")
		(net "DRIVE_12_ACT")
	)
	(segment
		(start 123.800108 -6.20014)
		(end 122.632724 -7.367524)
		(width 0.127)
		(layer "F.Cu")
		(net "DRIVE_12_ACT")
	)
	(segment
		(start 80.460088 -27.24277)
		(end 80.460088 -28.219146)
		(width 0.127)
		(layer "F.Cu")
		(net "DRIVE_12_ACT")
	)
	(segment
		(start 78.7908 -35.0012)
		(end 79.210154 -35.420554)
		(width 0.127)
		(layer "F.Cu")
		(net "DRIVE_12_ACT")
	)
	(segment
		(start 122.632724 -20.78736)
		(end 117.498622 -25.921462)
		(width 0.127)
		(layer "F.Cu")
		(net "DRIVE_12_ACT")
	)
	(segment
		(start 99.499928 -63.5)
		(end 98.841814 -63.5)
		(width 0.127)
		(layer "F.Cu")
		(net "DRIVE_12_ACT")
	)
	(segment
		(start 98.841814 -63.5)
		(end 98.105214 -64.2366)
		(width 0.127)
		(layer "F.Cu")
		(net "DRIVE_12_ACT")
	)
	(via
		(at 80.479138 -61.728096)
		(size 0.6604)
		(drill 0.3302)
		(layers "F.Cu" "B.Cu")
		(net "DRIVE_12_ACT")
	)
	(segment
		(start 119.500142 -80.50022)
		(end 120.000014 -81.000092)
		(width 0.127)
		(layer "F.Cu")
		(net "SCC_TYPE_3_LS")
	)
	(segment
		(start 121.82856 -85.007196)
		(end 121.82856 -85.654642)
		(width 0.127)
		(layer "F.Cu")
		(net "SCC_TYPE_3_LS")
	)
	(segment
		(start 121.82856 -85.654642)
		(end 122.0978 -85.923882)
		(width 0.127)
		(layer "F.Cu")
		(net "SCC_TYPE_3_LS")
	)
	(segment
		(start 122.0978 -85.923882)
		(end 122.0978 -86.5505)
		(width 0.127)
		(layer "F.Cu")
		(net "SCC_TYPE_3_LS")
	)
	(segment
		(start 121.031 -86.5505)
		(end 122.0978 -86.5505)
		(width 0.127)
		(layer "F.Cu")
		(net "SCC_TYPE_3_LS")
	)
	(via
		(at 120.20931 -82.023966)
		(size 0.6096)
		(drill 0.3048)
		(layers "F.Cu" "B.Cu")
		(net "SCC_TYPE_3_LS")
	)
	(via
		(at 121.82856 -85.007196)
		(size 0.508)
		(drill 0.254)
		(layers "F.Cu" "B.Cu")
		(net "SCC_TYPE_3_LS")
	)
	(via
		(at 120.000014 -81.000092)
		(size 0.4572)
		(drill 0.2032)
		(layers "F.Cu" "B.Cu")
		(net "SCC_TYPE_3_LS")
	)
	(segment
		(start 120.20931 -81.209388)
		(end 120.20931 -82.023966)
		(width 0.127)
		(layer "B.Cu")
		(net "SCC_TYPE_3_LS")
	)
	(segment
		(start 120.20931 -82.6262)
		(end 121.82856 -84.24545)
		(width 0.127)
		(layer "B.Cu")
		(net "SCC_TYPE_3_LS")
	)
	(segment
		(start 120.000014 -81.000092)
		(end 120.20931 -81.209388)
		(width 0.127)
		(layer "B.Cu")
		(net "SCC_TYPE_3_LS")
	)
	(segment
		(start 120.20931 -82.023966)
		(end 120.20931 -82.6262)
		(width 0.127)
		(layer "B.Cu")
		(net "SCC_TYPE_3_LS")
	)
	(segment
		(start 121.82856 -84.24545)
		(end 121.82856 -85.007196)
		(width 0.127)
		(layer "B.Cu")
		(net "SCC_TYPE_3_LS")
	)
	(segment
		(start 73.549256 -10.795)
		(end 76.858114 -14.103858)
		(width 0.127)
		(layer "F.Cu")
		(net "SCC_TYPE_3")
	)
	(segment
		(start 72.859392 -10.795)
		(end 73.549256 -10.795)
		(width 0.127)
		(layer "F.Cu")
		(net "SCC_TYPE_3")
	)
	(segment
		(start 76.858114 -18.052796)
		(end 77.366114 -18.560796)
		(width 0.127)
		(layer "F.Cu")
		(net "SCC_TYPE_3")
	)
	(segment
		(start 70.5485 -10.795)
		(end 72.859392 -10.795)
		(width 0.127)
		(layer "F.Cu")
		(net "SCC_TYPE_3")
	)
	(segment
		(start 76.858114 -14.103858)
		(end 76.858114 -18.052796)
		(width 0.127)
		(layer "F.Cu")
		(net "SCC_TYPE_3")
	)
	(via
		(at 77.366114 -18.560796)
		(size 0.508)
		(drill 0.254)
		(layers "F.Cu" "B.Cu")
		(net "SCC_TYPE_3")
	)
	(via
		(at 72.859392 -10.795)
		(size 0.6604)
		(drill 0.3302)
		(layers "F.Cu" "B.Cu")
		(net "SCC_TYPE_3")
	)
	(segment
		(start 95.000064 -7.600188)
		(end 95.000064 -7.676896)
		(width 0.127)
		(layer "In2.Cu")
		(net "SCC_TYPE_3")
	)
	(segment
		(start 77.874114 -19.068796)
		(end 77.366114 -18.560796)
		(width 0.127)
		(layer "In2.Cu")
		(net "SCC_TYPE_3")
	)
	(segment
		(start 90.07094 -19.068796)
		(end 77.874114 -19.068796)
		(width 0.127)
		(layer "In2.Cu")
		(net "SCC_TYPE_3")
	)
	(segment
		(start 94.35592 -14.783816)
		(end 90.07094 -19.068796)
		(width 0.127)
		(layer "In2.Cu")
		(net "SCC_TYPE_3")
	)
	(segment
		(start 95.000064 -7.676896)
		(end 94.35592 -8.32104)
		(width 0.127)
		(layer "In2.Cu")
		(net "SCC_TYPE_3")
	)
	(segment
		(start 94.35592 -8.32104)
		(end 94.35592 -14.783816)
		(width 0.127)
		(layer "In2.Cu")
		(net "SCC_TYPE_3")
	)
	(segment
		(start 9.928606 -101.23424)
		(end 9.3599 -101.23424)
		(width 0.127)
		(layer "F.Cu")
		(net "SCC_FULL_PGOOD")
	)
	(segment
		(start 167.284654 -102.0572)
		(end 167.34028 -102.0572)
		(width 0.127)
		(layer "F.Cu")
		(net "SCC_FULL_PGOOD")
	)
	(segment
		(start 41.66108 -25.686258)
		(end 41.66108 -26.49474)
		(width 0.127)
		(layer "F.Cu")
		(net "SCC_FULL_PGOOD")
	)
	(segment
		(start 6.5278 -101.4603)
		(end 8.3439 -101.4603)
		(width 0.127)
		(layer "F.Cu")
		(net "SCC_FULL_PGOOD")
	)
	(segment
		(start 167.34536 -102.05212)
		(end 167.34536 -101.11994)
		(width 0.127)
		(layer "F.Cu")
		(net "SCC_FULL_PGOOD")
	)
	(segment
		(start 26.6446 -104.6988)
		(end 25.377648 -104.6988)
		(width 0.127)
		(layer "F.Cu")
		(net "SCC_FULL_PGOOD")
	)
	(segment
		(start 10.2108 -100.952046)
		(end 9.928606 -101.23424)
		(width 0.127)
		(layer "F.Cu")
		(net "SCC_FULL_PGOOD")
	)
	(segment
		(start 167.34028 -102.0572)
		(end 167.34536 -102.05212)
		(width 0.127)
		(layer "F.Cu")
		(net "SCC_FULL_PGOOD")
	)
	(segment
		(start 8.3439 -101.4603)
		(end 8.56996 -101.23424)
		(width 0.127)
		(layer "F.Cu")
		(net "SCC_FULL_PGOOD")
	)
	(segment
		(start 6.5278 -103.0478)
		(end 6.5278 -101.4603)
		(width 0.127)
		(layer "F.Cu")
		(net "SCC_FULL_PGOOD")
	)
	(segment
		(start 9.525 -98.4123)
		(end 9.525 -98.7806)
		(width 0.127)
		(layer "F.Cu")
		(net "SCC_FULL_PGOOD")
	)
	(segment
		(start 25.377648 -104.6988)
		(end 8.1788 -104.6988)
		(width 0.127)
		(layer "F.Cu")
		(net "SCC_FULL_PGOOD")
	)
	(segment
		(start 9.525 -98.7806)
		(end 10.2108 -99.4664)
		(width 0.127)
		(layer "F.Cu")
		(net "SCC_FULL_PGOOD")
	)
	(segment
		(start 10.2108 -99.4664)
		(end 10.2108 -100.952046)
		(width 0.127)
		(layer "F.Cu")
		(net "SCC_FULL_PGOOD")
	)
	(segment
		(start 8.56996 -101.23424)
		(end 9.3599 -101.23424)
		(width 0.127)
		(layer "F.Cu")
		(net "SCC_FULL_PGOOD")
	)
	(segment
		(start 8.1788 -104.6988)
		(end 6.5278 -103.0478)
		(width 0.127)
		(layer "F.Cu")
		(net "SCC_FULL_PGOOD")
	)
	(via
		(at 176.6824 -62.065916)
		(size 0.508)
		(drill 0.254)
		(layers "F.Cu" "B.Cu")
		(net "SCC_FULL_PGOOD")
	)
	(via
		(at 167.284654 -102.0572)
		(size 0.508)
		(drill 0.254)
		(layers "F.Cu" "B.Cu")
		(net "SCC_FULL_PGOOD")
	)
	(via
		(at 116.230146 -106.589068)
		(size 0.508)
		(drill 0.254)
		(layers "F.Cu" "B.Cu")
		(net "SCC_FULL_PGOOD")
	)
	(via
		(at 41.66108 -25.686258)
		(size 0.508)
		(drill 0.254)
		(layers "F.Cu" "B.Cu")
		(net "SCC_FULL_PGOOD")
	)
	(via
		(at 91.44 -104.14)
		(size 0.508)
		(drill 0.254)
		(layers "F.Cu" "B.Cu")
		(net "SCC_FULL_PGOOD")
	)
	(via
		(at 26.6446 -104.6988)
		(size 0.508)
		(drill 0.254)
		(layers "F.Cu" "B.Cu")
		(net "SCC_FULL_PGOOD")
	)
	(via
		(at 25.377648 -104.6988)
		(size 0.6604)
		(drill 0.3302)
		(layers "F.Cu" "B.Cu")
		(net "SCC_FULL_PGOOD")
	)
	(segment
		(start 110.195106 -97.125536)
		(end 98.454464 -97.125536)
		(width 0.127)
		(layer "B.Cu")
		(net "SCC_FULL_PGOOD")
	)
	(segment
		(start 98.454464 -97.125536)
		(end 91.44 -104.14)
		(width 0.127)
		(layer "B.Cu")
		(net "SCC_FULL_PGOOD")
	)
	(segment
		(start 116.230146 -103.160576)
		(end 110.195106 -97.125536)
		(width 0.127)
		(layer "B.Cu")
		(net "SCC_FULL_PGOOD")
	)
	(segment
		(start 176.149 -61.532516)
		(end 176.149 -60.063126)
		(width 0.127)
		(layer "B.Cu")
		(net "SCC_FULL_PGOOD")
	)
	(segment
		(start 116.230146 -106.589068)
		(end 116.230146 -103.160576)
		(width 0.127)
		(layer "B.Cu")
		(net "SCC_FULL_PGOOD")
	)
	(segment
		(start 176.6824 -62.065916)
		(end 176.149 -61.532516)
		(width 0.127)
		(layer "B.Cu")
		(net "SCC_FULL_PGOOD")
	)
	(segment
		(start 120.029478 -102.789736)
		(end 152.937464 -102.789736)
		(width 0.127)
		(layer "In2.Cu")
		(net "SCC_FULL_PGOOD")
	)
	(segment
		(start 189.419992 -107.2007)
		(end 191.257682 -105.36301)
		(width 0.127)
		(layer "In2.Cu")
		(net "SCC_FULL_PGOOD")
	)
	(segment
		(start 167.3098 -102.032054)
		(end 167.284654 -102.0572)
		(width 0.127)
		(layer "In2.Cu")
		(net "SCC_FULL_PGOOD")
	)
	(segment
		(start 178.065684 -63.4492)
		(end 176.6824 -62.065916)
		(width 0.127)
		(layer "In2.Cu")
		(net "SCC_FULL_PGOOD")
	)
	(segment
		(start 167.3098 -101.3714)
		(end 167.3098 -102.032054)
		(width 0.127)
		(layer "In2.Cu")
		(net "SCC_FULL_PGOOD")
	)
	(segment
		(start 175.9839 -108.27004)
		(end 176.608486 -108.894626)
		(width 0.127)
		(layer "In2.Cu")
		(net "SCC_FULL_PGOOD")
	)
	(segment
		(start 188.6458 -70.5104)
		(end 181.5846 -63.4492)
		(width 0.127)
		(layer "In2.Cu")
		(net "SCC_FULL_PGOOD")
	)
	(segment
		(start 191.257682 -105.36301)
		(end 191.257682 -78.100682)
		(width 0.127)
		(layer "In2.Cu")
		(net "SCC_FULL_PGOOD")
	)
	(segment
		(start 158.0134 -97.7138)
		(end 163.6522 -97.7138)
		(width 0.127)
		(layer "In2.Cu")
		(net "SCC_FULL_PGOOD")
	)
	(segment
		(start 116.230146 -106.589068)
		(end 120.029478 -102.789736)
		(width 0.127)
		(layer "In2.Cu")
		(net "SCC_FULL_PGOOD")
	)
	(segment
		(start 167.284654 -102.0572)
		(end 167.3352 -102.107746)
		(width 0.127)
		(layer "In2.Cu")
		(net "SCC_FULL_PGOOD")
	)
	(segment
		(start 171.475654 -108.27004)
		(end 175.9839 -108.27004)
		(width 0.127)
		(layer "In2.Cu")
		(net "SCC_FULL_PGOOD")
	)
	(segment
		(start 191.257682 -78.100682)
		(end 188.6458 -75.4888)
		(width 0.127)
		(layer "In2.Cu")
		(net "SCC_FULL_PGOOD")
	)
	(segment
		(start 167.3352 -104.129586)
		(end 171.475654 -108.27004)
		(width 0.127)
		(layer "In2.Cu")
		(net "SCC_FULL_PGOOD")
	)
	(segment
		(start 176.608486 -108.894626)
		(end 180.246528 -108.894626)
		(width 0.127)
		(layer "In2.Cu")
		(net "SCC_FULL_PGOOD")
	)
	(segment
		(start 188.6458 -75.4888)
		(end 188.6458 -70.5104)
		(width 0.127)
		(layer "In2.Cu")
		(net "SCC_FULL_PGOOD")
	)
	(segment
		(start 163.6522 -97.7138)
		(end 167.3098 -101.3714)
		(width 0.127)
		(layer "In2.Cu")
		(net "SCC_FULL_PGOOD")
	)
	(segment
		(start 167.3352 -102.107746)
		(end 167.3352 -104.129586)
		(width 0.127)
		(layer "In2.Cu")
		(net "SCC_FULL_PGOOD")
	)
	(segment
		(start 181.5846 -63.4492)
		(end 178.065684 -63.4492)
		(width 0.127)
		(layer "In2.Cu")
		(net "SCC_FULL_PGOOD")
	)
	(segment
		(start 152.937464 -102.789736)
		(end 158.0134 -97.7138)
		(width 0.127)
		(layer "In2.Cu")
		(net "SCC_FULL_PGOOD")
	)
	(segment
		(start 180.246528 -108.894626)
		(end 181.940454 -107.2007)
		(width 0.127)
		(layer "In2.Cu")
		(net "SCC_FULL_PGOOD")
	)
	(segment
		(start 181.940454 -107.2007)
		(end 189.419992 -107.2007)
		(width 0.127)
		(layer "In2.Cu")
		(net "SCC_FULL_PGOOD")
	)
	(segment
		(start 25.3873 -91.0971)
		(end 24.49703 -91.98737)
		(width 0.127)
		(layer "In5.Cu")
		(net "SCC_FULL_PGOOD")
	)
	(segment
		(start 91.44 -104.14)
		(end 77.275436 -104.14)
		(width 0.127)
		(layer "In5.Cu")
		(net "SCC_FULL_PGOOD")
	)
	(segment
		(start 27.366468 -82.87385)
		(end 26.077418 -84.1629)
		(width 0.127)
		(layer "In5.Cu")
		(net "SCC_FULL_PGOOD")
	)
	(segment
		(start 34.460942 -25.686258)
		(end 33.2359 -26.9113)
		(width 0.127)
		(layer "In5.Cu")
		(net "SCC_FULL_PGOOD")
	)
	(segment
		(start 26.6446 -104.716834)
		(end 26.6446 -104.6988)
		(width 0.127)
		(layer "In5.Cu")
		(net "SCC_FULL_PGOOD")
	)
	(segment
		(start 77.275436 -104.14)
		(end 65.362836 -116.0526)
		(width 0.127)
		(layer "In5.Cu")
		(net "SCC_FULL_PGOOD")
	)
	(segment
		(start 25.3873 -84.768182)
		(end 25.3873 -91.0971)
		(width 0.127)
		(layer "In5.Cu")
		(net "SCC_FULL_PGOOD")
	)
	(segment
		(start 24.49703 -102.55123)
		(end 26.6446 -104.6988)
		(width 0.127)
		(layer "In5.Cu")
		(net "SCC_FULL_PGOOD")
	)
	(segment
		(start 65.362836 -116.0526)
		(end 37.980366 -116.0526)
		(width 0.127)
		(layer "In5.Cu")
		(net "SCC_FULL_PGOOD")
	)
	(segment
		(start 24.49703 -91.98737)
		(end 24.49703 -102.55123)
		(width 0.127)
		(layer "In5.Cu")
		(net "SCC_FULL_PGOOD")
	)
	(segment
		(start 41.66108 -25.686258)
		(end 34.460942 -25.686258)
		(width 0.127)
		(layer "In5.Cu")
		(net "SCC_FULL_PGOOD")
	)
	(segment
		(start 33.2359 -34.8869)
		(end 27.366468 -40.756332)
		(width 0.127)
		(layer "In5.Cu")
		(net "SCC_FULL_PGOOD")
	)
	(segment
		(start 37.980366 -116.0526)
		(end 26.6446 -104.716834)
		(width 0.127)
		(layer "In5.Cu")
		(net "SCC_FULL_PGOOD")
	)
	(segment
		(start 27.366468 -40.756332)
		(end 27.366468 -82.87385)
		(width 0.127)
		(layer "In5.Cu")
		(net "SCC_FULL_PGOOD")
	)
	(segment
		(start 25.992582 -84.1629)
		(end 25.3873 -84.768182)
		(width 0.127)
		(layer "In5.Cu")
		(net "SCC_FULL_PGOOD")
	)
	(segment
		(start 33.2359 -26.9113)
		(end 33.2359 -34.8869)
		(width 0.127)
		(layer "In5.Cu")
		(net "SCC_FULL_PGOOD")
	)
	(segment
		(start 26.077418 -84.1629)
		(end 25.992582 -84.1629)
		(width 0.127)
		(layer "In5.Cu")
		(net "SCC_FULL_PGOOD")
	)
	(segment
		(start 54.6735 -72.136)
		(end 53.6575 -72.136)
		(width 0.127)
		(layer "F.Cu")
		(net "VREF7")
	)
	(segment
		(start 54.37632 -75.8698)
		(end 54.37632 -74.950828)
		(width 0.127)
		(layer "F.Cu")
		(net "VREF7")
	)
	(segment
		(start 53.6321 -73.1012)
		(end 53.6321 -74.206608)
		(width 0.127)
		(layer "F.Cu")
		(net "VREF7")
	)
	(segment
		(start 53.6321 -73.1012)
		(end 53.6321 -72.1614)
		(width 0.127)
		(layer "F.Cu")
		(net "VREF7")
	)
	(segment
		(start 54.6862 -72.1233)
		(end 54.6735 -72.136)
		(width 0.127)
		(layer "F.Cu")
		(net "VREF7")
	)
	(segment
		(start 53.6321 -72.1614)
		(end 53.6575 -72.136)
		(width 0.127)
		(layer "F.Cu")
		(net "VREF7")
	)
	(segment
		(start 54.37632 -74.950828)
		(end 53.6702 -74.244708)
		(width 0.127)
		(layer "F.Cu")
		(net "VREF7")
	)
	(segment
		(start 53.6321 -74.206608)
		(end 53.6702 -74.244708)
		(width 0.127)
		(layer "F.Cu")
		(net "VREF7")
	)
	(via
		(at 53.6702 -74.244708)
		(size 0.6604)
		(drill 0.3302)
		(layers "F.Cu" "B.Cu")
		(net "VREF7")
	)
	(segment
		(start 154.7876 -100.51288)
		(end 154.6606 -100.38588)
		(width 0.127)
		(layer "F.Cu")
		(net "UART_SDB_TX")
	)
	(segment
		(start 154.6606 -100.38588)
		(end 153.627328 -100.38588)
		(width 0.127)
		(layer "F.Cu")
		(net "UART_SDB_TX")
	)
	(segment
		(start 154.7876 -102.929436)
		(end 154.7876 -100.51288)
		(width 0.127)
		(layer "F.Cu")
		(net "UART_SDB_TX")
	)
	(via
		(at 153.627328 -100.38588)
		(size 0.508)
		(drill 0.254)
		(layers "F.Cu" "B.Cu")
		(net "UART_SDB_TX")
	)
	(segment
		(start 65.224406 -96.055688)
		(end 61.368178 -96.055688)
		(width 0.127)
		(layer "In2.Cu")
		(net "UART_SDB_TX")
	)
	(segment
		(start 71.069962 -99.5172)
		(end 68.685918 -99.5172)
		(width 0.127)
		(layer "In2.Cu")
		(net "UART_SDB_TX")
	)
	(segment
		(start 48.8315 -70.552564)
		(end 55.274718 -64.109346)
		(width 0.127)
		(layer "In2.Cu")
		(net "UART_SDB_TX")
	)
	(segment
		(start 95.650304 -8.547608)
		(end 96.797876 -7.400036)
		(width 0.127)
		(layer "In2.Cu")
		(net "UART_SDB_TX")
	)
	(segment
		(start 90.334084 -19.703796)
		(end 95.47225 -14.56563)
		(width 0.127)
		(layer "In2.Cu")
		(net "UART_SDB_TX")
	)
	(segment
		(start 75.543918 -103.991156)
		(end 71.069962 -99.5172)
		(width 0.127)
		(layer "In2.Cu")
		(net "UART_SDB_TX")
	)
	(segment
		(start 68.683886 -58.776108)
		(end 68.683886 -31.090616)
		(width 0.127)
		(layer "In2.Cu")
		(net "UART_SDB_TX")
	)
	(segment
		(start 68.28663 -59.173364)
		(end 68.683886 -58.776108)
		(width 0.127)
		(layer "In2.Cu")
		(net "UART_SDB_TX")
	)
	(segment
		(start 69.69379 -24.17572)
		(end 74.165714 -19.703796)
		(width 0.127)
		(layer "In2.Cu")
		(net "UART_SDB_TX")
	)
	(segment
		(start 55.274718 -64.109346)
		(end 62.772036 -64.109346)
		(width 0.127)
		(layer "In2.Cu")
		(net "UART_SDB_TX")
	)
	(segment
		(start 152.066498 -101.94671)
		(end 92.87129 -101.94671)
		(width 0.127)
		(layer "In2.Cu")
		(net "UART_SDB_TX")
	)
	(segment
		(start 90.826844 -103.991156)
		(end 75.543918 -103.991156)
		(width 0.127)
		(layer "In2.Cu")
		(net "UART_SDB_TX")
	)
	(segment
		(start 68.685918 -99.5172)
		(end 65.224406 -96.055688)
		(width 0.127)
		(layer "In2.Cu")
		(net "UART_SDB_TX")
	)
	(segment
		(start 95.47225 -14.56563)
		(end 95.47225 -13.009118)
		(width 0.127)
		(layer "In2.Cu")
		(net "UART_SDB_TX")
	)
	(segment
		(start 62.772036 -64.109346)
		(end 67.708018 -59.173364)
		(width 0.127)
		(layer "In2.Cu")
		(net "UART_SDB_TX")
	)
	(segment
		(start 48.8315 -83.51901)
		(end 48.8315 -70.552564)
		(width 0.127)
		(layer "In2.Cu")
		(net "UART_SDB_TX")
	)
	(segment
		(start 153.627328 -100.38588)
		(end 152.066498 -101.94671)
		(width 0.127)
		(layer "In2.Cu")
		(net "UART_SDB_TX")
	)
	(segment
		(start 69.69379 -30.080712)
		(end 69.69379 -24.17572)
		(width 0.127)
		(layer "In2.Cu")
		(net "UART_SDB_TX")
	)
	(segment
		(start 92.87129 -101.94671)
		(end 90.826844 -103.991156)
		(width 0.127)
		(layer "In2.Cu")
		(net "UART_SDB_TX")
	)
	(segment
		(start 67.708018 -59.173364)
		(end 68.28663 -59.173364)
		(width 0.127)
		(layer "In2.Cu")
		(net "UART_SDB_TX")
	)
	(segment
		(start 61.368178 -96.055688)
		(end 48.8315 -83.51901)
		(width 0.127)
		(layer "In2.Cu")
		(net "UART_SDB_TX")
	)
	(segment
		(start 74.165714 -19.703796)
		(end 90.334084 -19.703796)
		(width 0.127)
		(layer "In2.Cu")
		(net "UART_SDB_TX")
	)
	(segment
		(start 95.650304 -12.831064)
		(end 95.650304 -8.547608)
		(width 0.127)
		(layer "In2.Cu")
		(net "UART_SDB_TX")
	)
	(segment
		(start 95.47225 -13.009118)
		(end 95.650304 -12.831064)
		(width 0.127)
		(layer "In2.Cu")
		(net "UART_SDB_TX")
	)
	(segment
		(start 68.683886 -31.090616)
		(end 69.69379 -30.080712)
		(width 0.127)
		(layer "In2.Cu")
		(net "UART_SDB_TX")
	)
	(segment
		(start 96.797876 -7.400036)
		(end 96.800162 -7.400036)
		(width 0.127)
		(layer "In2.Cu")
		(net "UART_SDB_TX")
	)
	(segment
		(start 151.78786 -102.70236)
		(end 151.78786 -100.38588)
		(width 0.127)
		(layer "F.Cu")
		(net "UART_SDB_RX")
	)
	(segment
		(start 150.9268 -100.3808)
		(end 150.93188 -100.38588)
		(width 0.127)
		(layer "F.Cu")
		(net "UART_SDB_RX")
	)
	(segment
		(start 155.015184 -105.929684)
		(end 151.78786 -102.70236)
		(width 0.127)
		(layer "F.Cu")
		(net "UART_SDB_RX")
	)
	(segment
		(start 157.3276 -105.929684)
		(end 155.015184 -105.929684)
		(width 0.127)
		(layer "F.Cu")
		(net "UART_SDB_RX")
	)
	(segment
		(start 150.93188 -100.38588)
		(end 151.78786 -100.38588)
		(width 0.127)
		(layer "F.Cu")
		(net "UART_SDB_RX")
	)
	(via
		(at 150.9268 -100.3808)
		(size 0.508)
		(drill 0.254)
		(layers "F.Cu" "B.Cu")
		(net "UART_SDB_RX")
	)
	(segment
		(start 69.3674 -51.040538)
		(end 70.32879 -50.079148)
		(width 0.127)
		(layer "In2.Cu")
		(net "UART_SDB_RX")
	)
	(segment
		(start 63.034926 -64.7446)
		(end 67.404996 -60.37453)
		(width 0.127)
		(layer "In2.Cu")
		(net "UART_SDB_RX")
	)
	(segment
		(start 70.32879 -24.438864)
		(end 74.428858 -20.338796)
		(width 0.127)
		(layer "In2.Cu")
		(net "UART_SDB_RX")
	)
	(segment
		(start 76.203302 -103.356156)
		(end 71.729346 -98.8822)
		(width 0.127)
		(layer "In2.Cu")
		(net "UART_SDB_RX")
	)
	(segment
		(start 68.586858 -60.37453)
		(end 69.3674 -59.593988)
		(width 0.127)
		(layer "In2.Cu")
		(net "UART_SDB_RX")
	)
	(segment
		(start 70.273672 -98.8822)
		(end 66.81216 -95.420688)
		(width 0.127)
		(layer "In2.Cu")
		(net "UART_SDB_RX")
	)
	(segment
		(start 49.4665 -70.815708)
		(end 55.537608 -64.7446)
		(width 0.127)
		(layer "In2.Cu")
		(net "UART_SDB_RX")
	)
	(segment
		(start 96.15932 -14.776704)
		(end 96.15932 -9.440926)
		(width 0.127)
		(layer "In2.Cu")
		(net "UART_SDB_RX")
	)
	(segment
		(start 49.4665 -83.255866)
		(end 49.4665 -70.815708)
		(width 0.127)
		(layer "In2.Cu")
		(net "UART_SDB_RX")
	)
	(segment
		(start 149.99589 -101.31171)
		(end 92.481146 -101.31171)
		(width 0.127)
		(layer "In2.Cu")
		(net "UART_SDB_RX")
	)
	(segment
		(start 71.729346 -98.8822)
		(end 70.273672 -98.8822)
		(width 0.127)
		(layer "In2.Cu")
		(net "UART_SDB_RX")
	)
	(segment
		(start 90.597228 -20.338796)
		(end 96.15932 -14.776704)
		(width 0.127)
		(layer "In2.Cu")
		(net "UART_SDB_RX")
	)
	(segment
		(start 69.3674 -59.593988)
		(end 69.3674 -51.040538)
		(width 0.127)
		(layer "In2.Cu")
		(net "UART_SDB_RX")
	)
	(segment
		(start 96.15932 -9.440926)
		(end 96.800162 -8.800084)
		(width 0.127)
		(layer "In2.Cu")
		(net "UART_SDB_RX")
	)
	(segment
		(start 67.404996 -60.37453)
		(end 68.586858 -60.37453)
		(width 0.127)
		(layer "In2.Cu")
		(net "UART_SDB_RX")
	)
	(segment
		(start 66.81216 -95.420688)
		(end 61.631322 -95.420688)
		(width 0.127)
		(layer "In2.Cu")
		(net "UART_SDB_RX")
	)
	(segment
		(start 92.481146 -101.31171)
		(end 90.4367 -103.356156)
		(width 0.127)
		(layer "In2.Cu")
		(net "UART_SDB_RX")
	)
	(segment
		(start 90.4367 -103.356156)
		(end 76.203302 -103.356156)
		(width 0.127)
		(layer "In2.Cu")
		(net "UART_SDB_RX")
	)
	(segment
		(start 61.631322 -95.420688)
		(end 49.4665 -83.255866)
		(width 0.127)
		(layer "In2.Cu")
		(net "UART_SDB_RX")
	)
	(segment
		(start 70.32879 -50.079148)
		(end 70.32879 -24.438864)
		(width 0.127)
		(layer "In2.Cu")
		(net "UART_SDB_RX")
	)
	(segment
		(start 150.9268 -100.3808)
		(end 149.99589 -101.31171)
		(width 0.127)
		(layer "In2.Cu")
		(net "UART_SDB_RX")
	)
	(segment
		(start 55.537608 -64.7446)
		(end 63.034926 -64.7446)
		(width 0.127)
		(layer "In2.Cu")
		(net "UART_SDB_RX")
	)
	(segment
		(start 74.428858 -20.338796)
		(end 90.597228 -20.338796)
		(width 0.127)
		(layer "In2.Cu")
		(net "UART_SDB_RX")
	)
	(segment
		(start 69.053456 -20.860004)
		(end 69.053456 -18.165572)
		(width 0.127)
		(layer "F.Cu")
		(net "PWM_OUT_ZONE_D_LS")
	)
	(segment
		(start 117.500146 -80.50022)
		(end 118.000018 -81.000092)
		(width 0.127)
		(layer "F.Cu")
		(net "PWM_OUT_ZONE_D_LS")
	)
	(segment
		(start 69.053456 -18.165572)
		(end 67.725544 -16.83766)
		(width 0.127)
		(layer "F.Cu")
		(net "PWM_OUT_ZONE_D_LS")
	)
	(segment
		(start 67.445128 -16.83766)
		(end 67.337178 -16.72971)
		(width 0.127)
		(layer "F.Cu")
		(net "PWM_OUT_ZONE_D_LS")
	)
	(segment
		(start 69.053456 -21.536406)
		(end 69.053456 -20.860004)
		(width 0.127)
		(layer "F.Cu")
		(net "PWM_OUT_ZONE_D_LS")
	)
	(segment
		(start 67.725544 -16.83766)
		(end 67.445128 -16.83766)
		(width 0.127)
		(layer "F.Cu")
		(net "PWM_OUT_ZONE_D_LS")
	)
	(segment
		(start 69.325998 -21.808948)
		(end 69.053456 -21.536406)
		(width 0.127)
		(layer "F.Cu")
		(net "PWM_OUT_ZONE_D_LS")
	)
	(segment
		(start 67.337178 -16.72971)
		(end 66.319908 -16.72971)
		(width 0.127)
		(layer "F.Cu")
		(net "PWM_OUT_ZONE_D_LS")
	)
	(via
		(at 69.325998 -21.808948)
		(size 0.508)
		(drill 0.254)
		(layers "F.Cu" "B.Cu")
		(net "PWM_OUT_ZONE_D_LS")
	)
	(via
		(at 118.000018 -81.000092)
		(size 0.4572)
		(drill 0.2032)
		(layers "F.Cu" "B.Cu")
		(net "PWM_OUT_ZONE_D_LS")
	)
	(via
		(at 69.053456 -20.860004)
		(size 0.6604)
		(drill 0.3302)
		(layers "F.Cu" "B.Cu")
		(net "PWM_OUT_ZONE_D_LS")
	)
	(segment
		(start 109.474508 -87.0839)
		(end 108.349796 -87.0839)
		(width 0.127)
		(layer "In5.Cu")
		(net "PWM_OUT_ZONE_D_LS")
	)
	(segment
		(start 77.65542 -75.6158)
		(end 77.65542 -72.868536)
		(width 0.127)
		(layer "In5.Cu")
		(net "PWM_OUT_ZONE_D_LS")
	)
	(segment
		(start 118.000018 -81.000092)
		(end 118.000018 -81.861406)
		(width 0.127)
		(layer "In5.Cu")
		(net "PWM_OUT_ZONE_D_LS")
	)
	(segment
		(start 115.3795 -84.481924)
		(end 115.3795 -84.679536)
		(width 0.127)
		(layer "In5.Cu")
		(net "PWM_OUT_ZONE_D_LS")
	)
	(segment
		(start 106.553 -88.880696)
		(end 99.778058 -88.880696)
		(width 0.127)
		(layer "In5.Cu")
		(net "PWM_OUT_ZONE_D_LS")
	)
	(segment
		(start 85.539834 -90.937842)
		(end 78.867 -84.265008)
		(width 0.127)
		(layer "In5.Cu")
		(net "PWM_OUT_ZONE_D_LS")
	)
	(segment
		(start 108.349796 -87.0839)
		(end 106.553 -88.880696)
		(width 0.127)
		(layer "In5.Cu")
		(net "PWM_OUT_ZONE_D_LS")
	)
	(segment
		(start 77.142086 -78.331822)
		(end 77.142086 -76.129134)
		(width 0.127)
		(layer "In5.Cu")
		(net "PWM_OUT_ZONE_D_LS")
	)
	(segment
		(start 118.000018 -81.861406)
		(end 115.3795 -84.481924)
		(width 0.127)
		(layer "In5.Cu")
		(net "PWM_OUT_ZONE_D_LS")
	)
	(segment
		(start 68.817998 -29.18206)
		(end 68.817998 -22.316948)
		(width 0.127)
		(layer "In5.Cu")
		(net "PWM_OUT_ZONE_D_LS")
	)
	(segment
		(start 97.720912 -90.937842)
		(end 85.539834 -90.937842)
		(width 0.127)
		(layer "In5.Cu")
		(net "PWM_OUT_ZONE_D_LS")
	)
	(segment
		(start 78.867 -84.265008)
		(end 78.867 -81.263236)
		(width 0.127)
		(layer "In5.Cu")
		(net "PWM_OUT_ZONE_D_LS")
	)
	(segment
		(start 99.778058 -88.880696)
		(end 97.720912 -90.937842)
		(width 0.127)
		(layer "In5.Cu")
		(net "PWM_OUT_ZONE_D_LS")
	)
	(segment
		(start 115.3795 -84.679536)
		(end 114.944398 -85.114638)
		(width 0.127)
		(layer "In5.Cu")
		(net "PWM_OUT_ZONE_D_LS")
	)
	(segment
		(start 114.944398 -85.114638)
		(end 111.44377 -85.114638)
		(width 0.127)
		(layer "In5.Cu")
		(net "PWM_OUT_ZONE_D_LS")
	)
	(segment
		(start 77.142086 -76.129134)
		(end 77.65542 -75.6158)
		(width 0.127)
		(layer "In5.Cu")
		(net "PWM_OUT_ZONE_D_LS")
	)
	(segment
		(start 68.817998 -22.316948)
		(end 69.325998 -21.808948)
		(width 0.127)
		(layer "In5.Cu")
		(net "PWM_OUT_ZONE_D_LS")
	)
	(segment
		(start 77.558392 -78.748128)
		(end 77.142086 -78.331822)
		(width 0.127)
		(layer "In5.Cu")
		(net "PWM_OUT_ZONE_D_LS")
	)
	(segment
		(start 111.44377 -85.114638)
		(end 109.474508 -87.0839)
		(width 0.127)
		(layer "In5.Cu")
		(net "PWM_OUT_ZONE_D_LS")
	)
	(segment
		(start 77.65542 -72.868536)
		(end 70.5993 -65.812416)
		(width 0.127)
		(layer "In5.Cu")
		(net "PWM_OUT_ZONE_D_LS")
	)
	(segment
		(start 70.5993 -65.812416)
		(end 70.5993 -30.963362)
		(width 0.127)
		(layer "In5.Cu")
		(net "PWM_OUT_ZONE_D_LS")
	)
	(segment
		(start 78.867 -81.263236)
		(end 77.558392 -79.954628)
		(width 0.127)
		(layer "In5.Cu")
		(net "PWM_OUT_ZONE_D_LS")
	)
	(segment
		(start 70.5993 -30.963362)
		(end 68.817998 -29.18206)
		(width 0.127)
		(layer "In5.Cu")
		(net "PWM_OUT_ZONE_D_LS")
	)
	(segment
		(start 77.558392 -79.954628)
		(end 77.558392 -78.748128)
		(width 0.127)
		(layer "In5.Cu")
		(net "PWM_OUT_ZONE_D_LS")
	)
	(segment
		(start 74.908156 -19.356832)
		(end 76.52512 -20.973796)
		(width 0.127)
		(layer "F.Cu")
		(net "PWM_OUT_ZONE_D")
	)
	(segment
		(start 74.908156 -17.581626)
		(end 73.78573 -16.4592)
		(width 0.127)
		(layer "F.Cu")
		(net "PWM_OUT_ZONE_D")
	)
	(segment
		(start 72.972168 -16.32966)
		(end 71.958708 -16.32966)
		(width 0.127)
		(layer "F.Cu")
		(net "PWM_OUT_ZONE_D")
	)
	(segment
		(start 74.908156 -18.193004)
		(end 74.908156 -17.581626)
		(width 0.127)
		(layer "F.Cu")
		(net "PWM_OUT_ZONE_D")
	)
	(segment
		(start 74.908156 -18.193004)
		(end 74.908156 -19.356832)
		(width 0.127)
		(layer "F.Cu")
		(net "PWM_OUT_ZONE_D")
	)
	(segment
		(start 73.78573 -16.4592)
		(end 73.101708 -16.4592)
		(width 0.127)
		(layer "F.Cu")
		(net "PWM_OUT_ZONE_D")
	)
	(segment
		(start 73.101708 -16.4592)
		(end 72.972168 -16.32966)
		(width 0.127)
		(layer "F.Cu")
		(net "PWM_OUT_ZONE_D")
	)
	(via
		(at 76.52512 -20.973796)
		(size 0.508)
		(drill 0.254)
		(layers "F.Cu" "B.Cu")
		(net "PWM_OUT_ZONE_D")
	)
	(via
		(at 74.908156 -18.193004)
		(size 0.6604)
		(drill 0.3302)
		(layers "F.Cu" "B.Cu")
		(net "PWM_OUT_ZONE_D")
	)
	(segment
		(start 97.943416 -8.256778)
		(end 97.943416 -9.27354)
		(width 0.127)
		(layer "In2.Cu")
		(net "PWM_OUT_ZONE_D")
	)
	(segment
		(start 91.070938 -21.481796)
		(end 77.03312 -21.481796)
		(width 0.127)
		(layer "In2.Cu")
		(net "PWM_OUT_ZONE_D")
	)
	(segment
		(start 98.600006 -7.600188)
		(end 97.943416 -8.256778)
		(width 0.127)
		(layer "In2.Cu")
		(net "PWM_OUT_ZONE_D")
	)
	(segment
		(start 97.943416 -9.27354)
		(end 97.940876 -9.27608)
		(width 0.127)
		(layer "In2.Cu")
		(net "PWM_OUT_ZONE_D")
	)
	(segment
		(start 97.940876 -9.27608)
		(end 97.940876 -14.611858)
		(width 0.127)
		(layer "In2.Cu")
		(net "PWM_OUT_ZONE_D")
	)
	(segment
		(start 77.03312 -21.481796)
		(end 76.52512 -20.973796)
		(width 0.127)
		(layer "In2.Cu")
		(net "PWM_OUT_ZONE_D")
	)
	(segment
		(start 97.940876 -14.611858)
		(end 91.070938 -21.481796)
		(width 0.127)
		(layer "In2.Cu")
		(net "PWM_OUT_ZONE_D")
	)
	(segment
		(start 69.64553 -18.039334)
		(end 69.64553 -18.03908)
		(width 0.127)
		(layer "F.Cu")
		(net "PWM_OUT_ZONE_C_LS")
	)
	(segment
		(start 71.981822 -23.450296)
		(end 71.981822 -23.45055)
		(width 0.127)
		(layer "F.Cu")
		(net "PWM_OUT_ZONE_C_LS")
	)
	(segment
		(start 71.02221 -22.490684)
		(end 69.72554 -21.194014)
		(width 0.127)
		(layer "F.Cu")
		(net "PWM_OUT_ZONE_C_LS")
	)
	(segment
		(start 67.93611 -16.32966)
		(end 66.319908 -16.32966)
		(width 0.127)
		(layer "F.Cu")
		(net "PWM_OUT_ZONE_C_LS")
	)
	(segment
		(start 69.72554 -21.194014)
		(end 69.72554 -18.119344)
		(width 0.127)
		(layer "F.Cu")
		(net "PWM_OUT_ZONE_C_LS")
	)
	(segment
		(start 69.72554 -18.119344)
		(end 69.64553 -18.039334)
		(width 0.127)
		(layer "F.Cu")
		(net "PWM_OUT_ZONE_C_LS")
	)
	(segment
		(start 117.500146 -79.500222)
		(end 118.000018 -79.00035)
		(width 0.127)
		(layer "F.Cu")
		(net "PWM_OUT_ZONE_C_LS")
	)
	(segment
		(start 71.02221 -22.490684)
		(end 71.981822 -23.450296)
		(width 0.127)
		(layer "F.Cu")
		(net "PWM_OUT_ZONE_C_LS")
	)
	(segment
		(start 69.64553 -18.03908)
		(end 67.93611 -16.32966)
		(width 0.127)
		(layer "F.Cu")
		(net "PWM_OUT_ZONE_C_LS")
	)
	(via
		(at 118.000018 -79.00035)
		(size 0.4572)
		(drill 0.2032)
		(layers "F.Cu" "B.Cu")
		(net "PWM_OUT_ZONE_C_LS")
	)
	(via
		(at 71.02221 -22.490684)
		(size 0.6604)
		(drill 0.3302)
		(layers "F.Cu" "B.Cu")
		(net "PWM_OUT_ZONE_C_LS")
	)
	(via
		(at 71.981822 -23.45055)
		(size 0.508)
		(drill 0.254)
		(layers "F.Cu" "B.Cu")
		(net "PWM_OUT_ZONE_C_LS")
	)
	(segment
		(start 97.173542 -89.521538)
		(end 85.80882 -89.521538)
		(width 0.127)
		(layer "In5.Cu")
		(net "PWM_OUT_ZONE_C_LS")
	)
	(segment
		(start 80.391 -82.46745)
		(end 80.391 -81.350104)
		(width 0.127)
		(layer "In5.Cu")
		(net "PWM_OUT_ZONE_C_LS")
	)
	(segment
		(start 108.839 -84.7344)
		(end 106.4387 -87.1347)
		(width 0.127)
		(layer "In5.Cu")
		(net "PWM_OUT_ZONE_C_LS")
	)
	(segment
		(start 81.793842 -83.870292)
		(end 80.391 -82.46745)
		(width 0.127)
		(layer "In5.Cu")
		(net "PWM_OUT_ZONE_C_LS")
	)
	(segment
		(start 110.223554 -84.2899)
		(end 109.779054 -84.7344)
		(width 0.127)
		(layer "In5.Cu")
		(net "PWM_OUT_ZONE_C_LS")
	)
	(segment
		(start 98.830384 -87.864696)
		(end 97.173542 -89.521538)
		(width 0.127)
		(layer "In5.Cu")
		(net "PWM_OUT_ZONE_C_LS")
	)
	(segment
		(start 109.779054 -84.7344)
		(end 108.839 -84.7344)
		(width 0.127)
		(layer "In5.Cu")
		(net "PWM_OUT_ZONE_C_LS")
	)
	(segment
		(start 71.6153 -65.391284)
		(end 71.6153 -30.54223)
		(width 0.127)
		(layer "In5.Cu")
		(net "PWM_OUT_ZONE_C_LS")
	)
	(segment
		(start 84.2899 -87.485982)
		(end 81.793842 -84.989924)
		(width 0.127)
		(layer "In5.Cu")
		(net "PWM_OUT_ZONE_C_LS")
	)
	(segment
		(start 84.2899 -88.002618)
		(end 84.2899 -87.485982)
		(width 0.127)
		(layer "In5.Cu")
		(net "PWM_OUT_ZONE_C_LS")
	)
	(segment
		(start 69.833998 -28.760928)
		(end 69.833998 -24.334724)
		(width 0.127)
		(layer "In5.Cu")
		(net "PWM_OUT_ZONE_C_LS")
	)
	(segment
		(start 102.145592 -87.864696)
		(end 98.830384 -87.864696)
		(width 0.127)
		(layer "In5.Cu")
		(net "PWM_OUT_ZONE_C_LS")
	)
	(segment
		(start 69.833998 -24.334724)
		(end 70.718172 -23.45055)
		(width 0.127)
		(layer "In5.Cu")
		(net "PWM_OUT_ZONE_C_LS")
	)
	(segment
		(start 106.4387 -87.1347)
		(end 102.875588 -87.1347)
		(width 0.127)
		(layer "In5.Cu")
		(net "PWM_OUT_ZONE_C_LS")
	)
	(segment
		(start 81.793842 -84.989924)
		(end 81.793842 -83.870292)
		(width 0.127)
		(layer "In5.Cu")
		(net "PWM_OUT_ZONE_C_LS")
	)
	(segment
		(start 71.6153 -30.54223)
		(end 69.833998 -28.760928)
		(width 0.127)
		(layer "In5.Cu")
		(net "PWM_OUT_ZONE_C_LS")
	)
	(segment
		(start 85.80882 -89.521538)
		(end 84.2899 -88.002618)
		(width 0.127)
		(layer "In5.Cu")
		(net "PWM_OUT_ZONE_C_LS")
	)
	(segment
		(start 78.74762 -72.523604)
		(end 71.6153 -65.391284)
		(width 0.127)
		(layer "In5.Cu")
		(net "PWM_OUT_ZONE_C_LS")
	)
	(segment
		(start 80.391 -81.350104)
		(end 78.74762 -79.706724)
		(width 0.127)
		(layer "In5.Cu")
		(net "PWM_OUT_ZONE_C_LS")
	)
	(segment
		(start 113.267236 -84.2899)
		(end 110.223554 -84.2899)
		(width 0.127)
		(layer "In5.Cu")
		(net "PWM_OUT_ZONE_C_LS")
	)
	(segment
		(start 116.393722 -81.163414)
		(end 113.267236 -84.2899)
		(width 0.127)
		(layer "In5.Cu")
		(net "PWM_OUT_ZONE_C_LS")
	)
	(segment
		(start 116.393722 -81.049368)
		(end 116.393722 -81.163414)
		(width 0.127)
		(layer "In5.Cu")
		(net "PWM_OUT_ZONE_C_LS")
	)
	(segment
		(start 117.1194 -80.437736)
		(end 117.005354 -80.437736)
		(width 0.127)
		(layer "In5.Cu")
		(net "PWM_OUT_ZONE_C_LS")
	)
	(segment
		(start 102.875588 -87.1347)
		(end 102.145592 -87.864696)
		(width 0.127)
		(layer "In5.Cu")
		(net "PWM_OUT_ZONE_C_LS")
	)
	(segment
		(start 117.005354 -80.437736)
		(end 116.393722 -81.049368)
		(width 0.127)
		(layer "In5.Cu")
		(net "PWM_OUT_ZONE_C_LS")
	)
	(segment
		(start 70.718172 -23.45055)
		(end 71.981822 -23.45055)
		(width 0.127)
		(layer "In5.Cu")
		(net "PWM_OUT_ZONE_C_LS")
	)
	(segment
		(start 118.000018 -79.00035)
		(end 118.000018 -79.557118)
		(width 0.127)
		(layer "In5.Cu")
		(net "PWM_OUT_ZONE_C_LS")
	)
	(segment
		(start 78.74762 -79.706724)
		(end 78.74762 -72.523604)
		(width 0.127)
		(layer "In5.Cu")
		(net "PWM_OUT_ZONE_C_LS")
	)
	(segment
		(start 118.000018 -79.557118)
		(end 117.1194 -80.437736)
		(width 0.127)
		(layer "In5.Cu")
		(net "PWM_OUT_ZONE_C_LS")
	)
	(segment
		(start 74.0664 -15.9512)
		(end 74.884788 -16.769588)
		(width 0.127)
		(layer "F.Cu")
		(net "PWM_OUT_ZONE_C")
	)
	(segment
		(start 72.979788 -15.9512)
		(end 74.0664 -15.9512)
		(width 0.127)
		(layer "F.Cu")
		(net "PWM_OUT_ZONE_C")
	)
	(segment
		(start 72.958198 -15.92961)
		(end 72.979788 -15.9512)
		(width 0.127)
		(layer "F.Cu")
		(net "PWM_OUT_ZONE_C")
	)
	(segment
		(start 71.958708 -15.92961)
		(end 72.958198 -15.92961)
		(width 0.127)
		(layer "F.Cu")
		(net "PWM_OUT_ZONE_C")
	)
	(segment
		(start 76.347574 -18.232374)
		(end 74.884788 -16.769588)
		(width 0.127)
		(layer "F.Cu")
		(net "PWM_OUT_ZONE_C")
	)
	(segment
		(start 77.79512 -20.973796)
		(end 76.347574 -19.52625)
		(width 0.127)
		(layer "F.Cu")
		(net "PWM_OUT_ZONE_C")
	)
	(segment
		(start 76.347574 -19.52625)
		(end 76.347574 -18.232374)
		(width 0.127)
		(layer "F.Cu")
		(net "PWM_OUT_ZONE_C")
	)
	(via
		(at 77.79512 -20.973796)
		(size 0.508)
		(drill 0.254)
		(layers "F.Cu" "B.Cu")
		(net "PWM_OUT_ZONE_C")
	)
	(via
		(at 74.884788 -16.769588)
		(size 0.6604)
		(drill 0.3302)
		(layers "F.Cu" "B.Cu")
		(net "PWM_OUT_ZONE_C")
	)
	(segment
		(start 97.432876 -9.065514)
		(end 97.435416 -9.062974)
		(width 0.127)
		(layer "In2.Cu")
		(net "PWM_OUT_ZONE_C")
	)
	(segment
		(start 97.432876 -14.401292)
		(end 97.432876 -9.065514)
		(width 0.127)
		(layer "In2.Cu")
		(net "PWM_OUT_ZONE_C")
	)
	(segment
		(start 90.860372 -20.973796)
		(end 97.432876 -14.401292)
		(width 0.127)
		(layer "In2.Cu")
		(net "PWM_OUT_ZONE_C")
	)
	(segment
		(start 97.435416 -8.537194)
		(end 97.432876 -8.534654)
		(width 0.127)
		(layer "In2.Cu")
		(net "PWM_OUT_ZONE_C")
	)
	(segment
		(start 97.435416 -9.062974)
		(end 97.435416 -8.537194)
		(width 0.127)
		(layer "In2.Cu")
		(net "PWM_OUT_ZONE_C")
	)
	(segment
		(start 97.432876 -7.36727)
		(end 98.600006 -6.20014)
		(width 0.127)
		(layer "In2.Cu")
		(net "PWM_OUT_ZONE_C")
	)
	(segment
		(start 77.79512 -20.973796)
		(end 90.860372 -20.973796)
		(width 0.127)
		(layer "In2.Cu")
		(net "PWM_OUT_ZONE_C")
	)
	(segment
		(start 97.432876 -8.534654)
		(end 97.432876 -7.36727)
		(width 0.127)
		(layer "In2.Cu")
		(net "PWM_OUT_ZONE_C")
	)
	(segment
		(start 187.0456 -115.9256)
		(end 186.97702 -115.85702)
		(width 0.254)
		(layer "F.Cu")
		(net "P1V8_C_G_PG")
	)
	(segment
		(start 186.44616 -112.841786)
		(end 186.814968 -113.210594)
		(width 0.254)
		(layer "F.Cu")
		(net "P1V8_C_G_PG")
	)
	(segment
		(start 186.814968 -114.536728)
		(end 186.97702 -114.69878)
		(width 0.254)
		(layer "F.Cu")
		(net "P1V8_C_G_PG")
	)
	(segment
		(start 186.44616 -112.10036)
		(end 186.44616 -112.841786)
		(width 0.254)
		(layer "F.Cu")
		(net "P1V8_C_G_PG")
	)
	(segment
		(start 186.97702 -115.85702)
		(end 186.97702 -114.69878)
		(width 0.254)
		(layer "F.Cu")
		(net "P1V8_C_G_PG")
	)
	(segment
		(start 186.814968 -113.631218)
		(end 186.814968 -114.536728)
		(width 0.254)
		(layer "F.Cu")
		(net "P1V8_C_G_PG")
	)
	(segment
		(start 188.1886 -115.9256)
		(end 187.0456 -115.9256)
		(width 0.254)
		(layer "F.Cu")
		(net "P1V8_C_G_PG")
	)
	(segment
		(start 186.814968 -113.210594)
		(end 186.814968 -113.631218)
		(width 0.254)
		(layer "F.Cu")
		(net "P1V8_C_G_PG")
	)
	(via
		(at 186.97702 -114.69878)
		(size 0.6604)
		(drill 0.3302)
		(layers "F.Cu" "B.Cu")
		(net "P1V8_C_G_PG")
	)
	(via
		(at 188.1886 -115.9256)
		(size 0.508)
		(drill 0.254)
		(layers "F.Cu" "B.Cu")
		(net "P1V8_C_G_PG")
	)
	(segment
		(start 188.054234 -115.791234)
		(end 186.362848 -115.791234)
		(width 0.254)
		(layer "B.Cu")
		(net "P1V8_C_G_PG")
	)
	(segment
		(start 188.1886 -115.9256)
		(end 188.054234 -115.791234)
		(width 0.254)
		(layer "B.Cu")
		(net "P1V8_C_G_PG")
	)
	(segment
		(start 185.378598 -108.772198)
		(end 185.378598 -107.961938)
		(width 0.254)
		(layer "F.Cu")
		(net "P0V9_G_PG")
	)
	(segment
		(start 185.46191 -108.85551)
		(end 185.46191 -110.19536)
		(width 0.254)
		(layer "F.Cu")
		(net "P0V9_G_PG")
	)
	(segment
		(start 185.378598 -108.772198)
		(end 185.46191 -108.85551)
		(width 0.254)
		(layer "F.Cu")
		(net "P0V9_G_PG")
	)
	(segment
		(start 185.378598 -107.961938)
		(end 185.09488 -107.67822)
		(width 0.254)
		(layer "F.Cu")
		(net "P0V9_G_PG")
	)
	(via
		(at 185.378598 -108.772198)
		(size 0.6604)
		(drill 0.3302)
		(layers "F.Cu" "B.Cu")
		(net "P0V9_G_PG")
	)
	(segment
		(start 56.388 -77.0255)
		(end 56.388 -76.514452)
		(width 0.127)
		(layer "F.Cu")
		(net "LS_EN_U41")
	)
	(segment
		(start 55.02656 -75.8698)
		(end 55.02656 -74.86396)
		(width 0.127)
		(layer "F.Cu")
		(net "LS_EN_U41")
	)
	(segment
		(start 56.3372 -76.463652)
		(end 56.3372 -75.8952)
		(width 0.127)
		(layer "F.Cu")
		(net "LS_EN_U41")
	)
	(segment
		(start 56.3372 -75.419458)
		(end 56.3372 -75.8952)
		(width 0.127)
		(layer "F.Cu")
		(net "LS_EN_U41")
	)
	(segment
		(start 54.9656 -73.2917)
		(end 54.9656 -74.047858)
		(width 0.127)
		(layer "F.Cu")
		(net "LS_EN_U41")
	)
	(segment
		(start 56.388 -76.514452)
		(end 56.3372 -76.463652)
		(width 0.127)
		(layer "F.Cu")
		(net "LS_EN_U41")
	)
	(segment
		(start 55.02656 -74.86396)
		(end 54.4576 -74.295)
		(width 0.127)
		(layer "F.Cu")
		(net "LS_EN_U41")
	)
	(segment
		(start 54.6862 -73.0123)
		(end 54.9656 -73.2917)
		(width 0.127)
		(layer "F.Cu")
		(net "LS_EN_U41")
	)
	(segment
		(start 54.9656 -74.047858)
		(end 56.3372 -75.419458)
		(width 0.127)
		(layer "F.Cu")
		(net "LS_EN_U41")
	)
	(segment
		(start 54.4576 -74.295)
		(end 54.4576 -73.2409)
		(width 0.127)
		(layer "F.Cu")
		(net "LS_EN_U41")
	)
	(segment
		(start 54.4576 -73.2409)
		(end 54.6862 -73.0123)
		(width 0.127)
		(layer "F.Cu")
		(net "LS_EN_U41")
	)
	(via
		(at 56.3372 -75.8952)
		(size 0.6604)
		(drill 0.3302)
		(layers "F.Cu" "B.Cu")
		(net "LS_EN_U41")
	)
	(segment
		(start 70.026784 -77.318616)
		(end 70.026784 -79.84236)
		(width 0.127)
		(layer "F.Cu")
		(net "I2C_EXP_IOC_SDA8")
	)
	(segment
		(start 70.727824 -75.548236)
		(end 70.962012 -75.782424)
		(width 0.127)
		(layer "F.Cu")
		(net "I2C_EXP_IOC_SDA8")
	)
	(segment
		(start 70.727824 -75.548236)
		(end 70.4342 -75.84186)
		(width 0.127)
		(layer "F.Cu")
		(net "I2C_EXP_IOC_SDA8")
	)
	(segment
		(start 125.50013 -78.500224)
		(end 126.000002 -79.000096)
		(width 0.127)
		(layer "F.Cu")
		(net "I2C_EXP_IOC_SDA8")
	)
	(segment
		(start 70.4342 -76.9112)
		(end 70.026784 -77.318616)
		(width 0.127)
		(layer "F.Cu")
		(net "I2C_EXP_IOC_SDA8")
	)
	(segment
		(start 70.962012 -75.782424)
		(end 70.962012 -77.314806)
		(width 0.127)
		(layer "F.Cu")
		(net "I2C_EXP_IOC_SDA8")
	)
	(segment
		(start 70.4342 -75.84186)
		(end 70.4342 -76.9112)
		(width 0.127)
		(layer "F.Cu")
		(net "I2C_EXP_IOC_SDA8")
	)
	(via
		(at 70.026784 -79.84236)
		(size 0.508)
		(drill 0.254)
		(layers "F.Cu" "B.Cu")
		(net "I2C_EXP_IOC_SDA8")
	)
	(via
		(at 126.000002 -79.000096)
		(size 0.4572)
		(drill 0.2032)
		(layers "F.Cu" "B.Cu")
		(net "I2C_EXP_IOC_SDA8")
	)
	(via
		(at 126.500128 -79.499968)
		(size 0.6096)
		(drill 0.3048)
		(layers "F.Cu" "B.Cu")
		(net "I2C_EXP_IOC_SDA8")
	)
	(via
		(at 132.566156 -84.558378)
		(size 0.508)
		(drill 0.254)
		(layers "F.Cu" "B.Cu")
		(net "I2C_EXP_IOC_SDA8")
	)
	(segment
		(start 126.500128 -79.499968)
		(end 127.122936 -79.499968)
		(width 0.127)
		(layer "B.Cu")
		(net "I2C_EXP_IOC_SDA8")
	)
	(segment
		(start 132.217414 -83.511898)
		(end 132.423916 -83.7184)
		(width 0.127)
		(layer "B.Cu")
		(net "I2C_EXP_IOC_SDA8")
	)
	(segment
		(start 129.393696 -80.83677)
		(end 129.393696 -81.765902)
		(width 0.127)
		(layer "B.Cu")
		(net "I2C_EXP_IOC_SDA8")
	)
	(segment
		(start 132.423916 -83.7184)
		(end 134.310882 -83.7184)
		(width 0.127)
		(layer "B.Cu")
		(net "I2C_EXP_IOC_SDA8")
	)
	(segment
		(start 127.122936 -79.499968)
		(end 127.805688 -80.18272)
		(width 0.127)
		(layer "B.Cu")
		(net "I2C_EXP_IOC_SDA8")
	)
	(segment
		(start 128.16713 -80.18272)
		(end 128.590802 -80.606392)
		(width 0.127)
		(layer "B.Cu")
		(net "I2C_EXP_IOC_SDA8")
	)
	(segment
		(start 126.500128 -79.499968)
		(end 126.499874 -79.499968)
		(width 0.127)
		(layer "B.Cu")
		(net "I2C_EXP_IOC_SDA8")
	)
	(segment
		(start 128.590802 -80.606392)
		(end 129.163318 -80.606392)
		(width 0.127)
		(layer "B.Cu")
		(net "I2C_EXP_IOC_SDA8")
	)
	(segment
		(start 132.566156 -84.558378)
		(end 132.669534 -84.455)
		(width 0.127)
		(layer "B.Cu")
		(net "I2C_EXP_IOC_SDA8")
	)
	(segment
		(start 126.499874 -79.499968)
		(end 126.000002 -79.000096)
		(width 0.127)
		(layer "B.Cu")
		(net "I2C_EXP_IOC_SDA8")
	)
	(segment
		(start 134.606538 -84.014056)
		(end 134.606538 -84.2645)
		(width 0.127)
		(layer "B.Cu")
		(net "I2C_EXP_IOC_SDA8")
	)
	(segment
		(start 134.416038 -84.455)
		(end 134.606538 -84.2645)
		(width 0.127)
		(layer "B.Cu")
		(net "I2C_EXP_IOC_SDA8")
	)
	(segment
		(start 134.310882 -83.7184)
		(end 134.606538 -84.014056)
		(width 0.127)
		(layer "B.Cu")
		(net "I2C_EXP_IOC_SDA8")
	)
	(segment
		(start 131.139692 -83.511898)
		(end 132.217414 -83.511898)
		(width 0.127)
		(layer "B.Cu")
		(net "I2C_EXP_IOC_SDA8")
	)
	(segment
		(start 129.163318 -80.606392)
		(end 129.393696 -80.83677)
		(width 0.127)
		(layer "B.Cu")
		(net "I2C_EXP_IOC_SDA8")
	)
	(segment
		(start 132.669534 -84.455)
		(end 134.416038 -84.455)
		(width 0.127)
		(layer "B.Cu")
		(net "I2C_EXP_IOC_SDA8")
	)
	(segment
		(start 127.805688 -80.18272)
		(end 128.16713 -80.18272)
		(width 0.127)
		(layer "B.Cu")
		(net "I2C_EXP_IOC_SDA8")
	)
	(segment
		(start 129.393696 -81.765902)
		(end 131.139692 -83.511898)
		(width 0.127)
		(layer "B.Cu")
		(net "I2C_EXP_IOC_SDA8")
	)
	(segment
		(start 100.714556 -92.975938)
		(end 98.171254 -95.51924)
		(width 0.127)
		(layer "In5.Cu")
		(net "I2C_EXP_IOC_SDA8")
	)
	(segment
		(start 126.21387 -85.0392)
		(end 120.97893 -90.27414)
		(width 0.127)
		(layer "In5.Cu")
		(net "I2C_EXP_IOC_SDA8")
	)
	(segment
		(start 132.509514 -84.61502)
		(end 131.06527 -84.61502)
		(width 0.127)
		(layer "In5.Cu")
		(net "I2C_EXP_IOC_SDA8")
	)
	(segment
		(start 98.171254 -95.51924)
		(end 80.82915 -95.51924)
		(width 0.127)
		(layer "In5.Cu")
		(net "I2C_EXP_IOC_SDA8")
	)
	(segment
		(start 131.06527 -84.61502)
		(end 130.64109 -85.0392)
		(width 0.127)
		(layer "In5.Cu")
		(net "I2C_EXP_IOC_SDA8")
	)
	(segment
		(start 132.566156 -84.558378)
		(end 132.509514 -84.61502)
		(width 0.127)
		(layer "In5.Cu")
		(net "I2C_EXP_IOC_SDA8")
	)
	(segment
		(start 130.64109 -85.0392)
		(end 126.21387 -85.0392)
		(width 0.127)
		(layer "In5.Cu")
		(net "I2C_EXP_IOC_SDA8")
	)
	(segment
		(start 72.362568 -87.052658)
		(end 72.362568 -82.178144)
		(width 0.127)
		(layer "In5.Cu")
		(net "I2C_EXP_IOC_SDA8")
	)
	(segment
		(start 80.82915 -95.51924)
		(end 72.362568 -87.052658)
		(width 0.127)
		(layer "In5.Cu")
		(net "I2C_EXP_IOC_SDA8")
	)
	(segment
		(start 120.97893 -90.27414)
		(end 117.620542 -90.27414)
		(width 0.127)
		(layer "In5.Cu")
		(net "I2C_EXP_IOC_SDA8")
	)
	(segment
		(start 114.918744 -92.975938)
		(end 100.714556 -92.975938)
		(width 0.127)
		(layer "In5.Cu")
		(net "I2C_EXP_IOC_SDA8")
	)
	(segment
		(start 72.362568 -82.178144)
		(end 70.026784 -79.84236)
		(width 0.127)
		(layer "In5.Cu")
		(net "I2C_EXP_IOC_SDA8")
	)
	(segment
		(start 117.620542 -90.27414)
		(end 114.918744 -92.975938)
		(width 0.127)
		(layer "In5.Cu")
		(net "I2C_EXP_IOC_SDA8")
	)
	(segment
		(start 131.933696 -83.933792)
		(end 129.500122 -81.500218)
		(width 0.127)
		(layer "F.Cu")
		(net "I2C_EXP_IOC_SCL8")
	)
	(segment
		(start 73.288144 -79.950056)
		(end 73.288144 -75.451716)
		(width 0.127)
		(layer "F.Cu")
		(net "I2C_EXP_IOC_SCL8")
	)
	(segment
		(start 134.07771 -85.262466)
		(end 133.865112 -85.262466)
		(width 0.127)
		(layer "F.Cu")
		(net "I2C_EXP_IOC_SCL8")
	)
	(segment
		(start 73.288144 -75.451716)
		(end 73.420224 -75.319636)
		(width 0.127)
		(layer "F.Cu")
		(net "I2C_EXP_IOC_SCL8")
	)
	(segment
		(start 74.254868 -75.076304)
		(end 74.011536 -75.319636)
		(width 0.127)
		(layer "F.Cu")
		(net "I2C_EXP_IOC_SCL8")
	)
	(segment
		(start 74.011536 -75.319636)
		(end 73.420224 -75.319636)
		(width 0.127)
		(layer "F.Cu")
		(net "I2C_EXP_IOC_SCL8")
	)
	(segment
		(start 74.855832 -75.076304)
		(end 74.254868 -75.076304)
		(width 0.127)
		(layer "F.Cu")
		(net "I2C_EXP_IOC_SCL8")
	)
	(segment
		(start 74.264012 -77.314806)
		(end 74.264012 -76.096114)
		(width 0.127)
		(layer "F.Cu")
		(net "I2C_EXP_IOC_SCL8")
	)
	(segment
		(start 74.855832 -75.504294)
		(end 74.855832 -75.076304)
		(width 0.127)
		(layer "F.Cu")
		(net "I2C_EXP_IOC_SCL8")
	)
	(segment
		(start 132.536438 -83.933792)
		(end 131.985766 -83.933792)
		(width 0.127)
		(layer "F.Cu")
		(net "I2C_EXP_IOC_SCL8")
	)
	(segment
		(start 74.264012 -76.096114)
		(end 74.855832 -75.504294)
		(width 0.127)
		(layer "F.Cu")
		(net "I2C_EXP_IOC_SCL8")
	)
	(segment
		(start 131.985766 -83.933792)
		(end 131.933696 -83.933792)
		(width 0.127)
		(layer "F.Cu")
		(net "I2C_EXP_IOC_SCL8")
	)
	(segment
		(start 133.865112 -85.262466)
		(end 132.536438 -83.933792)
		(width 0.127)
		(layer "F.Cu")
		(net "I2C_EXP_IOC_SCL8")
	)
	(via
		(at 73.420224 -75.319636)
		(size 0.6604)
		(drill 0.3302)
		(layers "F.Cu" "B.Cu")
		(net "I2C_EXP_IOC_SCL8")
	)
	(via
		(at 131.985766 -83.933792)
		(size 0.508)
		(drill 0.254)
		(layers "F.Cu" "B.Cu")
		(net "I2C_EXP_IOC_SCL8")
	)
	(via
		(at 73.288144 -79.950056)
		(size 0.508)
		(drill 0.254)
		(layers "F.Cu" "B.Cu")
		(net "I2C_EXP_IOC_SCL8")
	)
	(segment
		(start 117.098318 -89.76614)
		(end 120.768364 -89.76614)
		(width 0.127)
		(layer "In5.Cu")
		(net "I2C_EXP_IOC_SCL8")
	)
	(segment
		(start 122.964194 -87.525098)
		(end 125.781308 -84.708746)
		(width 0.127)
		(layer "In5.Cu")
		(net "I2C_EXP_IOC_SCL8")
	)
	(segment
		(start 120.768364 -89.76614)
		(end 121.795286 -88.739218)
		(width 0.127)
		(layer "In5.Cu")
		(net "I2C_EXP_IOC_SCL8")
	)
	(segment
		(start 72.870568 -80.367632)
		(end 72.870568 -86.842092)
		(width 0.127)
		(layer "In5.Cu")
		(net "I2C_EXP_IOC_SCL8")
	)
	(segment
		(start 122.381264 -87.525098)
		(end 122.964194 -87.525098)
		(width 0.127)
		(layer "In5.Cu")
		(net "I2C_EXP_IOC_SCL8")
	)
	(segment
		(start 125.781308 -84.708746)
		(end 130.368802 -84.708746)
		(width 0.127)
		(layer "In5.Cu")
		(net "I2C_EXP_IOC_SCL8")
	)
	(segment
		(start 121.795286 -88.739218)
		(end 121.795286 -88.111076)
		(width 0.127)
		(layer "In5.Cu")
		(net "I2C_EXP_IOC_SCL8")
	)
	(segment
		(start 114.39652 -92.467938)
		(end 117.098318 -89.76614)
		(width 0.127)
		(layer "In5.Cu")
		(net "I2C_EXP_IOC_SCL8")
	)
	(segment
		(start 121.795286 -88.111076)
		(end 122.381264 -87.525098)
		(width 0.127)
		(layer "In5.Cu")
		(net "I2C_EXP_IOC_SCL8")
	)
	(segment
		(start 130.368802 -84.708746)
		(end 131.338574 -83.738974)
		(width 0.127)
		(layer "In5.Cu")
		(net "I2C_EXP_IOC_SCL8")
	)
	(segment
		(start 100.50399 -92.467938)
		(end 114.39652 -92.467938)
		(width 0.127)
		(layer "In5.Cu")
		(net "I2C_EXP_IOC_SCL8")
	)
	(segment
		(start 81.039716 -95.01124)
		(end 97.960688 -95.01124)
		(width 0.127)
		(layer "In5.Cu")
		(net "I2C_EXP_IOC_SCL8")
	)
	(segment
		(start 73.288144 -79.950056)
		(end 72.870568 -80.367632)
		(width 0.127)
		(layer "In5.Cu")
		(net "I2C_EXP_IOC_SCL8")
	)
	(segment
		(start 131.790948 -83.738974)
		(end 131.985766 -83.933792)
		(width 0.127)
		(layer "In5.Cu")
		(net "I2C_EXP_IOC_SCL8")
	)
	(segment
		(start 72.870568 -86.842092)
		(end 81.039716 -95.01124)
		(width 0.127)
		(layer "In5.Cu")
		(net "I2C_EXP_IOC_SCL8")
	)
	(segment
		(start 97.960688 -95.01124)
		(end 100.50399 -92.467938)
		(width 0.127)
		(layer "In5.Cu")
		(net "I2C_EXP_IOC_SCL8")
	)
	(segment
		(start 131.338574 -83.738974)
		(end 131.790948 -83.738974)
		(width 0.127)
		(layer "In5.Cu")
		(net "I2C_EXP_IOC_SCL8")
	)
	(segment
		(start 54.991 -83.82)
		(end 53.07584 -81.90484)
		(width 0.127)
		(layer "F.Cu")
		(net "I2C_CLIP_SDA7_LS")
	)
	(segment
		(start 124.500132 -77.500226)
		(end 125.000004 -78.000098)
		(width 0.127)
		(layer "F.Cu")
		(net "I2C_CLIP_SDA7_LS")
	)
	(segment
		(start 55.4482 -83.82)
		(end 54.991 -83.82)
		(width 0.127)
		(layer "F.Cu")
		(net "I2C_CLIP_SDA7_LS")
	)
	(segment
		(start 53.07584 -80.9752)
		(end 53.07584 -79.121)
		(width 0.127)
		(layer "F.Cu")
		(net "I2C_CLIP_SDA7_LS")
	)
	(segment
		(start 53.07584 -81.90484)
		(end 53.07584 -80.9752)
		(width 0.127)
		(layer "F.Cu")
		(net "I2C_CLIP_SDA7_LS")
	)
	(via
		(at 129.575052 -88.519)
		(size 0.508)
		(drill 0.254)
		(layers "F.Cu" "B.Cu")
		(net "I2C_CLIP_SDA7_LS")
	)
	(via
		(at 55.4482 -83.82)
		(size 0.508)
		(drill 0.254)
		(layers "F.Cu" "B.Cu")
		(net "I2C_CLIP_SDA7_LS")
	)
	(via
		(at 125.000004 -78.000098)
		(size 0.4572)
		(drill 0.2032)
		(layers "F.Cu" "B.Cu")
		(net "I2C_CLIP_SDA7_LS")
	)
	(via
		(at 53.07584 -80.9752)
		(size 0.6604)
		(drill 0.3302)
		(layers "F.Cu" "B.Cu")
		(net "I2C_CLIP_SDA7_LS")
	)
	(segment
		(start 129.54 -89.2937)
		(end 129.54 -88.554052)
		(width 0.127)
		(layer "B.Cu")
		(net "I2C_CLIP_SDA7_LS")
	)
	(segment
		(start 129.54 -88.554052)
		(end 129.575052 -88.519)
		(width 0.127)
		(layer "B.Cu")
		(net "I2C_CLIP_SDA7_LS")
	)
	(segment
		(start 126.238 -82.0039)
		(end 127.2921 -83.058)
		(width 0.127)
		(layer "In2.Cu")
		(net "I2C_CLIP_SDA7_LS")
	)
	(segment
		(start 125.393704 -80.943704)
		(end 125.606302 -81.156302)
		(width 0.127)
		(layer "In2.Cu")
		(net "I2C_CLIP_SDA7_LS")
	)
	(segment
		(start 127.2921 -83.058)
		(end 127.2921 -84.3788)
		(width 0.127)
		(layer "In2.Cu")
		(net "I2C_CLIP_SDA7_LS")
	)
	(segment
		(start 125.606302 -81.156302)
		(end 125.606302 -81.163414)
		(width 0.127)
		(layer "In2.Cu")
		(net "I2C_CLIP_SDA7_LS")
	)
	(segment
		(start 125.000004 -78.000098)
		(end 125.068838 -78.068932)
		(width 0.127)
		(layer "In2.Cu")
		(net "I2C_CLIP_SDA7_LS")
	)
	(segment
		(start 125.843792 -81.393792)
		(end 126.238 -81.788)
		(width 0.127)
		(layer "In2.Cu")
		(net "I2C_CLIP_SDA7_LS")
	)
	(segment
		(start 125.606302 -81.163414)
		(end 125.83668 -81.393792)
		(width 0.127)
		(layer "In2.Cu")
		(net "I2C_CLIP_SDA7_LS")
	)
	(segment
		(start 128.3335 -86.428834)
		(end 129.575052 -87.670386)
		(width 0.127)
		(layer "In2.Cu")
		(net "I2C_CLIP_SDA7_LS")
	)
	(segment
		(start 125.393704 -78.836774)
		(end 125.393704 -80.943704)
		(width 0.127)
		(layer "In2.Cu")
		(net "I2C_CLIP_SDA7_LS")
	)
	(segment
		(start 126.238 -81.788)
		(end 126.238 -82.0039)
		(width 0.127)
		(layer "In2.Cu")
		(net "I2C_CLIP_SDA7_LS")
	)
	(segment
		(start 125.068838 -78.068932)
		(end 125.068838 -78.511908)
		(width 0.127)
		(layer "In2.Cu")
		(net "I2C_CLIP_SDA7_LS")
	)
	(segment
		(start 128.3335 -85.4202)
		(end 128.3335 -86.428834)
		(width 0.127)
		(layer "In2.Cu")
		(net "I2C_CLIP_SDA7_LS")
	)
	(segment
		(start 127.2921 -84.3788)
		(end 128.3335 -85.4202)
		(width 0.127)
		(layer "In2.Cu")
		(net "I2C_CLIP_SDA7_LS")
	)
	(segment
		(start 129.575052 -87.670386)
		(end 129.575052 -88.519)
		(width 0.127)
		(layer "In2.Cu")
		(net "I2C_CLIP_SDA7_LS")
	)
	(segment
		(start 125.068838 -78.511908)
		(end 125.393704 -78.836774)
		(width 0.127)
		(layer "In2.Cu")
		(net "I2C_CLIP_SDA7_LS")
	)
	(segment
		(start 125.83668 -81.393792)
		(end 125.843792 -81.393792)
		(width 0.127)
		(layer "In2.Cu")
		(net "I2C_CLIP_SDA7_LS")
	)
	(segment
		(start 126.5809 -93.248734)
		(end 127.5588 -92.270834)
		(width 0.127)
		(layer "In5.Cu")
		(net "I2C_CLIP_SDA7_LS")
	)
	(segment
		(start 127.5588 -92.270834)
		(end 127.5588 -91.887802)
		(width 0.127)
		(layer "In5.Cu")
		(net "I2C_CLIP_SDA7_LS")
	)
	(segment
		(start 122.961146 -97.039938)
		(end 126.5809 -93.420184)
		(width 0.127)
		(layer "In5.Cu")
		(net "I2C_CLIP_SDA7_LS")
	)
	(segment
		(start 58.641742 -90.267536)
		(end 66.243454 -90.267536)
		(width 0.127)
		(layer "In5.Cu")
		(net "I2C_CLIP_SDA7_LS")
	)
	(segment
		(start 66.243454 -90.267536)
		(end 76.937108 -100.96119)
		(width 0.127)
		(layer "In5.Cu")
		(net "I2C_CLIP_SDA7_LS")
	)
	(segment
		(start 127.6477 -90.516202)
		(end 129.53873 -88.625172)
		(width 0.127)
		(layer "In5.Cu")
		(net "I2C_CLIP_SDA7_LS")
	)
	(segment
		(start 127.6477 -91.798902)
		(end 127.6477 -90.516202)
		(width 0.127)
		(layer "In5.Cu")
		(net "I2C_CLIP_SDA7_LS")
	)
	(segment
		(start 129.53873 -88.555322)
		(end 129.575052 -88.519)
		(width 0.127)
		(layer "In5.Cu")
		(net "I2C_CLIP_SDA7_LS")
	)
	(segment
		(start 55.4482 -83.82)
		(end 55.4482 -87.073994)
		(width 0.127)
		(layer "In5.Cu")
		(net "I2C_CLIP_SDA7_LS")
	)
	(segment
		(start 102.399084 -97.039938)
		(end 122.961146 -97.039938)
		(width 0.127)
		(layer "In5.Cu")
		(net "I2C_CLIP_SDA7_LS")
	)
	(segment
		(start 76.937108 -100.96119)
		(end 98.477832 -100.96119)
		(width 0.127)
		(layer "In5.Cu")
		(net "I2C_CLIP_SDA7_LS")
	)
	(segment
		(start 129.53873 -88.625172)
		(end 129.53873 -88.555322)
		(width 0.127)
		(layer "In5.Cu")
		(net "I2C_CLIP_SDA7_LS")
	)
	(segment
		(start 55.4482 -87.073994)
		(end 58.641742 -90.267536)
		(width 0.127)
		(layer "In5.Cu")
		(net "I2C_CLIP_SDA7_LS")
	)
	(segment
		(start 127.5588 -91.887802)
		(end 127.6477 -91.798902)
		(width 0.127)
		(layer "In5.Cu")
		(net "I2C_CLIP_SDA7_LS")
	)
	(segment
		(start 126.5809 -93.420184)
		(end 126.5809 -93.248734)
		(width 0.127)
		(layer "In5.Cu")
		(net "I2C_CLIP_SDA7_LS")
	)
	(segment
		(start 98.477832 -100.96119)
		(end 102.399084 -97.039938)
		(width 0.127)
		(layer "In5.Cu")
		(net "I2C_CLIP_SDA7_LS")
	)
	(segment
		(start 51.1175 -72.8853)
		(end 51.1175 -72.250046)
		(width 0.127)
		(layer "F.Cu")
		(net "I2C_CLIP_SDA7")
	)
	(segment
		(start 49.7586 -76.6318)
		(end 49.3268 -76.2)
		(width 0.127)
		(layer "F.Cu")
		(net "I2C_CLIP_SDA7")
	)
	(segment
		(start 52.365148 -75.8698)
		(end 52.339748 -75.8952)
		(width 0.127)
		(layer "F.Cu")
		(net "I2C_CLIP_SDA7")
	)
	(segment
		(start 51.1175 -72.250046)
		(end 52.069238 -71.298308)
		(width 0.127)
		(layer "F.Cu")
		(net "I2C_CLIP_SDA7")
	)
	(segment
		(start 53.07584 -75.8698)
		(end 52.365148 -75.8698)
		(width 0.127)
		(layer "F.Cu")
		(net "I2C_CLIP_SDA7")
	)
	(segment
		(start 50.4698 -73.533)
		(end 51.1175 -72.8853)
		(width 0.127)
		(layer "F.Cu")
		(net "I2C_CLIP_SDA7")
	)
	(segment
		(start 51.7525 -76.3143)
		(end 51.435 -76.6318)
		(width 0.127)
		(layer "F.Cu")
		(net "I2C_CLIP_SDA7")
	)
	(segment
		(start 49.3268 -76.2)
		(end 49.3268 -74.676)
		(width 0.127)
		(layer "F.Cu")
		(net "I2C_CLIP_SDA7")
	)
	(segment
		(start 51.435 -76.6318)
		(end 49.7586 -76.6318)
		(width 0.127)
		(layer "F.Cu")
		(net "I2C_CLIP_SDA7")
	)
	(segment
		(start 49.3268 -74.676)
		(end 50.4698 -73.533)
		(width 0.127)
		(layer "F.Cu")
		(net "I2C_CLIP_SDA7")
	)
	(segment
		(start 52.339748 -75.8952)
		(end 51.7525 -75.8952)
		(width 0.127)
		(layer "F.Cu")
		(net "I2C_CLIP_SDA7")
	)
	(segment
		(start 51.7525 -75.8952)
		(end 51.7525 -76.3143)
		(width 0.127)
		(layer "F.Cu")
		(net "I2C_CLIP_SDA7")
	)
	(via
		(at 50.4698 -73.533)
		(size 0.6604)
		(drill 0.3302)
		(layers "F.Cu" "B.Cu")
		(net "I2C_CLIP_SDA7")
	)
	(via
		(at 52.069238 -71.298308)
		(size 0.508)
		(drill 0.254)
		(layers "F.Cu" "B.Cu")
		(net "I2C_CLIP_SDA7")
	)
	(segment
		(start 52.069238 -69.82968)
		(end 52.069238 -71.298308)
		(width 0.127)
		(layer "In2.Cu")
		(net "I2C_CLIP_SDA7")
	)
	(segment
		(start 106.436922 -8.236966)
		(end 106.436922 -12.471654)
		(width 0.127)
		(layer "In2.Cu")
		(net "I2C_CLIP_SDA7")
	)
	(segment
		(start 71.693024 -39.364158)
		(end 71.693024 -51.072542)
		(width 0.127)
		(layer "In2.Cu")
		(net "I2C_CLIP_SDA7")
	)
	(segment
		(start 93.846396 -25.06218)
		(end 81.731358 -25.06218)
		(width 0.127)
		(layer "In2.Cu")
		(net "I2C_CLIP_SDA7")
	)
	(segment
		(start 55.503572 -66.395346)
		(end 52.069238 -69.82968)
		(width 0.127)
		(layer "In2.Cu")
		(net "I2C_CLIP_SDA7")
	)
	(segment
		(start 68.433188 -62.795912)
		(end 66.600324 -62.795912)
		(width 0.127)
		(layer "In2.Cu")
		(net "I2C_CLIP_SDA7")
	)
	(segment
		(start 76.57846 -34.478722)
		(end 71.693024 -39.364158)
		(width 0.127)
		(layer "In2.Cu")
		(net "I2C_CLIP_SDA7")
	)
	(segment
		(start 71.693024 -51.072542)
		(end 70.581774 -52.183792)
		(width 0.127)
		(layer "In2.Cu")
		(net "I2C_CLIP_SDA7")
	)
	(segment
		(start 66.600324 -62.795912)
		(end 63.00089 -66.395346)
		(width 0.127)
		(layer "In2.Cu")
		(net "I2C_CLIP_SDA7")
	)
	(segment
		(start 81.731358 -25.06218)
		(end 76.57846 -30.215078)
		(width 0.127)
		(layer "In2.Cu")
		(net "I2C_CLIP_SDA7")
	)
	(segment
		(start 70.581774 -52.183792)
		(end 70.581774 -60.647326)
		(width 0.127)
		(layer "In2.Cu")
		(net "I2C_CLIP_SDA7")
	)
	(segment
		(start 70.581774 -60.647326)
		(end 68.433188 -62.795912)
		(width 0.127)
		(layer "In2.Cu")
		(net "I2C_CLIP_SDA7")
	)
	(segment
		(start 76.57846 -30.215078)
		(end 76.57846 -34.478722)
		(width 0.127)
		(layer "In2.Cu")
		(net "I2C_CLIP_SDA7")
	)
	(segment
		(start 106.436922 -12.471654)
		(end 93.846396 -25.06218)
		(width 0.127)
		(layer "In2.Cu")
		(net "I2C_CLIP_SDA7")
	)
	(segment
		(start 63.00089 -66.395346)
		(end 55.503572 -66.395346)
		(width 0.127)
		(layer "In2.Cu")
		(net "I2C_CLIP_SDA7")
	)
	(segment
		(start 105.800144 -7.600188)
		(end 106.436922 -8.236966)
		(width 0.127)
		(layer "In2.Cu")
		(net "I2C_CLIP_SDA7")
	)
	(segment
		(start 53.72608 -79.121)
		(end 53.72608 -81.66608)
		(width 0.127)
		(layer "F.Cu")
		(net "I2C_CLIP_SCL7_LS")
	)
	(segment
		(start 54.4068 -82.3468)
		(end 55.0164 -82.9564)
		(width 0.127)
		(layer "F.Cu")
		(net "I2C_CLIP_SCL7_LS")
	)
	(segment
		(start 53.72608 -81.66608)
		(end 54.4068 -82.3468)
		(width 0.127)
		(layer "F.Cu")
		(net "I2C_CLIP_SCL7_LS")
	)
	(segment
		(start 55.0164 -82.9564)
		(end 55.4736 -82.9564)
		(width 0.127)
		(layer "F.Cu")
		(net "I2C_CLIP_SCL7_LS")
	)
	(segment
		(start 121.500138 -73.500234)
		(end 122.00001 -74.000106)
		(width 0.127)
		(layer "F.Cu")
		(net "I2C_CLIP_SCL7_LS")
	)
	(via
		(at 122.00001 -74.000106)
		(size 0.4572)
		(drill 0.2032)
		(layers "F.Cu" "B.Cu")
		(net "I2C_CLIP_SCL7_LS")
	)
	(via
		(at 54.4068 -82.3468)
		(size 0.6604)
		(drill 0.3302)
		(layers "F.Cu" "B.Cu")
		(net "I2C_CLIP_SCL7_LS")
	)
	(via
		(at 128.590548 -88.519)
		(size 0.508)
		(drill 0.254)
		(layers "F.Cu" "B.Cu")
		(net "I2C_CLIP_SCL7_LS")
	)
	(via
		(at 55.4736 -82.9564)
		(size 0.508)
		(drill 0.254)
		(layers "F.Cu" "B.Cu")
		(net "I2C_CLIP_SCL7_LS")
	)
	(segment
		(start 128.524 -89.2937)
		(end 128.524 -88.585548)
		(width 0.127)
		(layer "B.Cu")
		(net "I2C_CLIP_SCL7_LS")
	)
	(segment
		(start 128.524 -88.585548)
		(end 128.590548 -88.519)
		(width 0.127)
		(layer "B.Cu")
		(net "I2C_CLIP_SCL7_LS")
	)
	(segment
		(start 124.393706 -81.010506)
		(end 124.393706 -78.836774)
		(width 0.127)
		(layer "In2.Cu")
		(net "I2C_CLIP_SCL7_LS")
	)
	(segment
		(start 126.8222 -83.439)
		(end 125.857 -82.4738)
		(width 0.127)
		(layer "In2.Cu")
		(net "I2C_CLIP_SCL7_LS")
	)
	(segment
		(start 125.857 -82.169)
		(end 125.222 -81.534)
		(width 0.127)
		(layer "In2.Cu")
		(net "I2C_CLIP_SCL7_LS")
	)
	(segment
		(start 122.682 -76.4794)
		(end 122.555 -76.3524)
		(width 0.127)
		(layer "In2.Cu")
		(net "I2C_CLIP_SCL7_LS")
	)
	(segment
		(start 125.222 -81.534)
		(end 124.9172 -81.534)
		(width 0.127)
		(layer "In2.Cu")
		(net "I2C_CLIP_SCL7_LS")
	)
	(segment
		(start 126.8222 -84.389468)
		(end 126.8222 -83.439)
		(width 0.127)
		(layer "In2.Cu")
		(net "I2C_CLIP_SCL7_LS")
	)
	(segment
		(start 121.7422 -75.565)
		(end 121.412 -75.2348)
		(width 0.127)
		(layer "In2.Cu")
		(net "I2C_CLIP_SCL7_LS")
	)
	(segment
		(start 127.8255 -85.392768)
		(end 126.8222 -84.389468)
		(width 0.127)
		(layer "In2.Cu")
		(net "I2C_CLIP_SCL7_LS")
	)
	(segment
		(start 122.3264 -75.565)
		(end 121.7422 -75.565)
		(width 0.127)
		(layer "In2.Cu")
		(net "I2C_CLIP_SCL7_LS")
	)
	(segment
		(start 123.393708 -77.950822)
		(end 123.393708 -76.683108)
		(width 0.127)
		(layer "In2.Cu")
		(net "I2C_CLIP_SCL7_LS")
	)
	(segment
		(start 124.393706 -78.836774)
		(end 124.163328 -78.606396)
		(width 0.127)
		(layer "In2.Cu")
		(net "I2C_CLIP_SCL7_LS")
	)
	(segment
		(start 128.590548 -88.519)
		(end 128.590548 -87.404448)
		(width 0.127)
		(layer "In2.Cu")
		(net "I2C_CLIP_SCL7_LS")
	)
	(segment
		(start 122.555 -75.7936)
		(end 122.3264 -75.565)
		(width 0.127)
		(layer "In2.Cu")
		(net "I2C_CLIP_SCL7_LS")
	)
	(segment
		(start 124.049282 -78.606396)
		(end 123.393708 -77.950822)
		(width 0.127)
		(layer "In2.Cu")
		(net "I2C_CLIP_SCL7_LS")
	)
	(segment
		(start 128.590548 -87.404448)
		(end 127.8255 -86.6394)
		(width 0.127)
		(layer "In2.Cu")
		(net "I2C_CLIP_SCL7_LS")
	)
	(segment
		(start 127.8255 -86.6394)
		(end 127.8255 -85.392768)
		(width 0.127)
		(layer "In2.Cu")
		(net "I2C_CLIP_SCL7_LS")
	)
	(segment
		(start 122.555 -76.3524)
		(end 122.555 -75.7936)
		(width 0.127)
		(layer "In2.Cu")
		(net "I2C_CLIP_SCL7_LS")
	)
	(segment
		(start 123.393708 -76.683108)
		(end 123.19 -76.4794)
		(width 0.127)
		(layer "In2.Cu")
		(net "I2C_CLIP_SCL7_LS")
	)
	(segment
		(start 124.163328 -78.606396)
		(end 124.049282 -78.606396)
		(width 0.127)
		(layer "In2.Cu")
		(net "I2C_CLIP_SCL7_LS")
	)
	(segment
		(start 124.9172 -81.534)
		(end 124.393706 -81.010506)
		(width 0.127)
		(layer "In2.Cu")
		(net "I2C_CLIP_SCL7_LS")
	)
	(segment
		(start 123.19 -76.4794)
		(end 122.682 -76.4794)
		(width 0.127)
		(layer "In2.Cu")
		(net "I2C_CLIP_SCL7_LS")
	)
	(segment
		(start 121.960894 -74.000106)
		(end 122.00001 -74.000106)
		(width 0.127)
		(layer "In2.Cu")
		(net "I2C_CLIP_SCL7_LS")
	)
	(segment
		(start 121.412 -75.2348)
		(end 121.412 -74.549)
		(width 0.127)
		(layer "In2.Cu")
		(net "I2C_CLIP_SCL7_LS")
	)
	(segment
		(start 121.412 -74.549)
		(end 121.960894 -74.000106)
		(width 0.127)
		(layer "In2.Cu")
		(net "I2C_CLIP_SCL7_LS")
	)
	(segment
		(start 125.857 -82.4738)
		(end 125.857 -82.169)
		(width 0.127)
		(layer "In2.Cu")
		(net "I2C_CLIP_SCL7_LS")
	)
	(segment
		(start 126.0348 -93.247718)
		(end 122.75058 -96.531938)
		(width 0.127)
		(layer "In5.Cu")
		(net "I2C_CLIP_SCL7_LS")
	)
	(segment
		(start 55.9816 -86.888828)
		(end 55.9816 -83.4644)
		(width 0.127)
		(layer "In5.Cu")
		(net "I2C_CLIP_SCL7_LS")
	)
	(segment
		(start 58.852308 -89.759536)
		(end 55.9816 -86.888828)
		(width 0.127)
		(layer "In5.Cu")
		(net "I2C_CLIP_SCL7_LS")
	)
	(segment
		(start 77.147674 -100.45319)
		(end 66.45402 -89.759536)
		(width 0.127)
		(layer "In5.Cu")
		(net "I2C_CLIP_SCL7_LS")
	)
	(segment
		(start 66.45402 -89.759536)
		(end 58.852308 -89.759536)
		(width 0.127)
		(layer "In5.Cu")
		(net "I2C_CLIP_SCL7_LS")
	)
	(segment
		(start 128.617472 -88.827864)
		(end 127.1397 -90.305636)
		(width 0.127)
		(layer "In5.Cu")
		(net "I2C_CLIP_SCL7_LS")
	)
	(segment
		(start 126.551182 -91.708986)
		(end 126.238 -92.022168)
		(width 0.127)
		(layer "In5.Cu")
		(net "I2C_CLIP_SCL7_LS")
	)
	(segment
		(start 128.617472 -88.545924)
		(end 128.617472 -88.827864)
		(width 0.127)
		(layer "In5.Cu")
		(net "I2C_CLIP_SCL7_LS")
	)
	(segment
		(start 126.0348 -92.836238)
		(end 126.0348 -93.247718)
		(width 0.127)
		(layer "In5.Cu")
		(net "I2C_CLIP_SCL7_LS")
	)
	(segment
		(start 126.864618 -91.708986)
		(end 126.551182 -91.708986)
		(width 0.127)
		(layer "In5.Cu")
		(net "I2C_CLIP_SCL7_LS")
	)
	(segment
		(start 128.590548 -88.519)
		(end 128.617472 -88.545924)
		(width 0.127)
		(layer "In5.Cu")
		(net "I2C_CLIP_SCL7_LS")
	)
	(segment
		(start 122.75058 -96.531938)
		(end 102.188518 -96.531938)
		(width 0.127)
		(layer "In5.Cu")
		(net "I2C_CLIP_SCL7_LS")
	)
	(segment
		(start 127.1397 -90.305636)
		(end 127.1397 -91.433904)
		(width 0.127)
		(layer "In5.Cu")
		(net "I2C_CLIP_SCL7_LS")
	)
	(segment
		(start 102.188518 -96.531938)
		(end 98.267266 -100.45319)
		(width 0.127)
		(layer "In5.Cu")
		(net "I2C_CLIP_SCL7_LS")
	)
	(segment
		(start 126.238 -92.022168)
		(end 126.238 -92.633038)
		(width 0.127)
		(layer "In5.Cu")
		(net "I2C_CLIP_SCL7_LS")
	)
	(segment
		(start 98.267266 -100.45319)
		(end 77.147674 -100.45319)
		(width 0.127)
		(layer "In5.Cu")
		(net "I2C_CLIP_SCL7_LS")
	)
	(segment
		(start 126.238 -92.633038)
		(end 126.0348 -92.836238)
		(width 0.127)
		(layer "In5.Cu")
		(net "I2C_CLIP_SCL7_LS")
	)
	(segment
		(start 55.9816 -83.4644)
		(end 55.4736 -82.9564)
		(width 0.127)
		(layer "In5.Cu")
		(net "I2C_CLIP_SCL7_LS")
	)
	(segment
		(start 127.1397 -91.433904)
		(end 126.864618 -91.708986)
		(width 0.127)
		(layer "In5.Cu")
		(net "I2C_CLIP_SCL7_LS")
	)
	(segment
		(start 48.768 -73.66)
		(end 48.768 -76.708)
		(width 0.127)
		(layer "F.Cu")
		(net "I2C_CLIP_SCL7")
	)
	(segment
		(start 53.72608 -75.8698)
		(end 53.72608 -76.65212)
		(width 0.127)
		(layer "F.Cu")
		(net "I2C_CLIP_SCL7")
	)
	(segment
		(start 51.7144 -70.7136)
		(end 49.276 -73.152)
		(width 0.127)
		(layer "F.Cu")
		(net "I2C_CLIP_SCL7")
	)
	(segment
		(start 51.0413 -77.216)
		(end 51.7525 -77.9272)
		(width 0.127)
		(layer "F.Cu")
		(net "I2C_CLIP_SCL7")
	)
	(segment
		(start 52.6161 -77.0636)
		(end 51.7525 -77.9272)
		(width 0.127)
		(layer "F.Cu")
		(net "I2C_CLIP_SCL7")
	)
	(segment
		(start 52.705 -70.7136)
		(end 51.7144 -70.7136)
		(width 0.127)
		(layer "F.Cu")
		(net "I2C_CLIP_SCL7")
	)
	(segment
		(start 48.768 -76.708)
		(end 49.276 -77.216)
		(width 0.127)
		(layer "F.Cu")
		(net "I2C_CLIP_SCL7")
	)
	(segment
		(start 49.276 -77.216)
		(end 51.0413 -77.216)
		(width 0.127)
		(layer "F.Cu")
		(net "I2C_CLIP_SCL7")
	)
	(segment
		(start 53.3146 -77.0636)
		(end 52.6161 -77.0636)
		(width 0.127)
		(layer "F.Cu")
		(net "I2C_CLIP_SCL7")
	)
	(segment
		(start 53.72608 -76.65212)
		(end 53.3146 -77.0636)
		(width 0.127)
		(layer "F.Cu")
		(net "I2C_CLIP_SCL7")
	)
	(segment
		(start 49.276 -73.152)
		(end 48.768 -73.66)
		(width 0.127)
		(layer "F.Cu")
		(net "I2C_CLIP_SCL7")
	)
	(via
		(at 49.276 -73.152)
		(size 0.6604)
		(drill 0.3302)
		(layers "F.Cu" "B.Cu")
		(net "I2C_CLIP_SCL7")
	)
	(via
		(at 52.705 -70.7136)
		(size 0.508)
		(drill 0.254)
		(layers "F.Cu" "B.Cu")
		(net "I2C_CLIP_SCL7")
	)
	(segment
		(start 65.76441 -64.350392)
		(end 63.195454 -66.919348)
		(width 0.127)
		(layer "In2.Cu")
		(net "I2C_CLIP_SCL7")
	)
	(segment
		(start 77.08646 -34.775648)
		(end 72.240394 -39.621714)
		(width 0.127)
		(layer "In2.Cu")
		(net "I2C_CLIP_SCL7")
	)
	(segment
		(start 55.698136 -66.919348)
		(end 52.705 -69.912484)
		(width 0.127)
		(layer "In2.Cu")
		(net "I2C_CLIP_SCL7")
	)
	(segment
		(start 52.705 -69.912484)
		(end 52.705 -70.7136)
		(width 0.127)
		(layer "In2.Cu")
		(net "I2C_CLIP_SCL7")
	)
	(segment
		(start 72.240394 -51.279806)
		(end 71.089774 -52.430426)
		(width 0.127)
		(layer "In2.Cu")
		(net "I2C_CLIP_SCL7")
	)
	(segment
		(start 105.800144 -6.20014)
		(end 106.944922 -7.344918)
		(width 0.127)
		(layer "In2.Cu")
		(net "I2C_CLIP_SCL7")
	)
	(segment
		(start 72.240394 -39.621714)
		(end 72.240394 -51.279806)
		(width 0.127)
		(layer "In2.Cu")
		(net "I2C_CLIP_SCL7")
	)
	(segment
		(start 80.421988 -28.073604)
		(end 77.08646 -31.409132)
		(width 0.127)
		(layer "In2.Cu")
		(net "I2C_CLIP_SCL7")
	)
	(segment
		(start 94.056962 -25.57018)
		(end 82.186526 -25.57018)
		(width 0.127)
		(layer "In2.Cu")
		(net "I2C_CLIP_SCL7")
	)
	(segment
		(start 71.089774 -52.430426)
		(end 71.089774 -60.857892)
		(width 0.127)
		(layer "In2.Cu")
		(net "I2C_CLIP_SCL7")
	)
	(segment
		(start 106.944922 -7.344918)
		(end 106.944922 -12.68222)
		(width 0.127)
		(layer "In2.Cu")
		(net "I2C_CLIP_SCL7")
	)
	(segment
		(start 63.195454 -66.919348)
		(end 55.698136 -66.919348)
		(width 0.127)
		(layer "In2.Cu")
		(net "I2C_CLIP_SCL7")
	)
	(segment
		(start 82.186526 -25.57018)
		(end 80.421988 -27.334718)
		(width 0.127)
		(layer "In2.Cu")
		(net "I2C_CLIP_SCL7")
	)
	(segment
		(start 67.597274 -64.350392)
		(end 65.76441 -64.350392)
		(width 0.127)
		(layer "In2.Cu")
		(net "I2C_CLIP_SCL7")
	)
	(segment
		(start 106.944922 -12.68222)
		(end 94.056962 -25.57018)
		(width 0.127)
		(layer "In2.Cu")
		(net "I2C_CLIP_SCL7")
	)
	(segment
		(start 77.08646 -31.409132)
		(end 77.08646 -34.775648)
		(width 0.127)
		(layer "In2.Cu")
		(net "I2C_CLIP_SCL7")
	)
	(segment
		(start 71.089774 -60.857892)
		(end 67.597274 -64.350392)
		(width 0.127)
		(layer "In2.Cu")
		(net "I2C_CLIP_SCL7")
	)
	(segment
		(start 80.421988 -27.334718)
		(end 80.421988 -28.073604)
		(width 0.127)
		(layer "In2.Cu")
		(net "I2C_CLIP_SCL7")
	)
	(segment
		(start 57.431686 -19.276314)
		(end 57.431686 -20.675346)
		(width 0.127)
		(layer "F.Cu")
		(net "SCC_STBY_PWR_EN")
	)
	(segment
		(start 58.865008 -15.326614)
		(end 58.4835 -15.708122)
		(width 0.127)
		(layer "F.Cu")
		(net "SCC_STBY_PWR_EN")
	)
	(segment
		(start 57.8485 -18.542)
		(end 57.8485 -17.907)
		(width 0.127)
		(layer "F.Cu")
		(net "SCC_STBY_PWR_EN")
	)
	(segment
		(start 57.8485 -17.907)
		(end 58.4835 -17.272)
		(width 0.127)
		(layer "F.Cu")
		(net "SCC_STBY_PWR_EN")
	)
	(segment
		(start 57.8485 -18.542)
		(end 57.8485 -18.8595)
		(width 0.127)
		(layer "F.Cu")
		(net "SCC_STBY_PWR_EN")
	)
	(segment
		(start 59.612022 -14.5796)
		(end 59.612022 -14.579854)
		(width 0.127)
		(layer "F.Cu")
		(net "SCC_STBY_PWR_EN")
	)
	(segment
		(start 57.8485 -18.8595)
		(end 57.431686 -19.276314)
		(width 0.127)
		(layer "F.Cu")
		(net "SCC_STBY_PWR_EN")
	)
	(segment
		(start 59.612022 -14.579854)
		(end 58.865262 -15.326614)
		(width 0.127)
		(layer "F.Cu")
		(net "SCC_STBY_PWR_EN")
	)
	(segment
		(start 58.865262 -15.326614)
		(end 58.865008 -15.326614)
		(width 0.127)
		(layer "F.Cu")
		(net "SCC_STBY_PWR_EN")
	)
	(segment
		(start 58.4835 -15.708122)
		(end 58.4835 -17.272)
		(width 0.127)
		(layer "F.Cu")
		(net "SCC_STBY_PWR_EN")
	)
	(via
		(at 58.865262 -15.326614)
		(size 0.6604)
		(drill 0.3302)
		(layers "F.Cu" "B.Cu")
		(net "SCC_STBY_PWR_EN")
	)
	(via
		(at 59.612022 -14.5796)
		(size 0.508)
		(drill 0.254)
		(layers "F.Cu" "B.Cu")
		(net "SCC_STBY_PWR_EN")
	)
	(segment
		(start 87.141304 -8.259064)
		(end 87.80018 -7.600188)
		(width 0.127)
		(layer "In2.Cu")
		(net "SCC_STBY_PWR_EN")
	)
	(segment
		(start 79.995522 -12.767818)
		(end 82.162904 -14.9352)
		(width 0.127)
		(layer "In2.Cu")
		(net "SCC_STBY_PWR_EN")
	)
	(segment
		(start 87.141304 -13.885672)
		(end 87.141304 -8.259064)
		(width 0.127)
		(layer "In2.Cu")
		(net "SCC_STBY_PWR_EN")
	)
	(segment
		(start 59.612022 -14.5796)
		(end 61.423804 -12.767818)
		(width 0.127)
		(layer "In2.Cu")
		(net "SCC_STBY_PWR_EN")
	)
	(segment
		(start 82.162904 -14.9352)
		(end 86.091776 -14.9352)
		(width 0.127)
		(layer "In2.Cu")
		(net "SCC_STBY_PWR_EN")
	)
	(segment
		(start 61.423804 -12.767818)
		(end 79.995522 -12.767818)
		(width 0.127)
		(layer "In2.Cu")
		(net "SCC_STBY_PWR_EN")
	)
	(segment
		(start 86.091776 -14.9352)
		(end 87.141304 -13.885672)
		(width 0.127)
		(layer "In2.Cu")
		(net "SCC_STBY_PWR_EN")
	)
	(segment
		(start 148.955252 -55.02402)
		(end 148.805138 -55.103522)
		(width 0.12446)
		(layer "F.Cu")
		(net "PHY_SCC_TO_IOC_C_47_DP")
	)
	(segment
		(start 165.800024 -38.000178)
		(end 165.800024 -37.999924)
		(width 0.12446)
		(layer "F.Cu")
		(net "PHY_SCC_TO_IOC_C_47_DP")
	)
	(segment
		(start 149.371812 -55.109618)
		(end 149.367748 -55.108856)
		(width 0.12446)
		(layer "F.Cu")
		(net "PHY_SCC_TO_IOC_C_47_DP")
	)
	(segment
		(start 149.367748 -55.108856)
		(end 148.955252 -55.02402)
		(width 0.12446)
		(layer "F.Cu")
		(net "PHY_SCC_TO_IOC_C_47_DP")
	)
	(segment
		(start 148.805138 -55.103522)
		(end 148.588476 -55.055516)
		(width 0.12446)
		(layer "F.Cu")
		(net "PHY_SCC_TO_IOC_C_47_DP")
	)
	(segment
		(start 166.19982 -38.399974)
		(end 165.800024 -38.000178)
		(width 0.12446)
		(layer "F.Cu")
		(net "PHY_SCC_TO_IOC_C_47_DP")
	)
	(segment
		(start 149.402546 -55.501286)
		(end 149.458172 -55.25008)
		(width 0.12446)
		(layer "F.Cu")
		(net "PHY_SCC_TO_IOC_C_47_DP")
	)
	(via
		(at 166.19982 -38.399974)
		(size 0.508)
		(drill 0.254)
		(layers "F.Cu" "B.Cu")
		(net "PHY_SCC_TO_IOC_C_47_DP")
	)
	(arc
		(start 149.458172 -55.25008)
		(mid 149.445403 -55.161123)
		(end 149.371812 -55.109618)
		(width 0.12446)
		(layer "F.Cu")
		(net "PHY_SCC_TO_IOC_C_47_DP")
	)
	(segment
		(start 166.19982 -38.399974)
		(end 166.19982 -38.280848)
		(width 0.1016)
		(layer "In2.Cu")
		(net "PHY_SCC_TO_IOC_C_47_DP")
	)
	(segment
		(start 165.754812 -38.158166)
		(end 165.535102 -37.938456)
		(width 0.1016)
		(layer "In2.Cu")
		(net "PHY_SCC_TO_IOC_C_47_DP")
	)
	(segment
		(start 157.620208 -41.68394)
		(end 153.778966 -47.601886)
		(width 0.1016)
		(layer "In2.Cu")
		(net "PHY_SCC_TO_IOC_C_47_DP")
	)
	(segment
		(start 163.934394 -37.984938)
		(end 163.017708 -38.179502)
		(width 0.1016)
		(layer "In2.Cu")
		(net "PHY_SCC_TO_IOC_C_47_DP")
	)
	(segment
		(start 153.778966 -47.601886)
		(end 152.641046 -52.951126)
		(width 0.1016)
		(layer "In2.Cu")
		(net "PHY_SCC_TO_IOC_C_47_DP")
	)
	(segment
		(start 149.461728 -55.22214)
		(end 149.402546 -55.501286)
		(width 0.1016)
		(layer "In2.Cu")
		(net "PHY_SCC_TO_IOC_C_47_DP")
	)
	(segment
		(start 151.580088 -54.583838)
		(end 150.206456 -55.243476)
		(width 0.1016)
		(layer "In2.Cu")
		(net "PHY_SCC_TO_IOC_C_47_DP")
	)
	(segment
		(start 149.53107 -55.1307)
		(end 149.519894 -55.138066)
		(width 0.1016)
		(layer "In2.Cu")
		(net "PHY_SCC_TO_IOC_C_47_DP")
	)
	(segment
		(start 166.077392 -38.158166)
		(end 165.754812 -38.158166)
		(width 0.1016)
		(layer "In2.Cu")
		(net "PHY_SCC_TO_IOC_C_47_DP")
	)
	(segment
		(start 165.535102 -37.938456)
		(end 164.151818 -37.938456)
		(width 0.1016)
		(layer "In2.Cu")
		(net "PHY_SCC_TO_IOC_C_47_DP")
	)
	(segment
		(start 150.206456 -55.243476)
		(end 149.607778 -55.116476)
		(width 0.1016)
		(layer "In2.Cu")
		(net "PHY_SCC_TO_IOC_C_47_DP")
	)
	(segment
		(start 164.151818 -37.938456)
		(end 163.934394 -37.984938)
		(width 0.1016)
		(layer "In2.Cu")
		(net "PHY_SCC_TO_IOC_C_47_DP")
	)
	(segment
		(start 152.641046 -52.951126)
		(end 151.580088 -54.583838)
		(width 0.1016)
		(layer "In2.Cu")
		(net "PHY_SCC_TO_IOC_C_47_DP")
	)
	(segment
		(start 163.017708 -38.179502)
		(end 157.620208 -41.68394)
		(width 0.1016)
		(layer "In2.Cu")
		(net "PHY_SCC_TO_IOC_C_47_DP")
	)
	(arc
		(start 166.19982 -38.280848)
		(mid 166.190447 -38.233817)
		(end 166.163752 -38.19398)
		(width 0.1016)
		(layer "In2.Cu")
		(net "PHY_SCC_TO_IOC_C_47_DP")
	)
	(arc
		(start 149.519894 -55.138066)
		(mid 149.48244 -55.17432)
		(end 149.461728 -55.22214)
		(width 0.1016)
		(layer "In2.Cu")
		(net "PHY_SCC_TO_IOC_C_47_DP")
	)
	(arc
		(start 149.607778 -55.116476)
		(mid 149.567992 -55.1159)
		(end 149.53107 -55.1307)
		(width 0.1016)
		(layer "In2.Cu")
		(net "PHY_SCC_TO_IOC_C_47_DP")
	)
	(arc
		(start 166.163752 -38.19398)
		(mid 166.124144 -38.167451)
		(end 166.077392 -38.158166)
		(width 0.1016)
		(layer "In2.Cu")
		(net "PHY_SCC_TO_IOC_C_47_DP")
	)
	(segment
		(start 166.59987 -37.999924)
		(end 166.19982 -37.599874)
		(width 0.12446)
		(layer "F.Cu")
		(net "PHY_SCC_TO_IOC_C_47_DN")
	)
	(segment
		(start 149.64029 -54.383178)
		(end 149.586188 -54.634638)
		(width 0.12446)
		(layer "F.Cu")
		(net "PHY_SCC_TO_IOC_C_47_DN")
	)
	(segment
		(start 148.92782 -54.526942)
		(end 148.710142 -54.48427)
		(width 0.12446)
		(layer "F.Cu")
		(net "PHY_SCC_TO_IOC_C_47_DN")
	)
	(segment
		(start 149.000718 -54.618382)
		(end 148.92782 -54.526942)
		(width 0.12446)
		(layer "F.Cu")
		(net "PHY_SCC_TO_IOC_C_47_DN")
	)
	(segment
		(start 149.413214 -54.703218)
		(end 149.000718 -54.618382)
		(width 0.12446)
		(layer "F.Cu")
		(net "PHY_SCC_TO_IOC_C_47_DN")
	)
	(via
		(at 166.19982 -37.599874)
		(size 0.508)
		(drill 0.254)
		(layers "F.Cu" "B.Cu")
		(net "PHY_SCC_TO_IOC_C_47_DN")
	)
	(arc
		(start 149.586188 -54.634638)
		(mid 149.509944 -54.694734)
		(end 149.413214 -54.703218)
		(width 0.12446)
		(layer "F.Cu")
		(net "PHY_SCC_TO_IOC_C_47_DN")
	)
	(segment
		(start 163.521136 -37.76091)
		(end 162.89909 -37.89299)
		(width 0.1016)
		(layer "In2.Cu")
		(net "PHY_SCC_TO_IOC_C_47_DN")
	)
	(segment
		(start 149.581108 -54.66207)
		(end 149.64029 -54.383178)
		(width 0.1016)
		(layer "In2.Cu")
		(net "PHY_SCC_TO_IOC_C_47_DN")
	)
	(segment
		(start 162.89909 -37.89299)
		(end 157.399736 -41.463468)
		(width 0.1016)
		(layer "In2.Cu")
		(net "PHY_SCC_TO_IOC_C_47_DN")
	)
	(segment
		(start 153.492454 -47.483268)
		(end 152.560782 -51.863244)
		(width 0.1016)
		(layer "In2.Cu")
		(net "PHY_SCC_TO_IOC_C_47_DN")
	)
	(segment
		(start 166.111936 -37.853366)
		(end 165.881304 -37.853366)
		(width 0.1016)
		(layer "In2.Cu")
		(net "PHY_SCC_TO_IOC_C_47_DN")
	)
	(segment
		(start 152.560782 -51.863244)
		(end 152.334722 -52.010056)
		(width 0.1016)
		(layer "In2.Cu")
		(net "PHY_SCC_TO_IOC_C_47_DN")
	)
	(segment
		(start 157.399736 -41.463468)
		(end 153.492454 -47.483268)
		(width 0.1016)
		(layer "In2.Cu")
		(net "PHY_SCC_TO_IOC_C_47_DN")
	)
	(segment
		(start 150.168102 -54.92369)
		(end 149.679406 -54.819804)
		(width 0.1016)
		(layer "In2.Cu")
		(net "PHY_SCC_TO_IOC_C_47_DN")
	)
	(segment
		(start 152.418034 -52.534058)
		(end 152.354534 -52.832254)
		(width 0.1016)
		(layer "In2.Cu")
		(net "PHY_SCC_TO_IOC_C_47_DN")
	)
	(segment
		(start 165.661594 -37.633656)
		(end 164.11956 -37.633656)
		(width 0.1016)
		(layer "In2.Cu")
		(net "PHY_SCC_TO_IOC_C_47_DN")
	)
	(segment
		(start 166.19982 -37.599874)
		(end 166.19982 -37.752274)
		(width 0.1016)
		(layer "In2.Cu")
		(net "PHY_SCC_TO_IOC_C_47_DN")
	)
	(segment
		(start 152.271222 -52.308252)
		(end 152.418034 -52.534058)
		(width 0.1016)
		(layer "In2.Cu")
		(net "PHY_SCC_TO_IOC_C_47_DN")
	)
	(segment
		(start 165.881304 -37.853366)
		(end 165.661594 -37.633656)
		(width 0.1016)
		(layer "In2.Cu")
		(net "PHY_SCC_TO_IOC_C_47_DN")
	)
	(segment
		(start 151.371046 -54.346094)
		(end 150.168102 -54.92369)
		(width 0.1016)
		(layer "In2.Cu")
		(net "PHY_SCC_TO_IOC_C_47_DN")
	)
	(segment
		(start 152.334722 -52.010056)
		(end 152.271222 -52.308252)
		(width 0.1016)
		(layer "In2.Cu")
		(net "PHY_SCC_TO_IOC_C_47_DN")
	)
	(segment
		(start 164.11956 -37.633656)
		(end 163.521136 -37.76091)
		(width 0.1016)
		(layer "In2.Cu")
		(net "PHY_SCC_TO_IOC_C_47_DN")
	)
	(segment
		(start 152.354534 -52.832254)
		(end 151.371046 -54.346094)
		(width 0.1016)
		(layer "In2.Cu")
		(net "PHY_SCC_TO_IOC_C_47_DN")
	)
	(arc
		(start 166.19982 -37.752274)
		(mid 166.178955 -37.822917)
		(end 166.111936 -37.853366)
		(width 0.1016)
		(layer "In2.Cu")
		(net "PHY_SCC_TO_IOC_C_47_DN")
	)
	(arc
		(start 149.679406 -54.819804)
		(mid 149.634329 -54.798973)
		(end 149.599904 -54.763162)
		(width 0.1016)
		(layer "In2.Cu")
		(net "PHY_SCC_TO_IOC_C_47_DN")
	)
	(arc
		(start 149.599904 -54.763162)
		(mid 149.580467 -54.714487)
		(end 149.581108 -54.66207)
		(width 0.1016)
		(layer "In2.Cu")
		(net "PHY_SCC_TO_IOC_C_47_DN")
	)
	(segment
		(start 147.59051 -51.097434)
		(end 147.804124 -51.14544)
		(width 0.12446)
		(layer "F.Cu")
		(net "PHY_SCC_TO_IOC_C_46_DP")
	)
	(segment
		(start 165.79977 -37.199824)
		(end 165.800024 -37.199824)
		(width 0.12446)
		(layer "F.Cu")
		(net "PHY_SCC_TO_IOC_C_46_DP")
	)
	(segment
		(start 147.955508 -51.06543)
		(end 148.319998 -51.14036)
		(width 0.12446)
		(layer "F.Cu")
		(net "PHY_SCC_TO_IOC_C_46_DP")
	)
	(segment
		(start 148.319998 -51.14036)
		(end 148.324062 -51.141122)
		(width 0.12446)
		(layer "F.Cu")
		(net "PHY_SCC_TO_IOC_C_46_DP")
	)
	(segment
		(start 147.804124 -51.14544)
		(end 147.955508 -51.06543)
		(width 0.12446)
		(layer "F.Cu")
		(net "PHY_SCC_TO_IOC_C_46_DP")
	)
	(segment
		(start 165.399974 -36.800028)
		(end 165.79977 -37.199824)
		(width 0.12446)
		(layer "F.Cu")
		(net "PHY_SCC_TO_IOC_C_46_DP")
	)
	(segment
		(start 148.410422 -51.281584)
		(end 148.354796 -51.53279)
		(width 0.12446)
		(layer "F.Cu")
		(net "PHY_SCC_TO_IOC_C_46_DP")
	)
	(via
		(at 165.399974 -36.800028)
		(size 0.508)
		(drill 0.254)
		(layers "F.Cu" "B.Cu")
		(net "PHY_SCC_TO_IOC_C_46_DP")
	)
	(arc
		(start 148.324062 -51.141122)
		(mid 148.397558 -51.192685)
		(end 148.410422 -51.281584)
		(width 0.12446)
		(layer "F.Cu")
		(net "PHY_SCC_TO_IOC_C_46_DP")
	)
	(segment
		(start 156.005784 -42.166286)
		(end 155.949904 -41.902634)
		(width 0.1016)
		(layer "In2.Cu")
		(net "PHY_SCC_TO_IOC_C_46_DP")
	)
	(segment
		(start 155.410154 -42.733468)
		(end 155.57627 -42.477944)
		(width 0.1016)
		(layer "In2.Cu")
		(net "PHY_SCC_TO_IOC_C_46_DP")
	)
	(segment
		(start 164.089334 -36.800028)
		(end 165.399974 -36.800028)
		(width 0.1016)
		(layer "In2.Cu")
		(net "PHY_SCC_TO_IOC_C_46_DP")
	)
	(segment
		(start 155.839668 -42.42181)
		(end 156.005784 -42.166286)
		(width 0.1016)
		(layer "In2.Cu")
		(net "PHY_SCC_TO_IOC_C_46_DP")
	)
	(segment
		(start 148.354796 -51.53279)
		(end 148.413978 -51.253644)
		(width 0.1016)
		(layer "In2.Cu")
		(net "PHY_SCC_TO_IOC_C_46_DP")
	)
	(segment
		(start 161.901124 -37.627814)
		(end 161.957258 -37.364416)
		(width 0.1016)
		(layer "In2.Cu")
		(net "PHY_SCC_TO_IOC_C_46_DP")
	)
	(segment
		(start 148.560028 -51.14798)
		(end 148.79701 -51.198272)
		(width 0.1016)
		(layer "In2.Cu")
		(net "PHY_SCC_TO_IOC_C_46_DP")
	)
	(segment
		(start 148.79701 -51.198272)
		(end 150.772368 -50.939192)
		(width 0.1016)
		(layer "In2.Cu")
		(net "PHY_SCC_TO_IOC_C_46_DP")
	)
	(segment
		(start 161.07029 -38.16731)
		(end 161.126424 -37.903912)
		(width 0.1016)
		(layer "In2.Cu")
		(net "PHY_SCC_TO_IOC_C_46_DP")
	)
	(segment
		(start 160.814766 -38.333426)
		(end 161.07029 -38.16731)
		(width 0.1016)
		(layer "In2.Cu")
		(net "PHY_SCC_TO_IOC_C_46_DP")
	)
	(segment
		(start 162.212782 -37.1983)
		(end 164.089334 -36.800028)
		(width 0.1016)
		(layer "In2.Cu")
		(net "PHY_SCC_TO_IOC_C_46_DP")
	)
	(segment
		(start 156.665676 -40.800528)
		(end 160.551114 -38.277292)
		(width 0.1016)
		(layer "In2.Cu")
		(net "PHY_SCC_TO_IOC_C_46_DP")
	)
	(segment
		(start 161.381948 -37.737796)
		(end 161.6456 -37.79393)
		(width 0.1016)
		(layer "In2.Cu")
		(net "PHY_SCC_TO_IOC_C_46_DP")
	)
	(segment
		(start 161.6456 -37.79393)
		(end 161.901124 -37.627814)
		(width 0.1016)
		(layer "In2.Cu")
		(net "PHY_SCC_TO_IOC_C_46_DP")
	)
	(segment
		(start 161.126424 -37.903912)
		(end 161.381948 -37.737796)
		(width 0.1016)
		(layer "In2.Cu")
		(net "PHY_SCC_TO_IOC_C_46_DP")
	)
	(segment
		(start 155.300172 -43.252644)
		(end 155.466288 -42.996866)
		(width 0.1016)
		(layer "In2.Cu")
		(net "PHY_SCC_TO_IOC_C_46_DP")
	)
	(segment
		(start 156.115766 -41.64711)
		(end 156.379418 -41.590976)
		(width 0.1016)
		(layer "In2.Cu")
		(net "PHY_SCC_TO_IOC_C_46_DP")
	)
	(segment
		(start 148.472144 -51.16957)
		(end 148.48332 -51.162204)
		(width 0.1016)
		(layer "In2.Cu")
		(net "PHY_SCC_TO_IOC_C_46_DP")
	)
	(segment
		(start 151.856694 -48.204628)
		(end 155.036774 -43.308524)
		(width 0.1016)
		(layer "In2.Cu")
		(net "PHY_SCC_TO_IOC_C_46_DP")
	)
	(segment
		(start 161.957258 -37.364416)
		(end 162.212782 -37.1983)
		(width 0.1016)
		(layer "In2.Cu")
		(net "PHY_SCC_TO_IOC_C_46_DP")
	)
	(segment
		(start 155.57627 -42.477944)
		(end 155.839668 -42.42181)
		(width 0.1016)
		(layer "In2.Cu")
		(net "PHY_SCC_TO_IOC_C_46_DP")
	)
	(segment
		(start 150.772368 -50.939192)
		(end 151.520398 -49.78781)
		(width 0.1016)
		(layer "In2.Cu")
		(net "PHY_SCC_TO_IOC_C_46_DP")
	)
	(segment
		(start 156.54528 -41.335452)
		(end 156.4894 -41.072054)
		(width 0.1016)
		(layer "In2.Cu")
		(net "PHY_SCC_TO_IOC_C_46_DP")
	)
	(segment
		(start 155.949904 -41.902634)
		(end 156.115766 -41.64711)
		(width 0.1016)
		(layer "In2.Cu")
		(net "PHY_SCC_TO_IOC_C_46_DP")
	)
	(segment
		(start 155.466288 -42.996866)
		(end 155.410154 -42.733468)
		(width 0.1016)
		(layer "In2.Cu")
		(net "PHY_SCC_TO_IOC_C_46_DP")
	)
	(segment
		(start 156.379418 -41.590976)
		(end 156.54528 -41.335452)
		(width 0.1016)
		(layer "In2.Cu")
		(net "PHY_SCC_TO_IOC_C_46_DP")
	)
	(segment
		(start 160.551114 -38.277292)
		(end 160.814766 -38.333426)
		(width 0.1016)
		(layer "In2.Cu")
		(net "PHY_SCC_TO_IOC_C_46_DP")
	)
	(segment
		(start 156.4894 -41.072054)
		(end 156.665676 -40.800528)
		(width 0.1016)
		(layer "In2.Cu")
		(net "PHY_SCC_TO_IOC_C_46_DP")
	)
	(segment
		(start 151.520398 -49.78781)
		(end 151.856694 -48.204628)
		(width 0.1016)
		(layer "In2.Cu")
		(net "PHY_SCC_TO_IOC_C_46_DP")
	)
	(segment
		(start 155.036774 -43.308524)
		(end 155.300172 -43.252644)
		(width 0.1016)
		(layer "In2.Cu")
		(net "PHY_SCC_TO_IOC_C_46_DP")
	)
	(arc
		(start 148.48332 -51.162204)
		(mid 148.520253 -51.147462)
		(end 148.560028 -51.14798)
		(width 0.1016)
		(layer "In2.Cu")
		(net "PHY_SCC_TO_IOC_C_46_DP")
	)
	(arc
		(start 148.413978 -51.253644)
		(mid 148.434745 -51.205862)
		(end 148.472144 -51.16957)
		(width 0.1016)
		(layer "In2.Cu")
		(net "PHY_SCC_TO_IOC_C_46_DP")
	)
	(segment
		(start 148.037296 -50.667158)
		(end 148.365464 -50.734722)
		(width 0.12446)
		(layer "F.Cu")
		(net "PHY_SCC_TO_IOC_C_46_DN")
	)
	(segment
		(start 148.033232 -50.666396)
		(end 148.037296 -50.667158)
		(width 0.12446)
		(layer "F.Cu")
		(net "PHY_SCC_TO_IOC_C_46_DN")
	)
	(segment
		(start 166.19982 -36.800028)
		(end 166.599616 -37.199824)
		(width 0.12446)
		(layer "F.Cu")
		(net "PHY_SCC_TO_IOC_C_46_DN")
	)
	(segment
		(start 166.599616 -37.199824)
		(end 166.59987 -37.199824)
		(width 0.12446)
		(layer "F.Cu")
		(net "PHY_SCC_TO_IOC_C_46_DN")
	)
	(segment
		(start 148.538438 -50.666142)
		(end 148.59254 -50.414682)
		(width 0.12446)
		(layer "F.Cu")
		(net "PHY_SCC_TO_IOC_C_46_DN")
	)
	(segment
		(start 147.711922 -50.526188)
		(end 147.959064 -50.573686)
		(width 0.12446)
		(layer "F.Cu")
		(net "PHY_SCC_TO_IOC_C_46_DN")
	)
	(segment
		(start 147.959064 -50.573686)
		(end 148.033232 -50.666396)
		(width 0.12446)
		(layer "F.Cu")
		(net "PHY_SCC_TO_IOC_C_46_DN")
	)
	(via
		(at 166.19982 -36.800028)
		(size 0.508)
		(drill 0.254)
		(layers "F.Cu" "B.Cu")
		(net "PHY_SCC_TO_IOC_C_46_DN")
	)
	(arc
		(start 148.365464 -50.734722)
		(mid 148.46222 -50.726303)
		(end 148.538438 -50.666142)
		(width 0.12446)
		(layer "F.Cu")
		(net "PHY_SCC_TO_IOC_C_46_DN")
	)
	(segment
		(start 165.132512 -36.495228)
		(end 164.969698 -36.495228)
		(width 0.0889)
		(layer "In2.Cu")
		(net "PHY_SCC_TO_IOC_C_46_DN")
	)
	(segment
		(start 162.094164 -36.911788)
		(end 156.445204 -40.580056)
		(width 0.1016)
		(layer "In2.Cu")
		(net "PHY_SCC_TO_IOC_C_46_DN")
	)
	(segment
		(start 150.593298 -50.65522)
		(end 148.809202 -50.889154)
		(width 0.1016)
		(layer "In2.Cu")
		(net "PHY_SCC_TO_IOC_C_46_DN")
	)
	(segment
		(start 164.05733 -36.495228)
		(end 162.094164 -36.911788)
		(width 0.1016)
		(layer "In2.Cu")
		(net "PHY_SCC_TO_IOC_C_46_DN")
	)
	(segment
		(start 156.445204 -40.580056)
		(end 151.570182 -48.08601)
		(width 0.1016)
		(layer "In2.Cu")
		(net "PHY_SCC_TO_IOC_C_46_DN")
	)
	(segment
		(start 151.233886 -49.669192)
		(end 150.593298 -50.65522)
		(width 0.1016)
		(layer "In2.Cu")
		(net "PHY_SCC_TO_IOC_C_46_DN")
	)
	(segment
		(start 164.969698 -36.495228)
		(end 164.05733 -36.495228)
		(width 0.1016)
		(layer "In2.Cu")
		(net "PHY_SCC_TO_IOC_C_46_DN")
	)
	(segment
		(start 166.19982 -36.800028)
		(end 165.79977 -36.399978)
		(width 0.0889)
		(layer "In2.Cu")
		(net "PHY_SCC_TO_IOC_C_46_DN")
	)
	(segment
		(start 151.570182 -48.08601)
		(end 151.233886 -49.669192)
		(width 0.1016)
		(layer "In2.Cu")
		(net "PHY_SCC_TO_IOC_C_46_DN")
	)
	(segment
		(start 165.227762 -36.399978)
		(end 165.132512 -36.495228)
		(width 0.0889)
		(layer "In2.Cu")
		(net "PHY_SCC_TO_IOC_C_46_DN")
	)
	(segment
		(start 148.533358 -50.693574)
		(end 148.59254 -50.414682)
		(width 0.1016)
		(layer "In2.Cu")
		(net "PHY_SCC_TO_IOC_C_46_DN")
	)
	(segment
		(start 165.79977 -36.399978)
		(end 165.227762 -36.399978)
		(width 0.0889)
		(layer "In2.Cu")
		(net "PHY_SCC_TO_IOC_C_46_DN")
	)
	(segment
		(start 148.809202 -50.889154)
		(end 148.632926 -50.851816)
		(width 0.1016)
		(layer "In2.Cu")
		(net "PHY_SCC_TO_IOC_C_46_DN")
	)
	(arc
		(start 148.632926 -50.851816)
		(mid 148.587021 -50.831024)
		(end 148.552154 -50.794666)
		(width 0.1016)
		(layer "In2.Cu")
		(net "PHY_SCC_TO_IOC_C_46_DN")
	)
	(arc
		(start 148.552154 -50.794666)
		(mid 148.532717 -50.745991)
		(end 148.533358 -50.693574)
		(width 0.1016)
		(layer "In2.Cu")
		(net "PHY_SCC_TO_IOC_C_46_DN")
	)
	(segment
		(start 166.19982 -35.999928)
		(end 165.800024 -35.600132)
		(width 0.12446)
		(layer "F.Cu")
		(net "PHY_SCC_TO_IOC_C_45_DP")
	)
	(segment
		(start 146.736816 -47.146972)
		(end 146.907758 -47.096934)
		(width 0.12446)
		(layer "F.Cu")
		(net "PHY_SCC_TO_IOC_C_45_DP")
	)
	(segment
		(start 147.362672 -47.313088)
		(end 147.307046 -47.564294)
		(width 0.12446)
		(layer "F.Cu")
		(net "PHY_SCC_TO_IOC_C_45_DP")
	)
	(segment
		(start 146.523202 -47.098966)
		(end 146.736816 -47.146972)
		(width 0.12446)
		(layer "F.Cu")
		(net "PHY_SCC_TO_IOC_C_45_DP")
	)
	(segment
		(start 165.800024 -35.600132)
		(end 165.800024 -35.599878)
		(width 0.12446)
		(layer "F.Cu")
		(net "PHY_SCC_TO_IOC_C_45_DP")
	)
	(segment
		(start 146.907758 -47.096934)
		(end 147.272248 -47.171864)
		(width 0.12446)
		(layer "F.Cu")
		(net "PHY_SCC_TO_IOC_C_45_DP")
	)
	(segment
		(start 147.272248 -47.171864)
		(end 147.276312 -47.172626)
		(width 0.12446)
		(layer "F.Cu")
		(net "PHY_SCC_TO_IOC_C_45_DP")
	)
	(via
		(at 166.19982 -35.999928)
		(size 0.508)
		(drill 0.254)
		(layers "F.Cu" "B.Cu")
		(net "PHY_SCC_TO_IOC_C_45_DP")
	)
	(arc
		(start 147.276312 -47.172626)
		(mid 147.349808 -47.224189)
		(end 147.362672 -47.313088)
		(width 0.12446)
		(layer "F.Cu")
		(net "PHY_SCC_TO_IOC_C_45_DP")
	)
	(segment
		(start 161.771838 -35.784282)
		(end 163.08705 -35.504882)
		(width 0.1016)
		(layer "In2.Cu")
		(net "PHY_SCC_TO_IOC_C_45_DP")
	)
	(segment
		(start 166.19982 -35.880802)
		(end 166.19982 -35.999928)
		(width 0.1016)
		(layer "In2.Cu")
		(net "PHY_SCC_TO_IOC_C_45_DP")
	)
	(segment
		(start 150.890224 -47.17542)
		(end 151.710644 -46.643036)
		(width 0.1016)
		(layer "In2.Cu")
		(net "PHY_SCC_TO_IOC_C_45_DP")
	)
	(segment
		(start 163.08705 -35.504882)
		(end 165.502844 -35.504882)
		(width 0.1016)
		(layer "In2.Cu")
		(net "PHY_SCC_TO_IOC_C_45_DP")
	)
	(segment
		(start 156.56306 -39.169086)
		(end 161.771838 -35.784282)
		(width 0.1016)
		(layer "In2.Cu")
		(net "PHY_SCC_TO_IOC_C_45_DP")
	)
	(segment
		(start 147.424394 -47.201074)
		(end 147.43557 -47.193708)
		(width 0.1016)
		(layer "In2.Cu")
		(net "PHY_SCC_TO_IOC_C_45_DP")
	)
	(segment
		(start 165.756082 -35.75812)
		(end 166.077392 -35.75812)
		(width 0.1016)
		(layer "In2.Cu")
		(net "PHY_SCC_TO_IOC_C_45_DP")
	)
	(segment
		(start 147.524978 -47.182278)
		(end 149.281388 -47.555912)
		(width 0.1016)
		(layer "In2.Cu")
		(net "PHY_SCC_TO_IOC_C_45_DP")
	)
	(segment
		(start 149.281388 -47.555912)
		(end 150.890224 -47.17542)
		(width 0.1016)
		(layer "In2.Cu")
		(net "PHY_SCC_TO_IOC_C_45_DP")
	)
	(segment
		(start 151.710644 -46.643036)
		(end 156.56306 -39.169086)
		(width 0.1016)
		(layer "In2.Cu")
		(net "PHY_SCC_TO_IOC_C_45_DP")
	)
	(segment
		(start 165.502844 -35.504882)
		(end 165.756082 -35.75812)
		(width 0.1016)
		(layer "In2.Cu")
		(net "PHY_SCC_TO_IOC_C_45_DP")
	)
	(segment
		(start 147.307046 -47.564294)
		(end 147.366228 -47.285148)
		(width 0.1016)
		(layer "In2.Cu")
		(net "PHY_SCC_TO_IOC_C_45_DP")
	)
	(arc
		(start 147.43557 -47.193708)
		(mid 147.472503 -47.178966)
		(end 147.512278 -47.179484)
		(width 0.1016)
		(layer "In2.Cu")
		(net "PHY_SCC_TO_IOC_C_45_DP")
	)
	(arc
		(start 166.077392 -35.75812)
		(mid 166.124132 -35.767435)
		(end 166.163752 -35.793934)
		(width 0.1016)
		(layer "In2.Cu")
		(net "PHY_SCC_TO_IOC_C_45_DP")
	)
	(arc
		(start 147.366228 -47.285148)
		(mid 147.386995 -47.237366)
		(end 147.424394 -47.201074)
		(width 0.1016)
		(layer "In2.Cu")
		(net "PHY_SCC_TO_IOC_C_45_DP")
	)
	(arc
		(start 147.512278 -47.179484)
		(mid 147.518618 -47.180928)
		(end 147.524978 -47.182278)
		(width 0.1016)
		(layer "In2.Cu")
		(net "PHY_SCC_TO_IOC_C_45_DP")
	)
	(arc
		(start 166.163752 -35.793934)
		(mid 166.190436 -35.833775)
		(end 166.19982 -35.880802)
		(width 0.1016)
		(layer "In2.Cu")
		(net "PHY_SCC_TO_IOC_C_45_DP")
	)
	(segment
		(start 147.317714 -46.766226)
		(end 146.989546 -46.698662)
		(width 0.12446)
		(layer "F.Cu")
		(net "PHY_SCC_TO_IOC_C_45_DN")
	)
	(segment
		(start 147.54479 -46.446186)
		(end 147.490688 -46.697646)
		(width 0.12446)
		(layer "F.Cu")
		(net "PHY_SCC_TO_IOC_C_45_DN")
	)
	(segment
		(start 146.891756 -46.575218)
		(end 146.644614 -46.52772)
		(width 0.12446)
		(layer "F.Cu")
		(net "PHY_SCC_TO_IOC_C_45_DN")
	)
	(segment
		(start 166.59987 -35.599878)
		(end 166.19982 -35.199828)
		(width 0.12446)
		(layer "F.Cu")
		(net "PHY_SCC_TO_IOC_C_45_DN")
	)
	(segment
		(start 146.985482 -46.6979)
		(end 146.891756 -46.575218)
		(width 0.12446)
		(layer "F.Cu")
		(net "PHY_SCC_TO_IOC_C_45_DN")
	)
	(segment
		(start 146.989546 -46.698662)
		(end 146.985482 -46.6979)
		(width 0.12446)
		(layer "F.Cu")
		(net "PHY_SCC_TO_IOC_C_45_DN")
	)
	(via
		(at 166.19982 -35.199828)
		(size 0.508)
		(drill 0.254)
		(layers "F.Cu" "B.Cu")
		(net "PHY_SCC_TO_IOC_C_45_DN")
	)
	(arc
		(start 147.490688 -46.697646)
		(mid 147.414444 -46.757742)
		(end 147.317714 -46.766226)
		(width 0.12446)
		(layer "F.Cu")
		(net "PHY_SCC_TO_IOC_C_45_DN")
	)
	(segment
		(start 161.123122 -35.614864)
		(end 161.386774 -35.670744)
		(width 0.1016)
		(layer "In2.Cu")
		(net "PHY_SCC_TO_IOC_C_45_DN")
	)
	(segment
		(start 156.342588 -38.948614)
		(end 160.80105 -36.05149)
		(width 0.1016)
		(layer "In2.Cu")
		(net "PHY_SCC_TO_IOC_C_45_DN")
	)
	(segment
		(start 160.85693 -35.787838)
		(end 161.123122 -35.614864)
		(width 0.1016)
		(layer "In2.Cu")
		(net "PHY_SCC_TO_IOC_C_45_DN")
	)
	(segment
		(start 149.277832 -47.243492)
		(end 150.768558 -46.89094)
		(width 0.1016)
		(layer "In2.Cu")
		(net "PHY_SCC_TO_IOC_C_45_DN")
	)
	(segment
		(start 147.54479 -46.446186)
		(end 147.485608 -46.725078)
		(width 0.1016)
		(layer "In2.Cu")
		(net "PHY_SCC_TO_IOC_C_45_DN")
	)
	(segment
		(start 161.386774 -35.670744)
		(end 161.652966 -35.49777)
		(width 0.1016)
		(layer "In2.Cu")
		(net "PHY_SCC_TO_IOC_C_45_DN")
	)
	(segment
		(start 163.054792 -35.200082)
		(end 165.629336 -35.200082)
		(width 0.1016)
		(layer "In2.Cu")
		(net "PHY_SCC_TO_IOC_C_45_DN")
	)
	(segment
		(start 147.588478 -46.884082)
		(end 149.277832 -47.243492)
		(width 0.1016)
		(layer "In2.Cu")
		(net "PHY_SCC_TO_IOC_C_45_DN")
	)
	(segment
		(start 160.80105 -36.05149)
		(end 160.85693 -35.787838)
		(width 0.1016)
		(layer "In2.Cu")
		(net "PHY_SCC_TO_IOC_C_45_DN")
	)
	(segment
		(start 166.19982 -35.352228)
		(end 166.19982 -35.199828)
		(width 0.1016)
		(layer "In2.Cu")
		(net "PHY_SCC_TO_IOC_C_45_DN")
	)
	(segment
		(start 165.629336 -35.200082)
		(end 165.882574 -35.45332)
		(width 0.1016)
		(layer "In2.Cu")
		(net "PHY_SCC_TO_IOC_C_45_DN")
	)
	(segment
		(start 155.417774 -40.372792)
		(end 156.342588 -38.948614)
		(width 0.1016)
		(layer "In2.Cu")
		(net "PHY_SCC_TO_IOC_C_45_DN")
	)
	(segment
		(start 161.652966 -35.49777)
		(end 163.054792 -35.200082)
		(width 0.1016)
		(layer "In2.Cu")
		(net "PHY_SCC_TO_IOC_C_45_DN")
	)
	(segment
		(start 165.882574 -35.45332)
		(end 166.111936 -35.45332)
		(width 0.1016)
		(layer "In2.Cu")
		(net "PHY_SCC_TO_IOC_C_45_DN")
	)
	(segment
		(start 151.490172 -46.422564)
		(end 153.881074 -42.739818)
		(width 0.1016)
		(layer "In2.Cu")
		(net "PHY_SCC_TO_IOC_C_45_DN")
	)
	(segment
		(start 153.881074 -42.739818)
		(end 155.417774 -40.372792)
		(width 0.1016)
		(layer "In2.Cu")
		(net "PHY_SCC_TO_IOC_C_45_DN")
	)
	(segment
		(start 150.768558 -46.89094)
		(end 151.490172 -46.422564)
		(width 0.1016)
		(layer "In2.Cu")
		(net "PHY_SCC_TO_IOC_C_45_DN")
	)
	(arc
		(start 147.485608 -46.725078)
		(mid 147.48492 -46.777504)
		(end 147.504404 -46.82617)
		(width 0.1016)
		(layer "In2.Cu")
		(net "PHY_SCC_TO_IOC_C_45_DN")
	)
	(arc
		(start 166.111936 -35.45332)
		(mid 166.178869 -35.422796)
		(end 166.19982 -35.352228)
		(width 0.1016)
		(layer "In2.Cu")
		(net "PHY_SCC_TO_IOC_C_45_DN")
	)
	(arc
		(start 147.504404 -46.82617)
		(mid 147.540719 -46.863413)
		(end 147.588478 -46.884082)
		(width 0.1016)
		(layer "In2.Cu")
		(net "PHY_SCC_TO_IOC_C_45_DN")
	)
	(segment
		(start 149.159722 -44.857162)
		(end 149.512782 -44.929552)
		(width 0.12446)
		(layer "F.Cu")
		(net "PHY_SCC_TO_IOC_C_44_DP")
	)
	(segment
		(start 165.800024 -34.800032)
		(end 165.399974 -34.399982)
		(width 0.12446)
		(layer "F.Cu")
		(net "PHY_SCC_TO_IOC_C_44_DP")
	)
	(segment
		(start 149.512782 -44.929552)
		(end 149.516846 -44.930314)
		(width 0.12446)
		(layer "F.Cu")
		(net "PHY_SCC_TO_IOC_C_44_DP")
	)
	(segment
		(start 149.042374 -44.940474)
		(end 149.159722 -44.857162)
		(width 0.12446)
		(layer "F.Cu")
		(net "PHY_SCC_TO_IOC_C_44_DP")
	)
	(segment
		(start 149.603206 -45.070776)
		(end 149.54758 -45.321982)
		(width 0.12446)
		(layer "F.Cu")
		(net "PHY_SCC_TO_IOC_C_44_DP")
	)
	(segment
		(start 148.78304 -44.88688)
		(end 149.042374 -44.940474)
		(width 0.12446)
		(layer "F.Cu")
		(net "PHY_SCC_TO_IOC_C_44_DP")
	)
	(via
		(at 165.399974 -34.399982)
		(size 0.508)
		(drill 0.254)
		(layers "F.Cu" "B.Cu")
		(net "PHY_SCC_TO_IOC_C_44_DP")
	)
	(arc
		(start 149.516846 -44.930314)
		(mid 149.590342 -44.981877)
		(end 149.603206 -45.070776)
		(width 0.12446)
		(layer "F.Cu")
		(net "PHY_SCC_TO_IOC_C_44_DP")
	)
	(segment
		(start 151.904954 -44.596812)
		(end 151.564848 -44.817538)
		(width 0.1016)
		(layer "In2.Cu")
		(net "PHY_SCC_TO_IOC_C_44_DP")
	)
	(segment
		(start 157.882082 -36.870132)
		(end 157.825948 -37.133784)
		(width 0.1016)
		(layer "In2.Cu")
		(net "PHY_SCC_TO_IOC_C_44_DP")
	)
	(segment
		(start 156.220414 -37.949124)
		(end 151.904954 -44.596812)
		(width 0.1016)
		(layer "In2.Cu")
		(net "PHY_SCC_TO_IOC_C_44_DP")
	)
	(segment
		(start 163.08959 -34.383218)
		(end 163.089336 -34.383472)
		(width 0.1016)
		(layer "In2.Cu")
		(net "PHY_SCC_TO_IOC_C_44_DP")
	)
	(segment
		(start 158.656782 -36.594034)
		(end 158.401258 -36.76015)
		(width 0.1016)
		(layer "In2.Cu")
		(net "PHY_SCC_TO_IOC_C_44_DP")
	)
	(segment
		(start 150.683976 -45.135038)
		(end 150.683976 -45.135292)
		(width 0.1016)
		(layer "In2.Cu")
		(net "PHY_SCC_TO_IOC_C_44_DP")
	)
	(segment
		(start 151.564848 -44.817538)
		(end 150.683976 -45.135038)
		(width 0.1016)
		(layer "In2.Cu")
		(net "PHY_SCC_TO_IOC_C_44_DP")
	)
	(segment
		(start 162.15995 -34.775394)
		(end 161.93389 -34.628582)
		(width 0.1016)
		(layer "In2.Cu")
		(net "PHY_SCC_TO_IOC_C_44_DP")
	)
	(segment
		(start 150.683976 -45.135292)
		(end 149.765512 -44.939966)
		(width 0.1016)
		(layer "In2.Cu")
		(net "PHY_SCC_TO_IOC_C_44_DP")
	)
	(segment
		(start 163.76396 -34.326068)
		(end 163.70681 -34.383218)
		(width 0.0889)
		(layer "In2.Cu")
		(net "PHY_SCC_TO_IOC_C_44_DP")
	)
	(segment
		(start 165.299898 -34.399982)
		(end 164.847016 -33.9471)
		(width 0.0889)
		(layer "In2.Cu")
		(net "PHY_SCC_TO_IOC_C_44_DP")
	)
	(segment
		(start 161.04235 -34.817812)
		(end 159.54375 -35.79114)
		(width 0.1016)
		(layer "In2.Cu")
		(net "PHY_SCC_TO_IOC_C_44_DP")
	)
	(segment
		(start 157.825948 -37.133784)
		(end 157.570424 -37.299646)
		(width 0.1016)
		(layer "In2.Cu")
		(net "PHY_SCC_TO_IOC_C_44_DP")
	)
	(segment
		(start 159.487616 -36.054538)
		(end 159.232092 -36.220654)
		(width 0.1016)
		(layer "In2.Cu")
		(net "PHY_SCC_TO_IOC_C_44_DP")
	)
	(segment
		(start 163.089336 -34.383472)
		(end 162.604704 -34.486342)
		(width 0.1016)
		(layer "In2.Cu")
		(net "PHY_SCC_TO_IOC_C_44_DP")
	)
	(segment
		(start 156.73959 -37.839142)
		(end 156.475938 -37.783008)
		(width 0.1016)
		(layer "In2.Cu")
		(net "PHY_SCC_TO_IOC_C_44_DP")
	)
	(segment
		(start 164.413692 -33.9471)
		(end 164.034724 -34.326068)
		(width 0.0889)
		(layer "In2.Cu")
		(net "PHY_SCC_TO_IOC_C_44_DP")
	)
	(segment
		(start 149.606762 -45.042836)
		(end 149.54758 -45.321982)
		(width 0.1016)
		(layer "In2.Cu")
		(net "PHY_SCC_TO_IOC_C_44_DP")
	)
	(segment
		(start 162.457892 -34.712148)
		(end 162.15995 -34.775394)
		(width 0.1016)
		(layer "In2.Cu")
		(net "PHY_SCC_TO_IOC_C_44_DP")
	)
	(segment
		(start 157.570424 -37.299646)
		(end 157.306772 -37.243512)
		(width 0.1016)
		(layer "In2.Cu")
		(net "PHY_SCC_TO_IOC_C_44_DP")
	)
	(segment
		(start 158.137606 -36.704016)
		(end 157.882082 -36.870132)
		(width 0.1016)
		(layer "In2.Cu")
		(net "PHY_SCC_TO_IOC_C_44_DP")
	)
	(segment
		(start 158.712916 -36.330636)
		(end 158.656782 -36.594034)
		(width 0.1016)
		(layer "In2.Cu")
		(net "PHY_SCC_TO_IOC_C_44_DP")
	)
	(segment
		(start 158.401258 -36.76015)
		(end 158.137606 -36.704016)
		(width 0.1016)
		(layer "In2.Cu")
		(net "PHY_SCC_TO_IOC_C_44_DP")
	)
	(segment
		(start 156.475938 -37.783008)
		(end 156.220414 -37.949124)
		(width 0.1016)
		(layer "In2.Cu")
		(net "PHY_SCC_TO_IOC_C_44_DP")
	)
	(segment
		(start 159.54375 -35.79114)
		(end 159.487616 -36.054538)
		(width 0.1016)
		(layer "In2.Cu")
		(net "PHY_SCC_TO_IOC_C_44_DP")
	)
	(segment
		(start 149.676104 -44.951396)
		(end 149.664928 -44.958762)
		(width 0.1016)
		(layer "In2.Cu")
		(net "PHY_SCC_TO_IOC_C_44_DP")
	)
	(segment
		(start 161.93389 -34.628582)
		(end 161.04235 -34.817812)
		(width 0.1016)
		(layer "In2.Cu")
		(net "PHY_SCC_TO_IOC_C_44_DP")
	)
	(segment
		(start 163.70681 -34.383218)
		(end 163.684712 -34.383218)
		(width 0.0889)
		(layer "In2.Cu")
		(net "PHY_SCC_TO_IOC_C_44_DP")
	)
	(segment
		(start 164.034724 -34.326068)
		(end 163.76396 -34.326068)
		(width 0.0889)
		(layer "In2.Cu")
		(net "PHY_SCC_TO_IOC_C_44_DP")
	)
	(segment
		(start 162.604704 -34.486342)
		(end 162.457892 -34.712148)
		(width 0.1016)
		(layer "In2.Cu")
		(net "PHY_SCC_TO_IOC_C_44_DP")
	)
	(segment
		(start 163.684712 -34.383218)
		(end 163.08959 -34.383218)
		(width 0.1016)
		(layer "In2.Cu")
		(net "PHY_SCC_TO_IOC_C_44_DP")
	)
	(segment
		(start 158.96844 -36.16452)
		(end 158.712916 -36.330636)
		(width 0.1016)
		(layer "In2.Cu")
		(net "PHY_SCC_TO_IOC_C_44_DP")
	)
	(segment
		(start 157.051248 -37.409628)
		(end 156.995114 -37.673026)
		(width 0.1016)
		(layer "In2.Cu")
		(net "PHY_SCC_TO_IOC_C_44_DP")
	)
	(segment
		(start 156.995114 -37.673026)
		(end 156.73959 -37.839142)
		(width 0.1016)
		(layer "In2.Cu")
		(net "PHY_SCC_TO_IOC_C_44_DP")
	)
	(segment
		(start 164.847016 -33.9471)
		(end 164.413692 -33.9471)
		(width 0.0889)
		(layer "In2.Cu")
		(net "PHY_SCC_TO_IOC_C_44_DP")
	)
	(segment
		(start 159.232092 -36.220654)
		(end 158.96844 -36.16452)
		(width 0.1016)
		(layer "In2.Cu")
		(net "PHY_SCC_TO_IOC_C_44_DP")
	)
	(segment
		(start 157.306772 -37.243512)
		(end 157.051248 -37.409628)
		(width 0.1016)
		(layer "In2.Cu")
		(net "PHY_SCC_TO_IOC_C_44_DP")
	)
	(segment
		(start 165.399974 -34.399982)
		(end 165.299898 -34.399982)
		(width 0.0889)
		(layer "In2.Cu")
		(net "PHY_SCC_TO_IOC_C_44_DP")
	)
	(arc
		(start 149.765512 -44.939966)
		(mid 149.759152 -44.938616)
		(end 149.752812 -44.937172)
		(width 0.1016)
		(layer "In2.Cu")
		(net "PHY_SCC_TO_IOC_C_44_DP")
	)
	(arc
		(start 149.752812 -44.937172)
		(mid 149.713026 -44.936596)
		(end 149.676104 -44.951396)
		(width 0.1016)
		(layer "In2.Cu")
		(net "PHY_SCC_TO_IOC_C_44_DP")
	)
	(arc
		(start 149.664928 -44.958762)
		(mid 149.627474 -44.995016)
		(end 149.606762 -45.042836)
		(width 0.1016)
		(layer "In2.Cu")
		(net "PHY_SCC_TO_IOC_C_44_DP")
	)
	(segment
		(start 149.731222 -44.455334)
		(end 149.785324 -44.203874)
		(width 0.12446)
		(layer "F.Cu")
		(net "PHY_SCC_TO_IOC_C_44_DN")
	)
	(segment
		(start 149.247352 -44.459906)
		(end 149.558248 -44.523914)
		(width 0.12446)
		(layer "F.Cu")
		(net "PHY_SCC_TO_IOC_C_44_DN")
	)
	(segment
		(start 149.147022 -44.365418)
		(end 149.247352 -44.459906)
		(width 0.12446)
		(layer "F.Cu")
		(net "PHY_SCC_TO_IOC_C_44_DN")
	)
	(segment
		(start 166.59987 -34.800032)
		(end 166.19982 -34.399982)
		(width 0.12446)
		(layer "F.Cu")
		(net "PHY_SCC_TO_IOC_C_44_DN")
	)
	(segment
		(start 148.904452 -44.31538)
		(end 149.147022 -44.365418)
		(width 0.12446)
		(layer "F.Cu")
		(net "PHY_SCC_TO_IOC_C_44_DN")
	)
	(via
		(at 166.19982 -34.399982)
		(size 0.508)
		(drill 0.254)
		(layers "F.Cu" "B.Cu")
		(net "PHY_SCC_TO_IOC_C_44_DN")
	)
	(arc
		(start 149.558248 -44.523914)
		(mid 149.655004 -44.515495)
		(end 149.731222 -44.455334)
		(width 0.12446)
		(layer "F.Cu")
		(net "PHY_SCC_TO_IOC_C_44_DN")
	)
	(segment
		(start 155.999942 -37.728652)
		(end 151.684482 -44.37634)
		(width 0.1016)
		(layer "In2.Cu")
		(net "PHY_SCC_TO_IOC_C_44_DN")
	)
	(segment
		(start 165.169342 -33.999932)
		(end 164.92601 -33.7566)
		(width 0.0889)
		(layer "In2.Cu")
		(net "PHY_SCC_TO_IOC_C_44_DN")
	)
	(segment
		(start 164.334698 -33.7566)
		(end 163.95573 -34.135568)
		(width 0.0889)
		(layer "In2.Cu")
		(net "PHY_SCC_TO_IOC_C_44_DN")
	)
	(segment
		(start 163.70681 -34.078418)
		(end 163.684712 -34.078418)
		(width 0.0889)
		(layer "In2.Cu")
		(net "PHY_SCC_TO_IOC_C_44_DN")
	)
	(segment
		(start 160.923732 -34.5313)
		(end 156.18206 -37.610288)
		(width 0.1016)
		(layer "In2.Cu")
		(net "PHY_SCC_TO_IOC_C_44_DN")
	)
	(segment
		(start 163.95573 -34.135568)
		(end 163.76396 -34.135568)
		(width 0.0889)
		(layer "In2.Cu")
		(net "PHY_SCC_TO_IOC_C_44_DN")
	)
	(segment
		(start 149.726142 -44.482766)
		(end 149.785324 -44.203874)
		(width 0.1016)
		(layer "In2.Cu")
		(net "PHY_SCC_TO_IOC_C_44_DN")
	)
	(segment
		(start 164.92601 -33.7566)
		(end 164.334698 -33.7566)
		(width 0.0889)
		(layer "In2.Cu")
		(net "PHY_SCC_TO_IOC_C_44_DN")
	)
	(segment
		(start 165.79977 -33.999932)
		(end 165.169342 -33.999932)
		(width 0.0889)
		(layer "In2.Cu")
		(net "PHY_SCC_TO_IOC_C_44_DN")
	)
	(segment
		(start 151.428196 -44.542456)
		(end 150.662386 -44.818808)
		(width 0.1016)
		(layer "In2.Cu")
		(net "PHY_SCC_TO_IOC_C_44_DN")
	)
	(segment
		(start 163.76396 -34.135568)
		(end 163.70681 -34.078418)
		(width 0.0889)
		(layer "In2.Cu")
		(net "PHY_SCC_TO_IOC_C_44_DN")
	)
	(segment
		(start 150.662386 -44.818808)
		(end 149.829012 -44.64177)
		(width 0.1016)
		(layer "In2.Cu")
		(net "PHY_SCC_TO_IOC_C_44_DN")
	)
	(segment
		(start 156.18206 -37.610288)
		(end 155.999942 -37.728652)
		(width 0.1016)
		(layer "In2.Cu")
		(net "PHY_SCC_TO_IOC_C_44_DN")
	)
	(segment
		(start 163.057332 -34.078418)
		(end 160.923732 -34.5313)
		(width 0.1016)
		(layer "In2.Cu")
		(net "PHY_SCC_TO_IOC_C_44_DN")
	)
	(segment
		(start 151.684482 -44.37634)
		(end 151.428196 -44.542456)
		(width 0.1016)
		(layer "In2.Cu")
		(net "PHY_SCC_TO_IOC_C_44_DN")
	)
	(segment
		(start 166.19982 -34.399982)
		(end 165.79977 -33.999932)
		(width 0.0889)
		(layer "In2.Cu")
		(net "PHY_SCC_TO_IOC_C_44_DN")
	)
	(segment
		(start 163.684712 -34.078418)
		(end 163.057332 -34.078418)
		(width 0.1016)
		(layer "In2.Cu")
		(net "PHY_SCC_TO_IOC_C_44_DN")
	)
	(arc
		(start 149.829012 -44.64177)
		(mid 149.781188 -44.621195)
		(end 149.744938 -44.583858)
		(width 0.1016)
		(layer "In2.Cu")
		(net "PHY_SCC_TO_IOC_C_44_DN")
	)
	(arc
		(start 149.744938 -44.583858)
		(mid 149.725501 -44.535183)
		(end 149.726142 -44.482766)
		(width 0.1016)
		(layer "In2.Cu")
		(net "PHY_SCC_TO_IOC_C_44_DN")
	)
	(segment
		(start 148.611844 -40.960802)
		(end 148.611844 -40.960548)
		(width 0.12446)
		(layer "F.Cu")
		(net "PHY_SCC_TO_IOC_C_43_DP")
	)
	(segment
		(start 148.576538 -40.953182)
		(end 148.192998 -40.871902)
		(width 0.12446)
		(layer "F.Cu")
		(net "PHY_SCC_TO_IOC_C_43_DP")
	)
	(segment
		(start 148.62683 -41.353486)
		(end 148.682456 -41.10228)
		(width 0.12446)
		(layer "F.Cu")
		(net "PHY_SCC_TO_IOC_C_43_DP")
	)
	(segment
		(start 148.593048 -40.956484)
		(end 148.576538 -40.953182)
		(width 0.12446)
		(layer "F.Cu")
		(net "PHY_SCC_TO_IOC_C_43_DP")
	)
	(segment
		(start 148.192998 -40.871902)
		(end 148.087588 -40.940482)
		(width 0.12446)
		(layer "F.Cu")
		(net "PHY_SCC_TO_IOC_C_43_DP")
	)
	(segment
		(start 166.19982 -33.599882)
		(end 165.800024 -33.200086)
		(width 0.12446)
		(layer "F.Cu")
		(net "PHY_SCC_TO_IOC_C_43_DP")
	)
	(segment
		(start 148.611844 -40.960548)
		(end 148.593048 -40.956484)
		(width 0.12446)
		(layer "F.Cu")
		(net "PHY_SCC_TO_IOC_C_43_DP")
	)
	(segment
		(start 165.800024 -33.200086)
		(end 165.800024 -33.199832)
		(width 0.12446)
		(layer "F.Cu")
		(net "PHY_SCC_TO_IOC_C_43_DP")
	)
	(segment
		(start 148.087588 -40.940482)
		(end 147.743418 -40.867076)
		(width 0.12446)
		(layer "F.Cu")
		(net "PHY_SCC_TO_IOC_C_43_DP")
	)
	(via
		(at 166.19982 -33.599882)
		(size 0.508)
		(drill 0.254)
		(layers "F.Cu" "B.Cu")
		(net "PHY_SCC_TO_IOC_C_43_DP")
	)
	(arc
		(start 148.682456 -41.10228)
		(mid 148.681273 -41.014481)
		(end 148.611844 -40.960802)
		(width 0.12446)
		(layer "F.Cu")
		(net "PHY_SCC_TO_IOC_C_43_DP")
	)
	(segment
		(start 165.48989 -33.094422)
		(end 165.69055 -33.295082)
		(width 0.0889)
		(layer "In2.Cu")
		(net "PHY_SCC_TO_IOC_C_43_DP")
	)
	(segment
		(start 154.00655 -39.474648)
		(end 155.324302 -37.445442)
		(width 0.1016)
		(layer "In2.Cu")
		(net "PHY_SCC_TO_IOC_C_43_DP")
	)
	(segment
		(start 165.240716 -33.094422)
		(end 165.48989 -33.094422)
		(width 0.0889)
		(layer "In2.Cu")
		(net "PHY_SCC_TO_IOC_C_43_DP")
	)
	(segment
		(start 148.62683 -41.353486)
		(end 148.686012 -41.07434)
		(width 0.1016)
		(layer "In2.Cu")
		(net "PHY_SCC_TO_IOC_C_43_DP")
	)
	(segment
		(start 164.913818 -33.42132)
		(end 165.240716 -33.094422)
		(width 0.0889)
		(layer "In2.Cu")
		(net "PHY_SCC_TO_IOC_C_43_DP")
	)
	(segment
		(start 151.6634 -40.9956)
		(end 154.00655 -39.474648)
		(width 0.1016)
		(layer "In2.Cu")
		(net "PHY_SCC_TO_IOC_C_43_DP")
	)
	(segment
		(start 161.360104 -33.525714)
		(end 161.582608 -33.47847)
		(width 0.1016)
		(layer "In2.Cu")
		(net "PHY_SCC_TO_IOC_C_43_DP")
	)
	(segment
		(start 163.796218 -33.47847)
		(end 163.818316 -33.47847)
		(width 0.0889)
		(layer "In2.Cu")
		(net "PHY_SCC_TO_IOC_C_43_DP")
	)
	(segment
		(start 166.19982 -33.54197)
		(end 166.19982 -33.599882)
		(width 0.0889)
		(layer "In2.Cu")
		(net "PHY_SCC_TO_IOC_C_43_DP")
	)
	(segment
		(start 148.844762 -40.97147)
		(end 150.50643 -41.324022)
		(width 0.1016)
		(layer "In2.Cu")
		(net "PHY_SCC_TO_IOC_C_43_DP")
	)
	(segment
		(start 148.744178 -40.990266)
		(end 148.755354 -40.9829)
		(width 0.1016)
		(layer "In2.Cu")
		(net "PHY_SCC_TO_IOC_C_43_DP")
	)
	(segment
		(start 163.875466 -33.42132)
		(end 164.913818 -33.42132)
		(width 0.0889)
		(layer "In2.Cu")
		(net "PHY_SCC_TO_IOC_C_43_DP")
	)
	(segment
		(start 150.50643 -41.324022)
		(end 151.6634 -40.9956)
		(width 0.1016)
		(layer "In2.Cu")
		(net "PHY_SCC_TO_IOC_C_43_DP")
	)
	(segment
		(start 165.69055 -33.295082)
		(end 165.952932 -33.295082)
		(width 0.0889)
		(layer "In2.Cu")
		(net "PHY_SCC_TO_IOC_C_43_DP")
	)
	(segment
		(start 155.324302 -37.445442)
		(end 161.360104 -33.525714)
		(width 0.1016)
		(layer "In2.Cu")
		(net "PHY_SCC_TO_IOC_C_43_DP")
	)
	(segment
		(start 161.582608 -33.47847)
		(end 163.796218 -33.47847)
		(width 0.1016)
		(layer "In2.Cu")
		(net "PHY_SCC_TO_IOC_C_43_DP")
	)
	(segment
		(start 163.818316 -33.47847)
		(end 163.875466 -33.42132)
		(width 0.0889)
		(layer "In2.Cu")
		(net "PHY_SCC_TO_IOC_C_43_DP")
	)
	(arc
		(start 148.686012 -41.07434)
		(mid 148.706779 -41.026558)
		(end 148.744178 -40.990266)
		(width 0.1016)
		(layer "In2.Cu")
		(net "PHY_SCC_TO_IOC_C_43_DP")
	)
	(arc
		(start 165.952932 -33.295082)
		(mid 166.127508 -33.367394)
		(end 166.19982 -33.54197)
		(width 0.0889)
		(layer "In2.Cu")
		(net "PHY_SCC_TO_IOC_C_43_DP")
	)
	(arc
		(start 148.832062 -40.968676)
		(mid 148.838402 -40.97012)
		(end 148.844762 -40.97147)
		(width 0.1016)
		(layer "In2.Cu")
		(net "PHY_SCC_TO_IOC_C_43_DP")
	)
	(arc
		(start 148.755354 -40.9829)
		(mid 148.792287 -40.968158)
		(end 148.832062 -40.968676)
		(width 0.1016)
		(layer "In2.Cu")
		(net "PHY_SCC_TO_IOC_C_43_DP")
	)
	(segment
		(start 148.677884 -40.558974)
		(end 148.635466 -40.54983)
		(width 0.12446)
		(layer "F.Cu")
		(net "PHY_SCC_TO_IOC_C_43_DN")
	)
	(segment
		(start 166.19982 -32.800036)
		(end 166.599616 -33.199832)
		(width 0.12446)
		(layer "F.Cu")
		(net "PHY_SCC_TO_IOC_C_43_DN")
	)
	(segment
		(start 166.599616 -33.199832)
		(end 166.59987 -33.199832)
		(width 0.12446)
		(layer "F.Cu")
		(net "PHY_SCC_TO_IOC_C_43_DN")
	)
	(segment
		(start 148.635466 -40.54983)
		(end 148.288502 -40.476424)
		(width 0.12446)
		(layer "F.Cu")
		(net "PHY_SCC_TO_IOC_C_43_DN")
	)
	(segment
		(start 148.220684 -40.371522)
		(end 147.86483 -40.29583)
		(width 0.12446)
		(layer "F.Cu")
		(net "PHY_SCC_TO_IOC_C_43_DN")
	)
	(segment
		(start 148.288502 -40.476424)
		(end 148.220684 -40.371522)
		(width 0.12446)
		(layer "F.Cu")
		(net "PHY_SCC_TO_IOC_C_43_DN")
	)
	(segment
		(start 148.864574 -40.235378)
		(end 148.810472 -40.486838)
		(width 0.12446)
		(layer "F.Cu")
		(net "PHY_SCC_TO_IOC_C_43_DN")
	)
	(via
		(at 166.19982 -32.800036)
		(size 0.508)
		(drill 0.254)
		(layers "F.Cu" "B.Cu")
		(net "PHY_SCC_TO_IOC_C_43_DN")
	)
	(arc
		(start 148.810472 -40.486838)
		(mid 148.757467 -40.547277)
		(end 148.677884 -40.558974)
		(width 0.12446)
		(layer "F.Cu")
		(net "PHY_SCC_TO_IOC_C_43_DN")
	)
	(segment
		(start 148.805392 -40.51427)
		(end 148.864574 -40.235378)
		(width 0.1016)
		(layer "In2.Cu")
		(net "PHY_SCC_TO_IOC_C_43_DN")
	)
	(segment
		(start 161.550604 -33.17367)
		(end 161.241486 -33.239202)
		(width 0.1016)
		(layer "In2.Cu")
		(net "PHY_SCC_TO_IOC_C_43_DN")
	)
	(segment
		(start 165.568884 -32.903922)
		(end 165.161722 -32.903922)
		(width 0.0889)
		(layer "In2.Cu")
		(net "PHY_SCC_TO_IOC_C_43_DN")
	)
	(segment
		(start 164.834824 -33.23082)
		(end 163.875466 -33.23082)
		(width 0.0889)
		(layer "In2.Cu")
		(net "PHY_SCC_TO_IOC_C_43_DN")
	)
	(segment
		(start 165.161722 -32.903922)
		(end 164.834824 -33.23082)
		(width 0.0889)
		(layer "In2.Cu")
		(net "PHY_SCC_TO_IOC_C_43_DN")
	)
	(segment
		(start 150.495762 -41.010078)
		(end 148.908262 -40.673274)
		(width 0.1016)
		(layer "In2.Cu")
		(net "PHY_SCC_TO_IOC_C_43_DN")
	)
	(segment
		(start 153.786078 -39.254176)
		(end 152.623012 -40.009064)
		(width 0.1016)
		(layer "In2.Cu")
		(net "PHY_SCC_TO_IOC_C_43_DN")
	)
	(segment
		(start 152.359614 -39.953184)
		(end 152.103836 -40.119046)
		(width 0.1016)
		(layer "In2.Cu")
		(net "PHY_SCC_TO_IOC_C_43_DN")
	)
	(segment
		(start 152.103836 -40.119046)
		(end 152.047702 -40.382698)
		(width 0.1016)
		(layer "In2.Cu")
		(net "PHY_SCC_TO_IOC_C_43_DN")
	)
	(segment
		(start 152.623012 -40.009064)
		(end 152.359614 -39.953184)
		(width 0.1016)
		(layer "In2.Cu")
		(net "PHY_SCC_TO_IOC_C_43_DN")
	)
	(segment
		(start 161.241486 -33.239202)
		(end 155.10383 -37.22497)
		(width 0.1016)
		(layer "In2.Cu")
		(net "PHY_SCC_TO_IOC_C_43_DN")
	)
	(segment
		(start 166.19982 -32.800036)
		(end 166.19982 -32.857694)
		(width 0.0889)
		(layer "In2.Cu")
		(net "PHY_SCC_TO_IOC_C_43_DN")
	)
	(segment
		(start 163.818316 -33.17367)
		(end 163.796218 -33.17367)
		(width 0.0889)
		(layer "In2.Cu")
		(net "PHY_SCC_TO_IOC_C_43_DN")
	)
	(segment
		(start 155.10383 -37.22497)
		(end 153.786078 -39.254176)
		(width 0.1016)
		(layer "In2.Cu")
		(net "PHY_SCC_TO_IOC_C_43_DN")
	)
	(segment
		(start 152.047702 -40.382698)
		(end 151.535892 -40.71493)
		(width 0.1016)
		(layer "In2.Cu")
		(net "PHY_SCC_TO_IOC_C_43_DN")
	)
	(segment
		(start 163.796218 -33.17367)
		(end 161.550604 -33.17367)
		(width 0.1016)
		(layer "In2.Cu")
		(net "PHY_SCC_TO_IOC_C_43_DN")
	)
	(segment
		(start 165.769544 -33.104582)
		(end 165.568884 -32.903922)
		(width 0.0889)
		(layer "In2.Cu")
		(net "PHY_SCC_TO_IOC_C_43_DN")
	)
	(segment
		(start 165.952932 -33.104582)
		(end 165.769544 -33.104582)
		(width 0.0889)
		(layer "In2.Cu")
		(net "PHY_SCC_TO_IOC_C_43_DN")
	)
	(segment
		(start 163.875466 -33.23082)
		(end 163.818316 -33.17367)
		(width 0.0889)
		(layer "In2.Cu")
		(net "PHY_SCC_TO_IOC_C_43_DN")
	)
	(segment
		(start 151.535892 -40.71493)
		(end 150.495762 -41.010078)
		(width 0.1016)
		(layer "In2.Cu")
		(net "PHY_SCC_TO_IOC_C_43_DN")
	)
	(arc
		(start 166.19982 -32.857694)
		(mid 166.127508 -33.03227)
		(end 165.952932 -33.104582)
		(width 0.0889)
		(layer "In2.Cu")
		(net "PHY_SCC_TO_IOC_C_43_DN")
	)
	(arc
		(start 148.908262 -40.673274)
		(mid 148.860438 -40.652699)
		(end 148.824188 -40.615362)
		(width 0.1016)
		(layer "In2.Cu")
		(net "PHY_SCC_TO_IOC_C_43_DN")
	)
	(arc
		(start 148.824188 -40.615362)
		(mid 148.804751 -40.566687)
		(end 148.805392 -40.51427)
		(width 0.1016)
		(layer "In2.Cu")
		(net "PHY_SCC_TO_IOC_C_43_DN")
	)
	(segment
		(start 151.04999 -38.859968)
		(end 150.994364 -39.111174)
		(width 0.12446)
		(layer "F.Cu")
		(net "PHY_SCC_TO_IOC_C_42_DP")
	)
	(segment
		(start 150.110952 -38.624764)
		(end 150.455122 -38.69817)
		(width 0.12446)
		(layer "F.Cu")
		(net "PHY_SCC_TO_IOC_C_42_DP")
	)
	(segment
		(start 165.800024 -32.399986)
		(end 166.200074 -31.999936)
		(width 0.12446)
		(layer "F.Cu")
		(net "PHY_SCC_TO_IOC_C_42_DP")
	)
	(segment
		(start 150.560532 -38.62959)
		(end 150.979378 -38.718236)
		(width 0.12446)
		(layer "F.Cu")
		(net "PHY_SCC_TO_IOC_C_42_DP")
	)
	(segment
		(start 150.979378 -38.718236)
		(end 150.979378 -38.71849)
		(width 0.12446)
		(layer "F.Cu")
		(net "PHY_SCC_TO_IOC_C_42_DP")
	)
	(segment
		(start 150.455122 -38.69817)
		(end 150.560532 -38.62959)
		(width 0.12446)
		(layer "F.Cu")
		(net "PHY_SCC_TO_IOC_C_42_DP")
	)
	(via
		(at 166.200074 -31.999936)
		(size 0.508)
		(drill 0.254)
		(layers "F.Cu" "B.Cu")
		(net "PHY_SCC_TO_IOC_C_42_DP")
	)
	(arc
		(start 150.979378 -38.71849)
		(mid 151.048711 -38.772217)
		(end 151.04999 -38.859968)
		(width 0.12446)
		(layer "F.Cu")
		(net "PHY_SCC_TO_IOC_C_42_DP")
	)
	(segment
		(start 165.311836 -31.940246)
		(end 165.254686 -31.997396)
		(width 0.0889)
		(layer "In2.Cu")
		(net "PHY_SCC_TO_IOC_C_42_DP")
	)
	(segment
		(start 156.678376 -35.25901)
		(end 156.422852 -35.425126)
		(width 0.1016)
		(layer "In2.Cu")
		(net "PHY_SCC_TO_IOC_C_42_DP")
	)
	(segment
		(start 157.197552 -35.149028)
		(end 156.942028 -35.315144)
		(width 0.1016)
		(layer "In2.Cu")
		(net "PHY_SCC_TO_IOC_C_42_DP")
	)
	(segment
		(start 155.592018 -35.964622)
		(end 155.535884 -36.22802)
		(width 0.1016)
		(layer "In2.Cu")
		(net "PHY_SCC_TO_IOC_C_42_DP")
	)
	(segment
		(start 163.679124 -32.535876)
		(end 160.87217 -32.535876)
		(width 0.1016)
		(layer "In2.Cu")
		(net "PHY_SCC_TO_IOC_C_42_DP")
	)
	(segment
		(start 155.28036 -36.394136)
		(end 155.016708 -36.338002)
		(width 0.1016)
		(layer "In2.Cu")
		(net "PHY_SCC_TO_IOC_C_42_DP")
	)
	(segment
		(start 155.847542 -35.798506)
		(end 155.592018 -35.964622)
		(width 0.1016)
		(layer "In2.Cu")
		(net "PHY_SCC_TO_IOC_C_42_DP")
	)
	(segment
		(start 166.200074 -31.999936)
		(end 166.140384 -31.940246)
		(width 0.0889)
		(layer "In2.Cu")
		(net "PHY_SCC_TO_IOC_C_42_DP")
	)
	(segment
		(start 156.366718 -35.688524)
		(end 156.111194 -35.85464)
		(width 0.1016)
		(layer "In2.Cu")
		(net "PHY_SCC_TO_IOC_C_42_DP")
	)
	(segment
		(start 165.254686 -31.997396)
		(end 165.232588 -31.997396)
		(width 0.0889)
		(layer "In2.Cu")
		(net "PHY_SCC_TO_IOC_C_42_DP")
	)
	(segment
		(start 164.217604 -31.997396)
		(end 163.679124 -32.535876)
		(width 0.1016)
		(layer "In2.Cu")
		(net "PHY_SCC_TO_IOC_C_42_DP")
	)
	(segment
		(start 159.729678 -33.504886)
		(end 159.474154 -33.671002)
		(width 0.1016)
		(layer "In2.Cu")
		(net "PHY_SCC_TO_IOC_C_42_DP")
	)
	(segment
		(start 151.122888 -38.740588)
		(end 151.111712 -38.747954)
		(width 0.1016)
		(layer "In2.Cu")
		(net "PHY_SCC_TO_IOC_C_42_DP")
	)
	(segment
		(start 165.232588 -31.997396)
		(end 164.217604 -31.997396)
		(width 0.1016)
		(layer "In2.Cu")
		(net "PHY_SCC_TO_IOC_C_42_DP")
	)
	(segment
		(start 159.785812 -33.241488)
		(end 159.729678 -33.504886)
		(width 0.1016)
		(layer "In2.Cu")
		(net "PHY_SCC_TO_IOC_C_42_DP")
	)
	(segment
		(start 155.535884 -36.22802)
		(end 155.28036 -36.394136)
		(width 0.1016)
		(layer "In2.Cu")
		(net "PHY_SCC_TO_IOC_C_42_DP")
	)
	(segment
		(start 154.761184 -36.504118)
		(end 153.55316 -38.364414)
		(width 0.1016)
		(layer "In2.Cu")
		(net "PHY_SCC_TO_IOC_C_42_DP")
	)
	(segment
		(start 158.64332 -34.210498)
		(end 158.379668 -34.154364)
		(width 0.1016)
		(layer "In2.Cu")
		(net "PHY_SCC_TO_IOC_C_42_DP")
	)
	(segment
		(start 160.616646 -32.701992)
		(end 160.560512 -32.96539)
		(width 0.1016)
		(layer "In2.Cu")
		(net "PHY_SCC_TO_IOC_C_42_DP")
	)
	(segment
		(start 160.87217 -32.535876)
		(end 160.616646 -32.701992)
		(width 0.1016)
		(layer "In2.Cu")
		(net "PHY_SCC_TO_IOC_C_42_DP")
	)
	(segment
		(start 158.898844 -34.044382)
		(end 158.64332 -34.210498)
		(width 0.1016)
		(layer "In2.Cu")
		(net "PHY_SCC_TO_IOC_C_42_DP")
	)
	(segment
		(start 160.041336 -33.075372)
		(end 159.785812 -33.241488)
		(width 0.1016)
		(layer "In2.Cu")
		(net "PHY_SCC_TO_IOC_C_42_DP")
	)
	(segment
		(start 158.379668 -34.154364)
		(end 157.253686 -34.88563)
		(width 0.1016)
		(layer "In2.Cu")
		(net "PHY_SCC_TO_IOC_C_42_DP")
	)
	(segment
		(start 151.053546 -38.832028)
		(end 150.994364 -39.111174)
		(width 0.1016)
		(layer "In2.Cu")
		(net "PHY_SCC_TO_IOC_C_42_DP")
	)
	(segment
		(start 159.210502 -33.614868)
		(end 158.954978 -33.780984)
		(width 0.1016)
		(layer "In2.Cu")
		(net "PHY_SCC_TO_IOC_C_42_DP")
	)
	(segment
		(start 160.560512 -32.96539)
		(end 160.304988 -33.131506)
		(width 0.1016)
		(layer "In2.Cu")
		(net "PHY_SCC_TO_IOC_C_42_DP")
	)
	(segment
		(start 152.130252 -38.92423)
		(end 151.212296 -38.729158)
		(width 0.1016)
		(layer "In2.Cu")
		(net "PHY_SCC_TO_IOC_C_42_DP")
	)
	(segment
		(start 156.111194 -35.85464)
		(end 155.847542 -35.798506)
		(width 0.1016)
		(layer "In2.Cu")
		(net "PHY_SCC_TO_IOC_C_42_DP")
	)
	(segment
		(start 160.304988 -33.131506)
		(end 160.041336 -33.075372)
		(width 0.1016)
		(layer "In2.Cu")
		(net "PHY_SCC_TO_IOC_C_42_DP")
	)
	(segment
		(start 153.022808 -38.708584)
		(end 152.130252 -38.92423)
		(width 0.1016)
		(layer "In2.Cu")
		(net "PHY_SCC_TO_IOC_C_42_DP")
	)
	(segment
		(start 155.016708 -36.338002)
		(end 154.761184 -36.504118)
		(width 0.1016)
		(layer "In2.Cu")
		(net "PHY_SCC_TO_IOC_C_42_DP")
	)
	(segment
		(start 153.55316 -38.364414)
		(end 153.022808 -38.708584)
		(width 0.1016)
		(layer "In2.Cu")
		(net "PHY_SCC_TO_IOC_C_42_DP")
	)
	(segment
		(start 156.942028 -35.315144)
		(end 156.678376 -35.25901)
		(width 0.1016)
		(layer "In2.Cu")
		(net "PHY_SCC_TO_IOC_C_42_DP")
	)
	(segment
		(start 157.253686 -34.88563)
		(end 157.197552 -35.149028)
		(width 0.1016)
		(layer "In2.Cu")
		(net "PHY_SCC_TO_IOC_C_42_DP")
	)
	(segment
		(start 158.954978 -33.780984)
		(end 158.898844 -34.044382)
		(width 0.1016)
		(layer "In2.Cu")
		(net "PHY_SCC_TO_IOC_C_42_DP")
	)
	(segment
		(start 166.140384 -31.940246)
		(end 165.311836 -31.940246)
		(width 0.0889)
		(layer "In2.Cu")
		(net "PHY_SCC_TO_IOC_C_42_DP")
	)
	(segment
		(start 159.474154 -33.671002)
		(end 159.210502 -33.614868)
		(width 0.1016)
		(layer "In2.Cu")
		(net "PHY_SCC_TO_IOC_C_42_DP")
	)
	(segment
		(start 156.422852 -35.425126)
		(end 156.366718 -35.688524)
		(width 0.1016)
		(layer "In2.Cu")
		(net "PHY_SCC_TO_IOC_C_42_DP")
	)
	(arc
		(start 151.212296 -38.729158)
		(mid 151.205936 -38.727808)
		(end 151.199596 -38.726364)
		(width 0.1016)
		(layer "In2.Cu")
		(net "PHY_SCC_TO_IOC_C_42_DP")
	)
	(arc
		(start 151.111712 -38.747954)
		(mid 151.074258 -38.784208)
		(end 151.053546 -38.832028)
		(width 0.1016)
		(layer "In2.Cu")
		(net "PHY_SCC_TO_IOC_C_42_DP")
	)
	(arc
		(start 151.199596 -38.726364)
		(mid 151.15981 -38.725788)
		(end 151.122888 -38.740588)
		(width 0.1016)
		(layer "In2.Cu")
		(net "PHY_SCC_TO_IOC_C_42_DP")
	)
	(segment
		(start 150.656036 -38.234112)
		(end 150.588218 -38.12921)
		(width 0.12446)
		(layer "F.Cu")
		(net "PHY_SCC_TO_IOC_C_42_DN")
	)
	(segment
		(start 166.59987 -32.399986)
		(end 166.99992 -31.999936)
		(width 0.12446)
		(layer "F.Cu")
		(net "PHY_SCC_TO_IOC_C_42_DN")
	)
	(segment
		(start 151.003 -38.307518)
		(end 150.656036 -38.234112)
		(width 0.12446)
		(layer "F.Cu")
		(net "PHY_SCC_TO_IOC_C_42_DN")
	)
	(segment
		(start 150.588218 -38.12921)
		(end 150.232364 -38.053518)
		(width 0.12446)
		(layer "F.Cu")
		(net "PHY_SCC_TO_IOC_C_42_DN")
	)
	(segment
		(start 151.232108 -37.993066)
		(end 151.178006 -38.244526)
		(width 0.12446)
		(layer "F.Cu")
		(net "PHY_SCC_TO_IOC_C_42_DN")
	)
	(segment
		(start 151.045418 -38.316662)
		(end 151.003 -38.307518)
		(width 0.12446)
		(layer "F.Cu")
		(net "PHY_SCC_TO_IOC_C_42_DN")
	)
	(via
		(at 166.99992 -31.999936)
		(size 0.508)
		(drill 0.254)
		(layers "F.Cu" "B.Cu")
		(net "PHY_SCC_TO_IOC_C_42_DN")
	)
	(arc
		(start 151.178006 -38.244526)
		(mid 151.125001 -38.304965)
		(end 151.045418 -38.316662)
		(width 0.12446)
		(layer "F.Cu")
		(net "PHY_SCC_TO_IOC_C_42_DN")
	)
	(segment
		(start 165.825932 -31.749746)
		(end 165.311836 -31.749746)
		(width 0.0889)
		(layer "In2.Cu")
		(net "PHY_SCC_TO_IOC_C_42_DN")
	)
	(segment
		(start 165.311836 -31.749746)
		(end 165.254686 -31.692596)
		(width 0.0889)
		(layer "In2.Cu")
		(net "PHY_SCC_TO_IOC_C_42_DN")
	)
	(segment
		(start 160.781746 -32.231076)
		(end 154.72283 -36.165282)
		(width 0.1016)
		(layer "In2.Cu")
		(net "PHY_SCC_TO_IOC_C_42_DN")
	)
	(segment
		(start 154.72283 -36.165282)
		(end 154.540712 -36.283646)
		(width 0.1016)
		(layer "In2.Cu")
		(net "PHY_SCC_TO_IOC_C_42_DN")
	)
	(segment
		(start 165.232588 -31.692596)
		(end 164.091112 -31.692596)
		(width 0.1016)
		(layer "In2.Cu")
		(net "PHY_SCC_TO_IOC_C_42_DN")
	)
	(segment
		(start 166.59987 -31.599886)
		(end 165.975792 -31.599886)
		(width 0.0889)
		(layer "In2.Cu")
		(net "PHY_SCC_TO_IOC_C_42_DN")
	)
	(segment
		(start 165.975792 -31.599886)
		(end 165.825932 -31.749746)
		(width 0.0889)
		(layer "In2.Cu")
		(net "PHY_SCC_TO_IOC_C_42_DN")
	)
	(segment
		(start 154.540712 -36.283646)
		(end 153.332688 -38.143942)
		(width 0.1016)
		(layer "In2.Cu")
		(net "PHY_SCC_TO_IOC_C_42_DN")
	)
	(segment
		(start 165.254686 -31.692596)
		(end 165.232588 -31.692596)
		(width 0.0889)
		(layer "In2.Cu")
		(net "PHY_SCC_TO_IOC_C_42_DN")
	)
	(segment
		(start 152.90038 -38.424358)
		(end 152.125934 -38.611556)
		(width 0.1016)
		(layer "In2.Cu")
		(net "PHY_SCC_TO_IOC_C_42_DN")
	)
	(segment
		(start 166.99992 -31.999936)
		(end 166.59987 -31.599886)
		(width 0.0889)
		(layer "In2.Cu")
		(net "PHY_SCC_TO_IOC_C_42_DN")
	)
	(segment
		(start 164.091112 -31.692596)
		(end 163.552632 -32.231076)
		(width 0.1016)
		(layer "In2.Cu")
		(net "PHY_SCC_TO_IOC_C_42_DN")
	)
	(segment
		(start 163.552632 -32.231076)
		(end 160.781746 -32.231076)
		(width 0.1016)
		(layer "In2.Cu")
		(net "PHY_SCC_TO_IOC_C_42_DN")
	)
	(segment
		(start 151.172926 -38.271958)
		(end 151.232108 -37.993066)
		(width 0.1016)
		(layer "In2.Cu")
		(net "PHY_SCC_TO_IOC_C_42_DN")
	)
	(segment
		(start 153.332688 -38.143942)
		(end 152.90038 -38.424358)
		(width 0.1016)
		(layer "In2.Cu")
		(net "PHY_SCC_TO_IOC_C_42_DN")
	)
	(segment
		(start 152.125934 -38.611556)
		(end 151.275796 -38.430962)
		(width 0.1016)
		(layer "In2.Cu")
		(net "PHY_SCC_TO_IOC_C_42_DN")
	)
	(arc
		(start 151.191722 -38.37305)
		(mid 151.172285 -38.324375)
		(end 151.172926 -38.271958)
		(width 0.1016)
		(layer "In2.Cu")
		(net "PHY_SCC_TO_IOC_C_42_DN")
	)
	(arc
		(start 151.275796 -38.430962)
		(mid 151.227972 -38.410387)
		(end 151.191722 -38.37305)
		(width 0.1016)
		(layer "In2.Cu")
		(net "PHY_SCC_TO_IOC_C_42_DN")
	)
	(segment
		(start 165.800024 -30.80004)
		(end 166.19982 -31.199836)
		(width 0.12446)
		(layer "F.Cu")
		(net "PHY_SCC_TO_IOC_C_41_DP")
	)
	(segment
		(start 148.728176 -35.754056)
		(end 148.928328 -35.79876)
		(width 0.12446)
		(layer "F.Cu")
		(net "PHY_SCC_TO_IOC_C_41_DP")
	)
	(segment
		(start 148.928328 -35.79876)
		(end 148.931376 -35.799522)
		(width 0.12446)
		(layer "F.Cu")
		(net "PHY_SCC_TO_IOC_C_41_DP")
	)
	(segment
		(start 149.187662 -35.974782)
		(end 149.132036 -36.225988)
		(width 0.12446)
		(layer "F.Cu")
		(net "PHY_SCC_TO_IOC_C_41_DP")
	)
	(segment
		(start 148.93163 -35.799522)
		(end 149.097238 -35.833558)
		(width 0.12446)
		(layer "F.Cu")
		(net "PHY_SCC_TO_IOC_C_41_DP")
	)
	(segment
		(start 149.097238 -35.833558)
		(end 149.101302 -35.83432)
		(width 0.12446)
		(layer "F.Cu")
		(net "PHY_SCC_TO_IOC_C_41_DP")
	)
	(segment
		(start 148.342858 -35.785552)
		(end 148.599144 -35.838638)
		(width 0.12446)
		(layer "F.Cu")
		(net "PHY_SCC_TO_IOC_C_41_DP")
	)
	(segment
		(start 148.599144 -35.838638)
		(end 148.728176 -35.754056)
		(width 0.12446)
		(layer "F.Cu")
		(net "PHY_SCC_TO_IOC_C_41_DP")
	)
	(segment
		(start 148.931376 -35.799522)
		(end 148.93163 -35.799522)
		(width 0.12446)
		(layer "F.Cu")
		(net "PHY_SCC_TO_IOC_C_41_DP")
	)
	(via
		(at 166.19982 -31.199836)
		(size 0.508)
		(drill 0.254)
		(layers "F.Cu" "B.Cu")
		(net "PHY_SCC_TO_IOC_C_41_DP")
	)
	(arc
		(start 149.101302 -35.83432)
		(mid 149.174798 -35.885883)
		(end 149.187662 -35.974782)
		(width 0.12446)
		(layer "F.Cu")
		(net "PHY_SCC_TO_IOC_C_41_DP")
	)
	(segment
		(start 158.915608 -31.751778)
		(end 157.490414 -32.677862)
		(width 0.1016)
		(layer "In2.Cu")
		(net "PHY_SCC_TO_IOC_C_41_DP")
	)
	(segment
		(start 150.442422 -36.044124)
		(end 149.347428 -35.843464)
		(width 0.1016)
		(layer "In2.Cu")
		(net "PHY_SCC_TO_IOC_C_41_DP")
	)
	(segment
		(start 149.33422 -35.840416)
		(end 149.33422 -35.84067)
		(width 0.1016)
		(layer "In2.Cu")
		(net "PHY_SCC_TO_IOC_C_41_DP")
	)
	(segment
		(start 150.47722 -36.036758)
		(end 150.442422 -36.044124)
		(width 0.1016)
		(layer "In2.Cu")
		(net "PHY_SCC_TO_IOC_C_41_DP")
	)
	(segment
		(start 150.477474 -36.036504)
		(end 150.476966 -36.036504)
		(width 0.1016)
		(layer "In2.Cu")
		(net "PHY_SCC_TO_IOC_C_41_DP")
	)
	(segment
		(start 166.077392 -30.958028)
		(end 165.758876 -30.958028)
		(width 0.1016)
		(layer "In2.Cu")
		(net "PHY_SCC_TO_IOC_C_41_DP")
	)
	(segment
		(start 153.21407 -35.455098)
		(end 150.477474 -36.036758)
		(width 0.1016)
		(layer "In2.Cu")
		(net "PHY_SCC_TO_IOC_C_41_DP")
	)
	(segment
		(start 149.191218 -35.946842)
		(end 149.132036 -36.225988)
		(width 0.1016)
		(layer "In2.Cu")
		(net "PHY_SCC_TO_IOC_C_41_DP")
	)
	(segment
		(start 150.476966 -36.036504)
		(end 150.47722 -36.036758)
		(width 0.1016)
		(layer "In2.Cu")
		(net "PHY_SCC_TO_IOC_C_41_DP")
	)
	(segment
		(start 166.19982 -31.199836)
		(end 166.19982 -31.08071)
		(width 0.1016)
		(layer "In2.Cu")
		(net "PHY_SCC_TO_IOC_C_41_DP")
	)
	(segment
		(start 165.758876 -30.958028)
		(end 165.509448 -30.7086)
		(width 0.1016)
		(layer "In2.Cu")
		(net "PHY_SCC_TO_IOC_C_41_DP")
	)
	(segment
		(start 165.509448 -30.7086)
		(end 163.823396 -30.7086)
		(width 0.1016)
		(layer "In2.Cu")
		(net "PHY_SCC_TO_IOC_C_41_DP")
	)
	(segment
		(start 157.490414 -32.677862)
		(end 153.21407 -35.455098)
		(width 0.1016)
		(layer "In2.Cu")
		(net "PHY_SCC_TO_IOC_C_41_DP")
	)
	(segment
		(start 149.33422 -35.84067)
		(end 149.26056 -35.855402)
		(width 0.1016)
		(layer "In2.Cu")
		(net "PHY_SCC_TO_IOC_C_41_DP")
	)
	(segment
		(start 150.477474 -36.036758)
		(end 150.477474 -36.036504)
		(width 0.1016)
		(layer "In2.Cu")
		(net "PHY_SCC_TO_IOC_C_41_DP")
	)
	(segment
		(start 149.26056 -35.855402)
		(end 149.249384 -35.862768)
		(width 0.1016)
		(layer "In2.Cu")
		(net "PHY_SCC_TO_IOC_C_41_DP")
	)
	(segment
		(start 163.823396 -30.7086)
		(end 158.915608 -31.751778)
		(width 0.1016)
		(layer "In2.Cu")
		(net "PHY_SCC_TO_IOC_C_41_DP")
	)
	(arc
		(start 149.249384 -35.862768)
		(mid 149.21193 -35.899022)
		(end 149.191218 -35.946842)
		(width 0.1016)
		(layer "In2.Cu")
		(net "PHY_SCC_TO_IOC_C_41_DP")
	)
	(arc
		(start 166.163752 -30.993842)
		(mid 166.124144 -30.967313)
		(end 166.077392 -30.958028)
		(width 0.1016)
		(layer "In2.Cu")
		(net "PHY_SCC_TO_IOC_C_41_DP")
	)
	(arc
		(start 149.347428 -35.843464)
		(mid 149.340812 -35.841992)
		(end 149.33422 -35.840416)
		(width 0.1016)
		(layer "In2.Cu")
		(net "PHY_SCC_TO_IOC_C_41_DP")
	)
	(arc
		(start 166.19982 -31.08071)
		(mid 166.190447 -31.033679)
		(end 166.163752 -30.993842)
		(width 0.1016)
		(layer "In2.Cu")
		(net "PHY_SCC_TO_IOC_C_41_DP")
	)
	(segment
		(start 149.017228 -35.402012)
		(end 148.750782 -35.342068)
		(width 0.12446)
		(layer "F.Cu")
		(net "PHY_SCC_TO_IOC_C_41_DN")
	)
	(segment
		(start 149.142704 -35.42792)
		(end 149.017228 -35.402012)
		(width 0.12446)
		(layer "F.Cu")
		(net "PHY_SCC_TO_IOC_C_41_DN")
	)
	(segment
		(start 148.698458 -35.26282)
		(end 148.46427 -35.214306)
		(width 0.12446)
		(layer "F.Cu")
		(net "PHY_SCC_TO_IOC_C_41_DN")
	)
	(segment
		(start 166.59987 -30.80004)
		(end 166.19982 -30.39999)
		(width 0.12446)
		(layer "F.Cu")
		(net "PHY_SCC_TO_IOC_C_41_DN")
	)
	(segment
		(start 148.750782 -35.342068)
		(end 148.698458 -35.26282)
		(width 0.12446)
		(layer "F.Cu")
		(net "PHY_SCC_TO_IOC_C_41_DN")
	)
	(segment
		(start 149.36978 -35.10788)
		(end 149.315678 -35.35934)
		(width 0.12446)
		(layer "F.Cu")
		(net "PHY_SCC_TO_IOC_C_41_DN")
	)
	(via
		(at 166.19982 -30.39999)
		(size 0.508)
		(drill 0.254)
		(layers "F.Cu" "B.Cu")
		(net "PHY_SCC_TO_IOC_C_41_DN")
	)
	(arc
		(start 149.315678 -35.35934)
		(mid 149.239434 -35.419436)
		(end 149.142704 -35.42792)
		(width 0.12446)
		(layer "F.Cu")
		(net "PHY_SCC_TO_IOC_C_41_DN")
	)
	(segment
		(start 163.791138 -30.4038)
		(end 158.79699 -31.465266)
		(width 0.1016)
		(layer "In2.Cu")
		(net "PHY_SCC_TO_IOC_C_41_DN")
	)
	(segment
		(start 153.095452 -35.168586)
		(end 150.438104 -35.733228)
		(width 0.1016)
		(layer "In2.Cu")
		(net "PHY_SCC_TO_IOC_C_41_DN")
	)
	(segment
		(start 150.438104 -35.733228)
		(end 149.40915 -35.54476)
		(width 0.1016)
		(layer "In2.Cu")
		(net "PHY_SCC_TO_IOC_C_41_DN")
	)
	(segment
		(start 165.885368 -30.653228)
		(end 165.63594 -30.4038)
		(width 0.1016)
		(layer "In2.Cu")
		(net "PHY_SCC_TO_IOC_C_41_DN")
	)
	(segment
		(start 155.899104 -33.34766)
		(end 153.095452 -35.168586)
		(width 0.1016)
		(layer "In2.Cu")
		(net "PHY_SCC_TO_IOC_C_41_DN")
	)
	(segment
		(start 165.63594 -30.4038)
		(end 163.791138 -30.4038)
		(width 0.1016)
		(layer "In2.Cu")
		(net "PHY_SCC_TO_IOC_C_41_DN")
	)
	(segment
		(start 158.79699 -31.465266)
		(end 155.899104 -33.34766)
		(width 0.1016)
		(layer "In2.Cu")
		(net "PHY_SCC_TO_IOC_C_41_DN")
	)
	(segment
		(start 149.310598 -35.386772)
		(end 149.36978 -35.10788)
		(width 0.1016)
		(layer "In2.Cu")
		(net "PHY_SCC_TO_IOC_C_41_DN")
	)
	(segment
		(start 166.19982 -30.39999)
		(end 166.19982 -30.552136)
		(width 0.1016)
		(layer "In2.Cu")
		(net "PHY_SCC_TO_IOC_C_41_DN")
	)
	(segment
		(start 166.111936 -30.653228)
		(end 165.885368 -30.653228)
		(width 0.1016)
		(layer "In2.Cu")
		(net "PHY_SCC_TO_IOC_C_41_DN")
	)
	(arc
		(start 166.19982 -30.552136)
		(mid 166.178955 -30.622779)
		(end 166.111936 -30.653228)
		(width 0.1016)
		(layer "In2.Cu")
		(net "PHY_SCC_TO_IOC_C_41_DN")
	)
	(arc
		(start 149.329394 -35.487864)
		(mid 149.309957 -35.439189)
		(end 149.310598 -35.386772)
		(width 0.1016)
		(layer "In2.Cu")
		(net "PHY_SCC_TO_IOC_C_41_DN")
	)
	(arc
		(start 149.40915 -35.54476)
		(mid 149.363837 -35.523915)
		(end 149.329394 -35.487864)
		(width 0.1016)
		(layer "In2.Cu")
		(net "PHY_SCC_TO_IOC_C_41_DN")
	)
	(segment
		(start 145.88744 -33.005522)
		(end 146.25193 -33.080452)
		(width 0.12446)
		(layer "F.Cu")
		(net "PHY_SCC_TO_IOC_C_40_DP")
	)
	(segment
		(start 165.800024 -29.999686)
		(end 165.800024 -29.99994)
		(width 0.12446)
		(layer "F.Cu")
		(net "PHY_SCC_TO_IOC_C_40_DP")
	)
	(segment
		(start 146.25193 -33.080452)
		(end 146.255994 -33.081214)
		(width 0.12446)
		(layer "F.Cu")
		(net "PHY_SCC_TO_IOC_C_40_DP")
	)
	(segment
		(start 145.522442 -33.03778)
		(end 145.735802 -33.085532)
		(width 0.12446)
		(layer "F.Cu")
		(net "PHY_SCC_TO_IOC_C_40_DP")
	)
	(segment
		(start 145.735802 -33.085532)
		(end 145.88744 -33.005522)
		(width 0.12446)
		(layer "F.Cu")
		(net "PHY_SCC_TO_IOC_C_40_DP")
	)
	(segment
		(start 166.19982 -29.59989)
		(end 165.800024 -29.999686)
		(width 0.12446)
		(layer "F.Cu")
		(net "PHY_SCC_TO_IOC_C_40_DP")
	)
	(segment
		(start 146.342354 -33.221676)
		(end 146.286728 -33.472882)
		(width 0.12446)
		(layer "F.Cu")
		(net "PHY_SCC_TO_IOC_C_40_DP")
	)
	(via
		(at 166.19982 -29.59989)
		(size 0.508)
		(drill 0.254)
		(layers "F.Cu" "B.Cu")
		(net "PHY_SCC_TO_IOC_C_40_DP")
	)
	(arc
		(start 146.255994 -33.081214)
		(mid 146.32949 -33.132777)
		(end 146.342354 -33.221676)
		(width 0.12446)
		(layer "F.Cu")
		(net "PHY_SCC_TO_IOC_C_40_DP")
	)
	(segment
		(start 165.346634 -29.44749)
		(end 165.368732 -29.44749)
		(width 0.0889)
		(layer "In2.Cu")
		(net "PHY_SCC_TO_IOC_C_40_DP")
	)
	(segment
		(start 151.662638 -33.386268)
		(end 151.80945 -33.160462)
		(width 0.1016)
		(layer "In2.Cu")
		(net "PHY_SCC_TO_IOC_C_40_DP")
	)
	(segment
		(start 152.333452 -33.243774)
		(end 152.631648 -33.180274)
		(width 0.1016)
		(layer "In2.Cu")
		(net "PHY_SCC_TO_IOC_C_40_DP")
	)
	(segment
		(start 152.107646 -33.096962)
		(end 152.333452 -33.243774)
		(width 0.1016)
		(layer "In2.Cu")
		(net "PHY_SCC_TO_IOC_C_40_DP")
	)
	(segment
		(start 161.31794 -29.877004)
		(end 161.544 -30.023816)
		(width 0.1016)
		(layer "In2.Cu")
		(net "PHY_SCC_TO_IOC_C_40_DP")
	)
	(segment
		(start 165.425882 -29.39034)
		(end 165.99027 -29.39034)
		(width 0.0889)
		(layer "In2.Cu")
		(net "PHY_SCC_TO_IOC_C_40_DP")
	)
	(segment
		(start 160.34893 -30.082998)
		(end 160.57499 -30.22981)
		(width 0.1016)
		(layer "In2.Cu")
		(net "PHY_SCC_TO_IOC_C_40_DP")
	)
	(segment
		(start 149.321012 -33.68929)
		(end 151.138636 -33.302956)
		(width 0.1016)
		(layer "In2.Cu")
		(net "PHY_SCC_TO_IOC_C_40_DP")
	)
	(segment
		(start 146.404076 -33.109662)
		(end 146.415252 -33.102296)
		(width 0.1016)
		(layer "In2.Cu")
		(net "PHY_SCC_TO_IOC_C_40_DP")
	)
	(segment
		(start 151.138636 -33.302956)
		(end 151.364696 -33.449768)
		(width 0.1016)
		(layer "In2.Cu")
		(net "PHY_SCC_TO_IOC_C_40_DP")
	)
	(segment
		(start 165.368732 -29.44749)
		(end 165.425882 -29.39034)
		(width 0.0889)
		(layer "In2.Cu")
		(net "PHY_SCC_TO_IOC_C_40_DP")
	)
	(segment
		(start 148.913088 -33.603438)
		(end 149.321012 -33.68929)
		(width 0.1016)
		(layer "In2.Cu")
		(net "PHY_SCC_TO_IOC_C_40_DP")
	)
	(segment
		(start 163.338764 -29.44749)
		(end 165.346634 -29.44749)
		(width 0.1016)
		(layer "In2.Cu")
		(net "PHY_SCC_TO_IOC_C_40_DP")
	)
	(segment
		(start 153.076656 -32.890968)
		(end 153.302462 -33.03778)
		(width 0.1016)
		(layer "In2.Cu")
		(net "PHY_SCC_TO_IOC_C_40_DP")
	)
	(segment
		(start 146.49196 -33.088072)
		(end 147.024852 -33.201356)
		(width 0.1016)
		(layer "In2.Cu")
		(net "PHY_SCC_TO_IOC_C_40_DP")
	)
	(segment
		(start 152.631648 -33.180274)
		(end 152.77846 -32.954468)
		(width 0.1016)
		(layer "In2.Cu")
		(net "PHY_SCC_TO_IOC_C_40_DP")
	)
	(segment
		(start 151.364696 -33.449768)
		(end 151.662638 -33.386268)
		(width 0.1016)
		(layer "In2.Cu")
		(net "PHY_SCC_TO_IOC_C_40_DP")
	)
	(segment
		(start 160.873186 -30.16631)
		(end 161.019744 -29.940504)
		(width 0.1016)
		(layer "In2.Cu")
		(net "PHY_SCC_TO_IOC_C_40_DP")
	)
	(segment
		(start 161.988754 -29.73451)
		(end 163.338764 -29.44749)
		(width 0.1016)
		(layer "In2.Cu")
		(net "PHY_SCC_TO_IOC_C_40_DP")
	)
	(segment
		(start 153.302462 -33.03778)
		(end 153.600658 -32.97428)
		(width 0.1016)
		(layer "In2.Cu")
		(net "PHY_SCC_TO_IOC_C_40_DP")
	)
	(segment
		(start 153.600658 -32.97428)
		(end 153.74747 -32.748474)
		(width 0.1016)
		(layer "In2.Cu")
		(net "PHY_SCC_TO_IOC_C_40_DP")
	)
	(segment
		(start 147.024852 -33.201356)
		(end 148.913088 -33.603438)
		(width 0.1016)
		(layer "In2.Cu")
		(net "PHY_SCC_TO_IOC_C_40_DP")
	)
	(segment
		(start 161.544 -30.023816)
		(end 161.842196 -29.960316)
		(width 0.1016)
		(layer "In2.Cu")
		(net "PHY_SCC_TO_IOC_C_40_DP")
	)
	(segment
		(start 151.80945 -33.160462)
		(end 152.107646 -33.096962)
		(width 0.1016)
		(layer "In2.Cu")
		(net "PHY_SCC_TO_IOC_C_40_DP")
	)
	(segment
		(start 153.74747 -32.748474)
		(end 155.76804 -32.31896)
		(width 0.1016)
		(layer "In2.Cu")
		(net "PHY_SCC_TO_IOC_C_40_DP")
	)
	(segment
		(start 160.57499 -30.22981)
		(end 160.873186 -30.16631)
		(width 0.1016)
		(layer "In2.Cu")
		(net "PHY_SCC_TO_IOC_C_40_DP")
	)
	(segment
		(start 161.842196 -29.960316)
		(end 161.988754 -29.73451)
		(width 0.1016)
		(layer "In2.Cu")
		(net "PHY_SCC_TO_IOC_C_40_DP")
	)
	(segment
		(start 152.77846 -32.954468)
		(end 153.076656 -32.890968)
		(width 0.1016)
		(layer "In2.Cu")
		(net "PHY_SCC_TO_IOC_C_40_DP")
	)
	(segment
		(start 155.76804 -32.31896)
		(end 158.657036 -30.442662)
		(width 0.1016)
		(layer "In2.Cu")
		(net "PHY_SCC_TO_IOC_C_40_DP")
	)
	(segment
		(start 165.99027 -29.39034)
		(end 166.19982 -29.59989)
		(width 0.0889)
		(layer "In2.Cu")
		(net "PHY_SCC_TO_IOC_C_40_DP")
	)
	(segment
		(start 146.286728 -33.472882)
		(end 146.34591 -33.193736)
		(width 0.1016)
		(layer "In2.Cu")
		(net "PHY_SCC_TO_IOC_C_40_DP")
	)
	(segment
		(start 161.019744 -29.940504)
		(end 161.31794 -29.877004)
		(width 0.1016)
		(layer "In2.Cu")
		(net "PHY_SCC_TO_IOC_C_40_DP")
	)
	(segment
		(start 158.657036 -30.442662)
		(end 160.34893 -30.082998)
		(width 0.1016)
		(layer "In2.Cu")
		(net "PHY_SCC_TO_IOC_C_40_DP")
	)
	(arc
		(start 146.34591 -33.193736)
		(mid 146.366677 -33.145954)
		(end 146.404076 -33.109662)
		(width 0.1016)
		(layer "In2.Cu")
		(net "PHY_SCC_TO_IOC_C_40_DP")
	)
	(arc
		(start 146.415252 -33.102296)
		(mid 146.452185 -33.087554)
		(end 146.49196 -33.088072)
		(width 0.1016)
		(layer "In2.Cu")
		(net "PHY_SCC_TO_IOC_C_40_DP")
	)
	(segment
		(start 145.890996 -32.513778)
		(end 145.965164 -32.606488)
		(width 0.12446)
		(layer "F.Cu")
		(net "PHY_SCC_TO_IOC_C_40_DN")
	)
	(segment
		(start 145.965164 -32.606488)
		(end 145.969228 -32.60725)
		(width 0.12446)
		(layer "F.Cu")
		(net "PHY_SCC_TO_IOC_C_40_DN")
	)
	(segment
		(start 145.643854 -32.46628)
		(end 145.890996 -32.513778)
		(width 0.12446)
		(layer "F.Cu")
		(net "PHY_SCC_TO_IOC_C_40_DN")
	)
	(segment
		(start 166.59987 -29.99994)
		(end 166.999666 -29.600144)
		(width 0.1016)
		(layer "F.Cu")
		(net "PHY_SCC_TO_IOC_C_40_DN")
	)
	(segment
		(start 146.47037 -32.606234)
		(end 146.524472 -32.354774)
		(width 0.12446)
		(layer "F.Cu")
		(net "PHY_SCC_TO_IOC_C_40_DN")
	)
	(segment
		(start 145.969228 -32.60725)
		(end 146.297396 -32.674814)
		(width 0.12446)
		(layer "F.Cu")
		(net "PHY_SCC_TO_IOC_C_40_DN")
	)
	(via
		(at 166.999666 -29.600144)
		(size 0.508)
		(drill 0.254)
		(layers "F.Cu" "B.Cu")
		(net "PHY_SCC_TO_IOC_C_40_DN")
	)
	(arc
		(start 146.297396 -32.674814)
		(mid 146.394152 -32.666395)
		(end 146.47037 -32.606234)
		(width 0.12446)
		(layer "F.Cu")
		(net "PHY_SCC_TO_IOC_C_40_DN")
	)
	(segment
		(start 149.321012 -33.377632)
		(end 148.976334 -33.305242)
		(width 0.1016)
		(layer "In2.Cu")
		(net "PHY_SCC_TO_IOC_C_40_DN")
	)
	(segment
		(start 163.306506 -29.14269)
		(end 158.538418 -30.15615)
		(width 0.1016)
		(layer "In2.Cu")
		(net "PHY_SCC_TO_IOC_C_40_DN")
	)
	(segment
		(start 147.088352 -32.90316)
		(end 146.56816 -32.79267)
		(width 0.1016)
		(layer "In2.Cu")
		(net "PHY_SCC_TO_IOC_C_40_DN")
	)
	(segment
		(start 165.368732 -29.14269)
		(end 165.346634 -29.14269)
		(width 0.0889)
		(layer "In2.Cu")
		(net "PHY_SCC_TO_IOC_C_40_DN")
	)
	(segment
		(start 166.999666 -29.600144)
		(end 166.599362 -29.19984)
		(width 0.0889)
		(layer "In2.Cu")
		(net "PHY_SCC_TO_IOC_C_40_DN")
	)
	(segment
		(start 166.599362 -29.19984)
		(end 165.425882 -29.19984)
		(width 0.0889)
		(layer "In2.Cu")
		(net "PHY_SCC_TO_IOC_C_40_DN")
	)
	(segment
		(start 165.425882 -29.19984)
		(end 165.368732 -29.14269)
		(width 0.0889)
		(layer "In2.Cu")
		(net "PHY_SCC_TO_IOC_C_40_DN")
	)
	(segment
		(start 146.46529 -32.633666)
		(end 146.524472 -32.354774)
		(width 0.1016)
		(layer "In2.Cu")
		(net "PHY_SCC_TO_IOC_C_40_DN")
	)
	(segment
		(start 155.649422 -32.032448)
		(end 149.321012 -33.377632)
		(width 0.1016)
		(layer "In2.Cu")
		(net "PHY_SCC_TO_IOC_C_40_DN")
	)
	(segment
		(start 148.976334 -33.305242)
		(end 147.088352 -32.90316)
		(width 0.1016)
		(layer "In2.Cu")
		(net "PHY_SCC_TO_IOC_C_40_DN")
	)
	(segment
		(start 158.538418 -30.15615)
		(end 155.649422 -32.032448)
		(width 0.1016)
		(layer "In2.Cu")
		(net "PHY_SCC_TO_IOC_C_40_DN")
	)
	(segment
		(start 165.346634 -29.14269)
		(end 163.306506 -29.14269)
		(width 0.1016)
		(layer "In2.Cu")
		(net "PHY_SCC_TO_IOC_C_40_DN")
	)
	(arc
		(start 146.56816 -32.79267)
		(mid 146.520336 -32.772095)
		(end 146.484086 -32.734758)
		(width 0.1016)
		(layer "In2.Cu")
		(net "PHY_SCC_TO_IOC_C_40_DN")
	)
	(arc
		(start 146.484086 -32.734758)
		(mid 146.464649 -32.686083)
		(end 146.46529 -32.633666)
		(width 0.1016)
		(layer "In2.Cu")
		(net "PHY_SCC_TO_IOC_C_40_DN")
	)
	(segment
		(start 131.0513 -60.080906)
		(end 130.189224 -60.080906)
		(width 0.0889)
		(layer "F.Cu")
		(net "PHY_SCC_TO_IOC_47_DP")
	)
	(segment
		(start 130.209544 -60.500006)
		(end 130.50012 -60.500006)
		(width 0.0889)
		(layer "F.Cu")
		(net "PHY_SCC_TO_IOC_47_DP")
	)
	(segment
		(start 144.581626 -55.166006)
		(end 144.216374 -55.24373)
		(width 0.12446)
		(layer "F.Cu")
		(net "PHY_SCC_TO_IOC_47_DP")
	)
	(segment
		(start 145.154142 -54.769004)
		(end 144.78889 -54.846728)
		(width 0.12446)
		(layer "F.Cu")
		(net "PHY_SCC_TO_IOC_47_DP")
	)
	(segment
		(start 144.216374 -55.24373)
		(end 143.897096 -55.036212)
		(width 0.12446)
		(layer "F.Cu")
		(net "PHY_SCC_TO_IOC_47_DP")
	)
	(segment
		(start 134.772654 -60.21705)
		(end 133.243828 -60.541408)
		(width 0.12446)
		(layer "F.Cu")
		(net "PHY_SCC_TO_IOC_47_DP")
	)
	(segment
		(start 133.243828 -60.541408)
		(end 132.24891 -60.541408)
		(width 0.12446)
		(layer "F.Cu")
		(net "PHY_SCC_TO_IOC_47_DP")
	)
	(segment
		(start 132.24891 -60.541408)
		(end 132.226812 -60.541408)
		(width 0.0889)
		(layer "F.Cu")
		(net "PHY_SCC_TO_IOC_47_DP")
	)
	(segment
		(start 143.897096 -55.036212)
		(end 142.18031 -55.40121)
		(width 0.12446)
		(layer "F.Cu")
		(net "PHY_SCC_TO_IOC_47_DP")
	)
	(segment
		(start 142.18031 -55.40121)
		(end 134.772654 -60.21705)
		(width 0.12446)
		(layer "F.Cu")
		(net "PHY_SCC_TO_IOC_47_DP")
	)
	(segment
		(start 144.78889 -54.846728)
		(end 144.581626 -55.166006)
		(width 0.12446)
		(layer "F.Cu")
		(net "PHY_SCC_TO_IOC_47_DP")
	)
	(segment
		(start 147.683728 -54.862984)
		(end 147.604226 -54.740556)
		(width 0.12446)
		(layer "F.Cu")
		(net "PHY_SCC_TO_IOC_47_DP")
	)
	(segment
		(start 131.397248 -60.426854)
		(end 131.0513 -60.080906)
		(width 0.0889)
		(layer "F.Cu")
		(net "PHY_SCC_TO_IOC_47_DP")
	)
	(segment
		(start 132.226812 -60.541408)
		(end 132.112258 -60.426854)
		(width 0.0889)
		(layer "F.Cu")
		(net "PHY_SCC_TO_IOC_47_DP")
	)
	(segment
		(start 130.095244 -60.174886)
		(end 130.095244 -60.385706)
		(width 0.0889)
		(layer "F.Cu")
		(net "PHY_SCC_TO_IOC_47_DP")
	)
	(segment
		(start 146.045936 -54.57952)
		(end 145.838672 -54.898798)
		(width 0.12446)
		(layer "F.Cu")
		(net "PHY_SCC_TO_IOC_47_DP")
	)
	(segment
		(start 132.112258 -60.426854)
		(end 131.397248 -60.426854)
		(width 0.0889)
		(layer "F.Cu")
		(net "PHY_SCC_TO_IOC_47_DP")
	)
	(segment
		(start 145.838672 -54.898798)
		(end 145.47342 -54.976522)
		(width 0.12446)
		(layer "F.Cu")
		(net "PHY_SCC_TO_IOC_47_DP")
	)
	(segment
		(start 147.604226 -54.740556)
		(end 146.446494 -54.494176)
		(width 0.12446)
		(layer "F.Cu")
		(net "PHY_SCC_TO_IOC_47_DP")
	)
	(segment
		(start 146.446494 -54.494176)
		(end 146.045936 -54.57952)
		(width 0.12446)
		(layer "F.Cu")
		(net "PHY_SCC_TO_IOC_47_DP")
	)
	(segment
		(start 148.041868 -54.939184)
		(end 147.683728 -54.862984)
		(width 0.12446)
		(layer "F.Cu")
		(net "PHY_SCC_TO_IOC_47_DP")
	)
	(segment
		(start 145.47342 -54.976522)
		(end 145.154142 -54.769004)
		(width 0.12446)
		(layer "F.Cu")
		(net "PHY_SCC_TO_IOC_47_DP")
	)
	(arc
		(start 130.095244 -60.385706)
		(mid 130.128722 -60.466528)
		(end 130.209544 -60.500006)
		(width 0.0889)
		(layer "F.Cu")
		(net "PHY_SCC_TO_IOC_47_DP")
	)
	(arc
		(start 130.189224 -60.080906)
		(mid 130.12277 -60.108432)
		(end 130.095244 -60.174886)
		(width 0.0889)
		(layer "F.Cu")
		(net "PHY_SCC_TO_IOC_47_DP")
	)
	(segment
		(start 146.44624 -54.078378)
		(end 146.046952 -54.163722)
		(width 0.12446)
		(layer "F.Cu")
		(net "PHY_SCC_TO_IOC_47_DN")
	)
	(segment
		(start 134.614412 -59.835034)
		(end 133.200394 -60.135008)
		(width 0.12446)
		(layer "F.Cu")
		(net "PHY_SCC_TO_IOC_47_DN")
	)
	(segment
		(start 147.717002 -54.348634)
		(end 146.44624 -54.078378)
		(width 0.12446)
		(layer "F.Cu")
		(net "PHY_SCC_TO_IOC_47_DN")
	)
	(segment
		(start 142.021814 -55.019194)
		(end 134.614412 -59.835034)
		(width 0.12446)
		(layer "F.Cu")
		(net "PHY_SCC_TO_IOC_47_DN")
	)
	(segment
		(start 132.125466 -60.236354)
		(end 131.476242 -60.236354)
		(width 0.0889)
		(layer "F.Cu")
		(net "PHY_SCC_TO_IOC_47_DN")
	)
	(segment
		(start 129.904744 -60.174886)
		(end 129.904744 -60.385706)
		(width 0.0889)
		(layer "F.Cu")
		(net "PHY_SCC_TO_IOC_47_DN")
	)
	(segment
		(start 131.130294 -59.890406)
		(end 130.189224 -59.890406)
		(width 0.0889)
		(layer "F.Cu")
		(net "PHY_SCC_TO_IOC_47_DN")
	)
	(segment
		(start 148.163534 -54.367938)
		(end 147.80514 -54.291484)
		(width 0.12446)
		(layer "F.Cu")
		(net "PHY_SCC_TO_IOC_47_DN")
	)
	(segment
		(start 132.24891 -60.135008)
		(end 132.226812 -60.135008)
		(width 0.0889)
		(layer "F.Cu")
		(net "PHY_SCC_TO_IOC_47_DN")
	)
	(segment
		(start 147.80514 -54.291484)
		(end 147.717002 -54.348634)
		(width 0.12446)
		(layer "F.Cu")
		(net "PHY_SCC_TO_IOC_47_DN")
	)
	(segment
		(start 129.790444 -60.500006)
		(end 129.500122 -60.500006)
		(width 0.0889)
		(layer "F.Cu")
		(net "PHY_SCC_TO_IOC_47_DN")
	)
	(segment
		(start 131.476242 -60.236354)
		(end 131.130294 -59.890406)
		(width 0.0889)
		(layer "F.Cu")
		(net "PHY_SCC_TO_IOC_47_DN")
	)
	(segment
		(start 146.046952 -54.163722)
		(end 142.021814 -55.019194)
		(width 0.12446)
		(layer "F.Cu")
		(net "PHY_SCC_TO_IOC_47_DN")
	)
	(segment
		(start 132.226812 -60.135008)
		(end 132.125466 -60.236354)
		(width 0.0889)
		(layer "F.Cu")
		(net "PHY_SCC_TO_IOC_47_DN")
	)
	(segment
		(start 133.200394 -60.135008)
		(end 132.24891 -60.135008)
		(width 0.12446)
		(layer "F.Cu")
		(net "PHY_SCC_TO_IOC_47_DN")
	)
	(arc
		(start 129.904744 -60.385706)
		(mid 129.871266 -60.466528)
		(end 129.790444 -60.500006)
		(width 0.0889)
		(layer "F.Cu")
		(net "PHY_SCC_TO_IOC_47_DN")
	)
	(arc
		(start 130.189224 -59.890406)
		(mid 129.988066 -59.973728)
		(end 129.904744 -60.174886)
		(width 0.0889)
		(layer "F.Cu")
		(net "PHY_SCC_TO_IOC_47_DN")
	)
	(segment
		(start 139.022836 -55.598822)
		(end 138.819382 -55.912004)
		(width 0.12446)
		(layer "F.Cu")
		(net "PHY_SCC_TO_IOC_46_DP")
	)
	(segment
		(start 129.095246 -59.278012)
		(end 129.095246 -59.385708)
		(width 0.0889)
		(layer "F.Cu")
		(net "PHY_SCC_TO_IOC_46_DP")
	)
	(segment
		(start 138.447018 -55.990998)
		(end 138.049254 -56.603392)
		(width 0.12446)
		(layer "F.Cu")
		(net "PHY_SCC_TO_IOC_46_DP")
	)
	(segment
		(start 138.819382 -55.912004)
		(end 138.447018 -55.990998)
		(width 0.12446)
		(layer "F.Cu")
		(net "PHY_SCC_TO_IOC_46_DP")
	)
	(segment
		(start 142.251684 -51.529234)
		(end 140.684758 -52.545996)
		(width 0.12446)
		(layer "F.Cu")
		(net "PHY_SCC_TO_IOC_46_DP")
	)
	(segment
		(start 139.147042 -54.913276)
		(end 138.943588 -55.226458)
		(width 0.12446)
		(layer "F.Cu")
		(net "PHY_SCC_TO_IOC_46_DP")
	)
	(segment
		(start 139.643612 -54.148736)
		(end 139.72286 -54.5211)
		(width 0.12446)
		(layer "F.Cu")
		(net "PHY_SCC_TO_IOC_46_DP")
	)
	(segment
		(start 140.684758 -52.545996)
		(end 139.643612 -54.148736)
		(width 0.12446)
		(layer "F.Cu")
		(net "PHY_SCC_TO_IOC_46_DP")
	)
	(segment
		(start 138.943588 -55.226458)
		(end 139.022836 -55.598822)
		(width 0.12446)
		(layer "F.Cu")
		(net "PHY_SCC_TO_IOC_46_DP")
	)
	(segment
		(start 146.605752 -50.78222)
		(end 146.185128 -50.692558)
		(width 0.12446)
		(layer "F.Cu")
		(net "PHY_SCC_TO_IOC_46_DP")
	)
	(segment
		(start 134.415784 -58.990992)
		(end 133.489192 -59.188858)
		(width 0.12446)
		(layer "F.Cu")
		(net "PHY_SCC_TO_IOC_46_DP")
	)
	(segment
		(start 146.185128 -50.692558)
		(end 142.251684 -51.529234)
		(width 0.12446)
		(layer "F.Cu")
		(net "PHY_SCC_TO_IOC_46_DP")
	)
	(segment
		(start 146.685762 -50.904902)
		(end 146.605752 -50.78222)
		(width 0.12446)
		(layer "F.Cu")
		(net "PHY_SCC_TO_IOC_46_DP")
	)
	(segment
		(start 139.72286 -54.5211)
		(end 139.519406 -54.834282)
		(width 0.12446)
		(layer "F.Cu")
		(net "PHY_SCC_TO_IOC_46_DP")
	)
	(segment
		(start 138.049254 -56.603392)
		(end 134.415784 -58.990992)
		(width 0.12446)
		(layer "F.Cu")
		(net "PHY_SCC_TO_IOC_46_DP")
	)
	(segment
		(start 131.818126 -59.188858)
		(end 131.796028 -59.188858)
		(width 0.0889)
		(layer "F.Cu")
		(net "PHY_SCC_TO_IOC_46_DP")
	)
	(segment
		(start 133.489192 -59.188858)
		(end 131.818126 -59.188858)
		(width 0.12446)
		(layer "F.Cu")
		(net "PHY_SCC_TO_IOC_46_DP")
	)
	(segment
		(start 139.519406 -54.834282)
		(end 139.147042 -54.913276)
		(width 0.12446)
		(layer "F.Cu")
		(net "PHY_SCC_TO_IOC_46_DP")
	)
	(segment
		(start 147.043902 -50.981102)
		(end 146.685762 -50.904902)
		(width 0.12446)
		(layer "F.Cu")
		(net "PHY_SCC_TO_IOC_46_DP")
	)
	(segment
		(start 131.796028 -59.188858)
		(end 131.688078 -59.080908)
		(width 0.0889)
		(layer "F.Cu")
		(net "PHY_SCC_TO_IOC_46_DP")
	)
	(segment
		(start 131.688078 -59.080908)
		(end 129.29235 -59.080908)
		(width 0.0889)
		(layer "F.Cu")
		(net "PHY_SCC_TO_IOC_46_DP")
	)
	(segment
		(start 129.209546 -59.500008)
		(end 129.500122 -59.500008)
		(width 0.0889)
		(layer "F.Cu")
		(net "PHY_SCC_TO_IOC_46_DP")
	)
	(arc
		(start 129.29235 -59.080908)
		(mid 129.152976 -59.138638)
		(end 129.095246 -59.278012)
		(width 0.0889)
		(layer "F.Cu")
		(net "PHY_SCC_TO_IOC_46_DP")
	)
	(arc
		(start 129.095246 -59.385708)
		(mid 129.128724 -59.46653)
		(end 129.209546 -59.500008)
		(width 0.0889)
		(layer "F.Cu")
		(net "PHY_SCC_TO_IOC_46_DP")
	)
	(segment
		(start 128.790446 -59.500008)
		(end 128.500124 -59.500008)
		(width 0.0889)
		(layer "F.Cu")
		(net "PHY_SCC_TO_IOC_46_DN")
	)
	(segment
		(start 128.904746 -59.278012)
		(end 128.904746 -59.385708)
		(width 0.0889)
		(layer "F.Cu")
		(net "PHY_SCC_TO_IOC_46_DN")
	)
	(segment
		(start 147.165314 -50.409856)
		(end 146.807174 -50.333402)
		(width 0.12446)
		(layer "F.Cu")
		(net "PHY_SCC_TO_IOC_46_DN")
	)
	(segment
		(start 140.39088 -52.251864)
		(end 137.754868 -56.31053)
		(width 0.12446)
		(layer "F.Cu")
		(net "PHY_SCC_TO_IOC_46_DN")
	)
	(segment
		(start 133.446266 -58.782458)
		(end 131.818126 -58.782458)
		(width 0.12446)
		(layer "F.Cu")
		(net "PHY_SCC_TO_IOC_46_DN")
	)
	(segment
		(start 146.719036 -50.390552)
		(end 146.185128 -50.277014)
		(width 0.12446)
		(layer "F.Cu")
		(net "PHY_SCC_TO_IOC_46_DN")
	)
	(segment
		(start 146.807174 -50.333402)
		(end 146.719036 -50.390552)
		(width 0.12446)
		(layer "F.Cu")
		(net "PHY_SCC_TO_IOC_46_DN")
	)
	(segment
		(start 137.754868 -56.31053)
		(end 134.256272 -58.609484)
		(width 0.12446)
		(layer "F.Cu")
		(net "PHY_SCC_TO_IOC_46_DN")
	)
	(segment
		(start 131.796028 -58.782458)
		(end 131.688078 -58.890408)
		(width 0.0889)
		(layer "F.Cu")
		(net "PHY_SCC_TO_IOC_46_DN")
	)
	(segment
		(start 131.818126 -58.782458)
		(end 131.796028 -58.782458)
		(width 0.0889)
		(layer "F.Cu")
		(net "PHY_SCC_TO_IOC_46_DN")
	)
	(segment
		(start 131.688078 -58.890408)
		(end 129.29235 -58.890408)
		(width 0.0889)
		(layer "F.Cu")
		(net "PHY_SCC_TO_IOC_46_DN")
	)
	(segment
		(start 141.247114 -51.69662)
		(end 140.39088 -52.251864)
		(width 0.12446)
		(layer "F.Cu")
		(net "PHY_SCC_TO_IOC_46_DN")
	)
	(segment
		(start 134.256272 -58.609484)
		(end 133.446266 -58.782458)
		(width 0.12446)
		(layer "F.Cu")
		(net "PHY_SCC_TO_IOC_46_DN")
	)
	(segment
		(start 142.093442 -51.147218)
		(end 141.247114 -51.69662)
		(width 0.12446)
		(layer "F.Cu")
		(net "PHY_SCC_TO_IOC_46_DN")
	)
	(segment
		(start 146.185128 -50.277014)
		(end 142.093442 -51.147218)
		(width 0.12446)
		(layer "F.Cu")
		(net "PHY_SCC_TO_IOC_46_DN")
	)
	(arc
		(start 129.29235 -58.890408)
		(mid 129.018273 -59.003935)
		(end 128.904746 -59.278012)
		(width 0.0889)
		(layer "F.Cu")
		(net "PHY_SCC_TO_IOC_46_DN")
	)
	(arc
		(start 128.904746 -59.385708)
		(mid 128.871268 -59.46653)
		(end 128.790446 -59.500008)
		(width 0.0889)
		(layer "F.Cu")
		(net "PHY_SCC_TO_IOC_46_DN")
	)
	(segment
		(start 141.740636 -49.113186)
		(end 141.661388 -48.740822)
		(width 0.12446)
		(layer "F.Cu")
		(net "PHY_SCC_TO_IOC_45_DP")
	)
	(segment
		(start 141.040866 -50.191162)
		(end 140.961618 -49.818798)
		(width 0.12446)
		(layer "F.Cu")
		(net "PHY_SCC_TO_IOC_45_DP")
	)
	(segment
		(start 141.164818 -49.505616)
		(end 141.537182 -49.426368)
		(width 0.12446)
		(layer "F.Cu")
		(net "PHY_SCC_TO_IOC_45_DP")
	)
	(segment
		(start 131.849876 -58.18886)
		(end 132.328666 -58.18886)
		(width 0.12446)
		(layer "F.Cu")
		(net "PHY_SCC_TO_IOC_45_DP")
	)
	(segment
		(start 145.549874 -46.801024)
		(end 145.618454 -46.906434)
		(width 0.12446)
		(layer "F.Cu")
		(net "PHY_SCC_TO_IOC_45_DP")
	)
	(segment
		(start 132.328666 -58.18886)
		(end 133.879336 -57.859676)
		(width 0.12446)
		(layer "F.Cu")
		(net "PHY_SCC_TO_IOC_45_DP")
	)
	(segment
		(start 130.270504 -58.08091)
		(end 131.719828 -58.08091)
		(width 0.0889)
		(layer "F.Cu")
		(net "PHY_SCC_TO_IOC_45_DP")
	)
	(segment
		(start 133.879336 -57.859676)
		(end 137.10412 -55.76062)
		(width 0.12446)
		(layer "F.Cu")
		(net "PHY_SCC_TO_IOC_45_DP")
	)
	(segment
		(start 141.537182 -49.426368)
		(end 141.740636 -49.113186)
		(width 0.12446)
		(layer "F.Cu")
		(net "PHY_SCC_TO_IOC_45_DP")
	)
	(segment
		(start 140.961618 -49.818798)
		(end 141.164818 -49.505616)
		(width 0.12446)
		(layer "F.Cu")
		(net "PHY_SCC_TO_IOC_45_DP")
	)
	(segment
		(start 145.180304 -46.723046)
		(end 145.549874 -46.801024)
		(width 0.12446)
		(layer "F.Cu")
		(net "PHY_SCC_TO_IOC_45_DP")
	)
	(segment
		(start 140.837412 -50.504344)
		(end 141.040866 -50.191162)
		(width 0.12446)
		(layer "F.Cu")
		(net "PHY_SCC_TO_IOC_45_DP")
	)
	(segment
		(start 137.10412 -55.76062)
		(end 138.903202 -52.98948)
		(width 0.12446)
		(layer "F.Cu")
		(net "PHY_SCC_TO_IOC_45_DP")
	)
	(segment
		(start 143.58239 -47.312834)
		(end 144.154398 -46.941232)
		(width 0.12446)
		(layer "F.Cu")
		(net "PHY_SCC_TO_IOC_45_DP")
	)
	(segment
		(start 130.50012 -58.50001)
		(end 130.209544 -58.50001)
		(width 0.0889)
		(layer "F.Cu")
		(net "PHY_SCC_TO_IOC_45_DP")
	)
	(segment
		(start 141.661388 -48.740822)
		(end 141.864588 -48.42764)
		(width 0.12446)
		(layer "F.Cu")
		(net "PHY_SCC_TO_IOC_45_DP")
	)
	(segment
		(start 145.618454 -46.906434)
		(end 145.976594 -46.982634)
		(width 0.12446)
		(layer "F.Cu")
		(net "PHY_SCC_TO_IOC_45_DP")
	)
	(segment
		(start 144.154398 -46.941232)
		(end 145.180304 -46.723046)
		(width 0.12446)
		(layer "F.Cu")
		(net "PHY_SCC_TO_IOC_45_DP")
	)
	(segment
		(start 138.903202 -52.98948)
		(end 140.465048 -50.583592)
		(width 0.12446)
		(layer "F.Cu")
		(net "PHY_SCC_TO_IOC_45_DP")
	)
	(segment
		(start 131.719828 -58.08091)
		(end 131.827778 -58.18886)
		(width 0.0889)
		(layer "F.Cu")
		(net "PHY_SCC_TO_IOC_45_DP")
	)
	(segment
		(start 140.465048 -50.583592)
		(end 140.837412 -50.504344)
		(width 0.12446)
		(layer "F.Cu")
		(net "PHY_SCC_TO_IOC_45_DP")
	)
	(segment
		(start 131.827778 -58.18886)
		(end 131.849876 -58.18886)
		(width 0.0889)
		(layer "F.Cu")
		(net "PHY_SCC_TO_IOC_45_DP")
	)
	(segment
		(start 130.069844 -58.36031)
		(end 130.069844 -58.28157)
		(width 0.0889)
		(layer "F.Cu")
		(net "PHY_SCC_TO_IOC_45_DP")
	)
	(segment
		(start 143.58239 -47.31258)
		(end 143.58239 -47.312834)
		(width 0.12446)
		(layer "F.Cu")
		(net "PHY_SCC_TO_IOC_45_DP")
	)
	(segment
		(start 141.864588 -48.42764)
		(end 143.58239 -47.31258)
		(width 0.12446)
		(layer "F.Cu")
		(net "PHY_SCC_TO_IOC_45_DP")
	)
	(arc
		(start 130.069844 -58.28157)
		(mid 130.085168 -58.204712)
		(end 130.128772 -58.139584)
		(width 0.0889)
		(layer "F.Cu")
		(net "PHY_SCC_TO_IOC_45_DP")
	)
	(arc
		(start 130.209544 -58.50001)
		(mid 130.110761 -58.459093)
		(end 130.069844 -58.36031)
		(width 0.0889)
		(layer "F.Cu")
		(net "PHY_SCC_TO_IOC_45_DP")
	)
	(arc
		(start 130.128772 -58.139584)
		(mid 130.193799 -58.096134)
		(end 130.270504 -58.08091)
		(width 0.0889)
		(layer "F.Cu")
		(net "PHY_SCC_TO_IOC_45_DP")
	)
	(segment
		(start 145.634456 -46.403514)
		(end 145.739866 -46.334934)
		(width 0.12446)
		(layer "F.Cu")
		(net "PHY_SCC_TO_IOC_45_DN")
	)
	(segment
		(start 129.500122 -58.50001)
		(end 129.790444 -58.50001)
		(width 0.0889)
		(layer "F.Cu")
		(net "PHY_SCC_TO_IOC_45_DN")
	)
	(segment
		(start 132.28574 -57.78246)
		(end 133.72084 -57.47766)
		(width 0.12446)
		(layer "F.Cu")
		(net "PHY_SCC_TO_IOC_45_DN")
	)
	(segment
		(start 131.849876 -57.78246)
		(end 132.28574 -57.78246)
		(width 0.12446)
		(layer "F.Cu")
		(net "PHY_SCC_TO_IOC_45_DN")
	)
	(segment
		(start 145.179796 -46.307502)
		(end 145.634456 -46.403514)
		(width 0.12446)
		(layer "F.Cu")
		(net "PHY_SCC_TO_IOC_45_DN")
	)
	(segment
		(start 131.719828 -57.89041)
		(end 131.827778 -57.78246)
		(width 0.0889)
		(layer "F.Cu")
		(net "PHY_SCC_TO_IOC_45_DN")
	)
	(segment
		(start 136.809988 -55.466742)
		(end 141.57071 -48.133762)
		(width 0.12446)
		(layer "F.Cu")
		(net "PHY_SCC_TO_IOC_45_DN")
	)
	(segment
		(start 141.57071 -48.133762)
		(end 143.996156 -46.559216)
		(width 0.12446)
		(layer "F.Cu")
		(net "PHY_SCC_TO_IOC_45_DN")
	)
	(segment
		(start 131.827778 -57.78246)
		(end 131.849876 -57.78246)
		(width 0.0889)
		(layer "F.Cu")
		(net "PHY_SCC_TO_IOC_45_DN")
	)
	(segment
		(start 143.996156 -46.559216)
		(end 145.179796 -46.307502)
		(width 0.12446)
		(layer "F.Cu")
		(net "PHY_SCC_TO_IOC_45_DN")
	)
	(segment
		(start 145.739866 -46.334934)
		(end 146.098006 -46.411388)
		(width 0.12446)
		(layer "F.Cu")
		(net "PHY_SCC_TO_IOC_45_DN")
	)
	(segment
		(start 133.72084 -57.47766)
		(end 136.809988 -55.466742)
		(width 0.12446)
		(layer "F.Cu")
		(net "PHY_SCC_TO_IOC_45_DN")
	)
	(segment
		(start 130.270504 -57.89041)
		(end 131.719828 -57.89041)
		(width 0.0889)
		(layer "F.Cu")
		(net "PHY_SCC_TO_IOC_45_DN")
	)
	(segment
		(start 129.879344 -58.41111)
		(end 129.879344 -58.28157)
		(width 0.0889)
		(layer "F.Cu")
		(net "PHY_SCC_TO_IOC_45_DN")
	)
	(arc
		(start 129.790444 -58.50001)
		(mid 129.853306 -58.473972)
		(end 129.879344 -58.41111)
		(width 0.0889)
		(layer "F.Cu")
		(net "PHY_SCC_TO_IOC_45_DN")
	)
	(arc
		(start 129.879344 -58.28157)
		(mid 129.909188 -58.131714)
		(end 129.994152 -58.00471)
		(width 0.0889)
		(layer "F.Cu")
		(net "PHY_SCC_TO_IOC_45_DN")
	)
	(arc
		(start 129.994152 -58.00471)
		(mid 130.120972 -57.920098)
		(end 130.270504 -57.89041)
		(width 0.0889)
		(layer "F.Cu")
		(net "PHY_SCC_TO_IOC_45_DN")
	)
	(segment
		(start 137.253726 -52.810664)
		(end 137.456926 -52.497482)
		(width 0.12446)
		(layer "F.Cu")
		(net "PHY_SCC_TO_IOC_44_DP")
	)
	(segment
		(start 137.377678 -52.125118)
		(end 137.581132 -51.811936)
		(width 0.12446)
		(layer "F.Cu")
		(net "PHY_SCC_TO_IOC_44_DP")
	)
	(segment
		(start 129.095246 -57.385712)
		(end 129.095246 -57.174892)
		(width 0.0889)
		(layer "F.Cu")
		(net "PHY_SCC_TO_IOC_44_DP")
	)
	(segment
		(start 132.76453 -57.125362)
		(end 135.127492 -55.59044)
		(width 0.12446)
		(layer "F.Cu")
		(net "PHY_SCC_TO_IOC_44_DP")
	)
	(segment
		(start 137.953496 -51.732688)
		(end 138.156696 -51.419506)
		(width 0.12446)
		(layer "F.Cu")
		(net "PHY_SCC_TO_IOC_44_DP")
	)
	(segment
		(start 135.127492 -55.59044)
		(end 136.881108 -52.889912)
		(width 0.12446)
		(layer "F.Cu")
		(net "PHY_SCC_TO_IOC_44_DP")
	)
	(segment
		(start 136.881108 -52.889912)
		(end 137.253726 -52.810664)
		(width 0.12446)
		(layer "F.Cu")
		(net "PHY_SCC_TO_IOC_44_DP")
	)
	(segment
		(start 129.500122 -57.500012)
		(end 129.209546 -57.500012)
		(width 0.0889)
		(layer "F.Cu")
		(net "PHY_SCC_TO_IOC_44_DP")
	)
	(segment
		(start 131.647946 -57.080912)
		(end 131.692396 -57.125362)
		(width 0.0889)
		(layer "F.Cu")
		(net "PHY_SCC_TO_IOC_44_DP")
	)
	(segment
		(start 131.692396 -57.125362)
		(end 131.714494 -57.125362)
		(width 0.0889)
		(layer "F.Cu")
		(net "PHY_SCC_TO_IOC_44_DP")
	)
	(segment
		(start 131.714494 -57.125362)
		(end 132.76453 -57.125362)
		(width 0.12446)
		(layer "F.Cu")
		(net "PHY_SCC_TO_IOC_44_DP")
	)
	(segment
		(start 137.581132 -51.811936)
		(end 137.953496 -51.732688)
		(width 0.12446)
		(layer "F.Cu")
		(net "PHY_SCC_TO_IOC_44_DP")
	)
	(segment
		(start 145.763488 -44.186856)
		(end 147.83435 -44.626784)
		(width 0.12446)
		(layer "F.Cu")
		(net "PHY_SCC_TO_IOC_44_DP")
	)
	(segment
		(start 137.456926 -52.497482)
		(end 137.377678 -52.125118)
		(width 0.12446)
		(layer "F.Cu")
		(net "PHY_SCC_TO_IOC_44_DP")
	)
	(segment
		(start 129.189226 -57.080912)
		(end 131.647946 -57.080912)
		(width 0.0889)
		(layer "F.Cu")
		(net "PHY_SCC_TO_IOC_44_DP")
	)
	(segment
		(start 138.156696 -51.419506)
		(end 138.077702 -51.047142)
		(width 0.12446)
		(layer "F.Cu")
		(net "PHY_SCC_TO_IOC_44_DP")
	)
	(segment
		(start 147.878292 -44.694348)
		(end 148.236432 -44.770548)
		(width 0.12446)
		(layer "F.Cu")
		(net "PHY_SCC_TO_IOC_44_DP")
	)
	(segment
		(start 143.989806 -44.564046)
		(end 145.763488 -44.186856)
		(width 0.12446)
		(layer "F.Cu")
		(net "PHY_SCC_TO_IOC_44_DP")
	)
	(segment
		(start 138.077702 -51.047142)
		(end 141.046708 -46.47438)
		(width 0.12446)
		(layer "F.Cu")
		(net "PHY_SCC_TO_IOC_44_DP")
	)
	(segment
		(start 141.046708 -46.47438)
		(end 143.989806 -44.564046)
		(width 0.12446)
		(layer "F.Cu")
		(net "PHY_SCC_TO_IOC_44_DP")
	)
	(segment
		(start 147.83435 -44.626784)
		(end 147.878292 -44.694348)
		(width 0.12446)
		(layer "F.Cu")
		(net "PHY_SCC_TO_IOC_44_DP")
	)
	(arc
		(start 129.209546 -57.500012)
		(mid 129.128724 -57.466534)
		(end 129.095246 -57.385712)
		(width 0.0889)
		(layer "F.Cu")
		(net "PHY_SCC_TO_IOC_44_DP")
	)
	(arc
		(start 129.095246 -57.174892)
		(mid 129.122772 -57.108438)
		(end 129.189226 -57.080912)
		(width 0.0889)
		(layer "F.Cu")
		(net "PHY_SCC_TO_IOC_44_DP")
	)
	(segment
		(start 143.831564 -44.18203)
		(end 145.763488 -43.771312)
		(width 0.12446)
		(layer "F.Cu")
		(net "PHY_SCC_TO_IOC_44_DN")
	)
	(segment
		(start 134.833614 -55.296562)
		(end 140.75283 -46.180502)
		(width 0.12446)
		(layer "F.Cu")
		(net "PHY_SCC_TO_IOC_44_DN")
	)
	(segment
		(start 140.75283 -46.180502)
		(end 143.831564 -44.18203)
		(width 0.12446)
		(layer "F.Cu")
		(net "PHY_SCC_TO_IOC_44_DN")
	)
	(segment
		(start 132.64388 -56.718962)
		(end 134.833614 -55.296562)
		(width 0.12446)
		(layer "F.Cu")
		(net "PHY_SCC_TO_IOC_44_DN")
	)
	(segment
		(start 128.500124 -57.500012)
		(end 128.790446 -57.500012)
		(width 0.0889)
		(layer "F.Cu")
		(net "PHY_SCC_TO_IOC_44_DN")
	)
	(segment
		(start 131.692396 -56.718962)
		(end 131.714494 -56.718962)
		(width 0.0889)
		(layer "F.Cu")
		(net "PHY_SCC_TO_IOC_44_DN")
	)
	(segment
		(start 145.763488 -43.771312)
		(end 147.85721 -44.216066)
		(width 0.12446)
		(layer "F.Cu")
		(net "PHY_SCC_TO_IOC_44_DN")
	)
	(segment
		(start 131.520946 -56.890412)
		(end 131.692396 -56.718962)
		(width 0.0889)
		(layer "F.Cu")
		(net "PHY_SCC_TO_IOC_44_DN")
	)
	(segment
		(start 128.904746 -57.385712)
		(end 128.904746 -57.174892)
		(width 0.0889)
		(layer "F.Cu")
		(net "PHY_SCC_TO_IOC_44_DN")
	)
	(segment
		(start 129.189226 -56.890412)
		(end 131.520946 -56.890412)
		(width 0.0889)
		(layer "F.Cu")
		(net "PHY_SCC_TO_IOC_44_DN")
	)
	(segment
		(start 147.85721 -44.216066)
		(end 147.999704 -44.122848)
		(width 0.12446)
		(layer "F.Cu")
		(net "PHY_SCC_TO_IOC_44_DN")
	)
	(segment
		(start 131.714494 -56.718962)
		(end 132.64388 -56.718962)
		(width 0.12446)
		(layer "F.Cu")
		(net "PHY_SCC_TO_IOC_44_DN")
	)
	(segment
		(start 147.999704 -44.122848)
		(end 148.357844 -44.199048)
		(width 0.12446)
		(layer "F.Cu")
		(net "PHY_SCC_TO_IOC_44_DN")
	)
	(arc
		(start 128.790446 -57.500012)
		(mid 128.871268 -57.466534)
		(end 128.904746 -57.385712)
		(width 0.0889)
		(layer "F.Cu")
		(net "PHY_SCC_TO_IOC_44_DN")
	)
	(arc
		(start 128.904746 -57.174892)
		(mid 128.988068 -56.973734)
		(end 129.189226 -56.890412)
		(width 0.0889)
		(layer "F.Cu")
		(net "PHY_SCC_TO_IOC_44_DN")
	)
	(segment
		(start 130.095244 -56.174894)
		(end 130.095244 -56.385714)
		(width 0.0889)
		(layer "F.Cu")
		(net "PHY_SCC_TO_IOC_43_DP")
	)
	(segment
		(start 143.269208 -42.543222)
		(end 142.95628 -42.746422)
		(width 0.12446)
		(layer "F.Cu")
		(net "PHY_SCC_TO_IOC_43_DP")
	)
	(segment
		(start 146.813016 -40.514016)
		(end 146.44243 -40.439086)
		(width 0.12446)
		(layer "F.Cu")
		(net "PHY_SCC_TO_IOC_43_DP")
	)
	(segment
		(start 141.671548 -43.259756)
		(end 134.370064 -54.503828)
		(width 0.12446)
		(layer "F.Cu")
		(net "PHY_SCC_TO_IOC_43_DP")
	)
	(segment
		(start 132.573776 -55.670196)
		(end 132.354066 -55.623714)
		(width 0.0889)
		(layer "F.Cu")
		(net "PHY_SCC_TO_IOC_43_DP")
	)
	(segment
		(start 144.034002 -42.046652)
		(end 143.661638 -41.967404)
		(width 0.12446)
		(layer "F.Cu")
		(net "PHY_SCC_TO_IOC_43_DP")
	)
	(segment
		(start 130.209544 -56.500014)
		(end 130.50012 -56.500014)
		(width 0.0889)
		(layer "F.Cu")
		(net "PHY_SCC_TO_IOC_43_DP")
	)
	(segment
		(start 146.929856 -40.693594)
		(end 146.813016 -40.514016)
		(width 0.12446)
		(layer "F.Cu")
		(net "PHY_SCC_TO_IOC_43_DP")
	)
	(segment
		(start 132.354066 -55.623714)
		(end 131.755388 -56.012334)
		(width 0.0889)
		(layer "F.Cu")
		(net "PHY_SCC_TO_IOC_43_DP")
	)
	(segment
		(start 142.583662 -42.667428)
		(end 141.671548 -43.259756)
		(width 0.12446)
		(layer "F.Cu")
		(net "PHY_SCC_TO_IOC_43_DP")
	)
	(segment
		(start 143.661638 -41.967404)
		(end 143.348456 -42.170858)
		(width 0.12446)
		(layer "F.Cu")
		(net "PHY_SCC_TO_IOC_43_DP")
	)
	(segment
		(start 131.4323 -56.080914)
		(end 130.189224 -56.080914)
		(width 0.0889)
		(layer "F.Cu")
		(net "PHY_SCC_TO_IOC_43_DP")
	)
	(segment
		(start 144.347184 -41.843198)
		(end 144.034002 -42.046652)
		(width 0.12446)
		(layer "F.Cu")
		(net "PHY_SCC_TO_IOC_43_DP")
	)
	(segment
		(start 142.95628 -42.746422)
		(end 142.583662 -42.667428)
		(width 0.12446)
		(layer "F.Cu")
		(net "PHY_SCC_TO_IOC_43_DP")
	)
	(segment
		(start 147.19681 -40.750744)
		(end 146.929856 -40.693594)
		(width 0.12446)
		(layer "F.Cu")
		(net "PHY_SCC_TO_IOC_43_DP")
	)
	(segment
		(start 146.44243 -40.439086)
		(end 145.807176 -40.573706)
		(width 0.12446)
		(layer "F.Cu")
		(net "PHY_SCC_TO_IOC_43_DP")
	)
	(segment
		(start 144.426432 -41.470834)
		(end 144.347184 -41.843198)
		(width 0.12446)
		(layer "F.Cu")
		(net "PHY_SCC_TO_IOC_43_DP")
	)
	(segment
		(start 145.807176 -40.573706)
		(end 144.426432 -41.47058)
		(width 0.12446)
		(layer "F.Cu")
		(net "PHY_SCC_TO_IOC_43_DP")
	)
	(segment
		(start 144.426432 -41.47058)
		(end 144.426432 -41.470834)
		(width 0.12446)
		(layer "F.Cu")
		(net "PHY_SCC_TO_IOC_43_DP")
	)
	(segment
		(start 143.348456 -42.170858)
		(end 143.269208 -42.543222)
		(width 0.12446)
		(layer "F.Cu")
		(net "PHY_SCC_TO_IOC_43_DP")
	)
	(segment
		(start 132.592318 -55.658258)
		(end 132.573776 -55.670196)
		(width 0.0889)
		(layer "F.Cu")
		(net "PHY_SCC_TO_IOC_43_DP")
	)
	(segment
		(start 131.755388 -56.012334)
		(end 131.4323 -56.080914)
		(width 0.0889)
		(layer "F.Cu")
		(net "PHY_SCC_TO_IOC_43_DP")
	)
	(segment
		(start 134.370064 -54.503828)
		(end 132.592318 -55.658258)
		(width 0.12446)
		(layer "F.Cu")
		(net "PHY_SCC_TO_IOC_43_DP")
	)
	(arc
		(start 130.095244 -56.385714)
		(mid 130.128722 -56.466536)
		(end 130.209544 -56.500014)
		(width 0.0889)
		(layer "F.Cu")
		(net "PHY_SCC_TO_IOC_43_DP")
	)
	(arc
		(start 130.189224 -56.080914)
		(mid 130.12277 -56.10844)
		(end 130.095244 -56.174894)
		(width 0.0889)
		(layer "F.Cu")
		(net "PHY_SCC_TO_IOC_43_DP")
	)
	(segment
		(start 146.440398 -40.023796)
		(end 145.723356 -40.175942)
		(width 0.12446)
		(layer "F.Cu")
		(net "PHY_SCC_TO_IOC_43_DN")
	)
	(segment
		(start 134.076186 -54.20995)
		(end 132.37083 -55.31739)
		(width 0.12446)
		(layer "F.Cu")
		(net "PHY_SCC_TO_IOC_43_DN")
	)
	(segment
		(start 131.411218 -55.890414)
		(end 130.189224 -55.890414)
		(width 0.0889)
		(layer "F.Cu")
		(net "PHY_SCC_TO_IOC_43_DN")
	)
	(segment
		(start 145.723356 -40.175942)
		(end 145.723102 -40.175942)
		(width 0.12446)
		(layer "F.Cu")
		(net "PHY_SCC_TO_IOC_43_DN")
	)
	(segment
		(start 147.03044 -40.11803)
		(end 147.000468 -40.13708)
		(width 0.12446)
		(layer "F.Cu")
		(net "PHY_SCC_TO_IOC_43_DN")
	)
	(segment
		(start 147.000468 -40.13708)
		(end 146.440398 -40.023796)
		(width 0.12446)
		(layer "F.Cu")
		(net "PHY_SCC_TO_IOC_43_DN")
	)
	(segment
		(start 132.37083 -55.31739)
		(end 132.352288 -55.329328)
		(width 0.0889)
		(layer "F.Cu")
		(net "PHY_SCC_TO_IOC_43_DN")
	)
	(segment
		(start 141.37767 -42.965878)
		(end 134.076186 -54.20995)
		(width 0.12446)
		(layer "F.Cu")
		(net "PHY_SCC_TO_IOC_43_DN")
	)
	(segment
		(start 132.330444 -55.41137)
		(end 131.68122 -55.833264)
		(width 0.0889)
		(layer "F.Cu")
		(net "PHY_SCC_TO_IOC_43_DN")
	)
	(segment
		(start 145.649188 -40.19169)
		(end 141.37767 -42.965878)
		(width 0.12446)
		(layer "F.Cu")
		(net "PHY_SCC_TO_IOC_43_DN")
	)
	(segment
		(start 131.68122 -55.833264)
		(end 131.411218 -55.890414)
		(width 0.0889)
		(layer "F.Cu")
		(net "PHY_SCC_TO_IOC_43_DN")
	)
	(segment
		(start 145.723102 -40.175942)
		(end 145.649188 -40.19169)
		(width 0.12446)
		(layer "F.Cu")
		(net "PHY_SCC_TO_IOC_43_DN")
	)
	(segment
		(start 129.790444 -56.500014)
		(end 129.500122 -56.500014)
		(width 0.0889)
		(layer "F.Cu")
		(net "PHY_SCC_TO_IOC_43_DN")
	)
	(segment
		(start 132.352288 -55.329328)
		(end 132.330444 -55.41137)
		(width 0.0889)
		(layer "F.Cu")
		(net "PHY_SCC_TO_IOC_43_DN")
	)
	(segment
		(start 129.904744 -56.174894)
		(end 129.904744 -56.385714)
		(width 0.0889)
		(layer "F.Cu")
		(net "PHY_SCC_TO_IOC_43_DN")
	)
	(segment
		(start 147.318222 -40.179498)
		(end 147.03044 -40.11803)
		(width 0.12446)
		(layer "F.Cu")
		(net "PHY_SCC_TO_IOC_43_DN")
	)
	(arc
		(start 130.189224 -55.890414)
		(mid 129.988066 -55.973736)
		(end 129.904744 -56.174894)
		(width 0.0889)
		(layer "F.Cu")
		(net "PHY_SCC_TO_IOC_43_DN")
	)
	(arc
		(start 129.904744 -56.385714)
		(mid 129.871266 -56.466536)
		(end 129.790444 -56.500014)
		(width 0.0889)
		(layer "F.Cu")
		(net "PHY_SCC_TO_IOC_43_DN")
	)
	(segment
		(start 141.529562 -41.141396)
		(end 142.971774 -40.20439)
		(width 0.12446)
		(layer "F.Cu")
		(net "PHY_SCC_TO_IOC_42_DP")
	)
	(segment
		(start 144.42186 -39.58336)
		(end 144.735042 -39.379906)
		(width 0.12446)
		(layer "F.Cu")
		(net "PHY_SCC_TO_IOC_42_DP")
	)
	(segment
		(start 129.500122 -55.500016)
		(end 129.209546 -55.500016)
		(width 0.0889)
		(layer "F.Cu")
		(net "PHY_SCC_TO_IOC_42_DP")
	)
	(segment
		(start 144.049496 -39.504366)
		(end 144.42186 -39.58336)
		(width 0.12446)
		(layer "F.Cu")
		(net "PHY_SCC_TO_IOC_42_DP")
	)
	(segment
		(start 144.735042 -39.379906)
		(end 144.814036 -39.007542)
		(width 0.12446)
		(layer "F.Cu")
		(net "PHY_SCC_TO_IOC_42_DP")
	)
	(segment
		(start 142.971774 -40.20439)
		(end 143.344138 -40.283638)
		(width 0.12446)
		(layer "F.Cu")
		(net "PHY_SCC_TO_IOC_42_DP")
	)
	(segment
		(start 149.140418 -38.327584)
		(end 149.208236 -38.432486)
		(width 0.12446)
		(layer "F.Cu")
		(net "PHY_SCC_TO_IOC_42_DP")
	)
	(segment
		(start 129.189226 -55.080916)
		(end 130.85191 -55.080916)
		(width 0.0889)
		(layer "F.Cu")
		(net "PHY_SCC_TO_IOC_42_DP")
	)
	(segment
		(start 149.018498 -38.301676)
		(end 149.018752 -38.301676)
		(width 0.12446)
		(layer "F.Cu")
		(net "PHY_SCC_TO_IOC_42_DP")
	)
	(segment
		(start 143.65732 -40.080184)
		(end 143.736314 -39.70782)
		(width 0.12446)
		(layer "F.Cu")
		(net "PHY_SCC_TO_IOC_42_DP")
	)
	(segment
		(start 132.0292 -54.432708)
		(end 132.047742 -54.42077)
		(width 0.0889)
		(layer "F.Cu")
		(net "PHY_SCC_TO_IOC_42_DP")
	)
	(segment
		(start 143.736314 -39.70782)
		(end 144.049496 -39.504366)
		(width 0.12446)
		(layer "F.Cu")
		(net "PHY_SCC_TO_IOC_42_DP")
	)
	(segment
		(start 129.095246 -55.385716)
		(end 129.095246 -55.174896)
		(width 0.0889)
		(layer "F.Cu")
		(net "PHY_SCC_TO_IOC_42_DP")
	)
	(segment
		(start 130.85191 -55.080916)
		(end 131.879848 -54.400958)
		(width 0.0889)
		(layer "F.Cu")
		(net "PHY_SCC_TO_IOC_42_DP")
	)
	(segment
		(start 131.879848 -54.400958)
		(end 132.0292 -54.432708)
		(width 0.0889)
		(layer "F.Cu")
		(net "PHY_SCC_TO_IOC_42_DP")
	)
	(segment
		(start 133.535674 -53.451252)
		(end 141.529562 -41.141396)
		(width 0.12446)
		(layer "F.Cu")
		(net "PHY_SCC_TO_IOC_42_DP")
	)
	(segment
		(start 144.814036 -39.007542)
		(end 145.1483 -38.790626)
		(width 0.12446)
		(layer "F.Cu")
		(net "PHY_SCC_TO_IOC_42_DP")
	)
	(segment
		(start 149.208236 -38.432486)
		(end 149.564344 -38.508432)
		(width 0.12446)
		(layer "F.Cu")
		(net "PHY_SCC_TO_IOC_42_DP")
	)
	(segment
		(start 132.047742 -54.42077)
		(end 133.535674 -53.451252)
		(width 0.12446)
		(layer "F.Cu")
		(net "PHY_SCC_TO_IOC_42_DP")
	)
	(segment
		(start 148.199348 -38.141402)
		(end 149.018498 -38.301676)
		(width 0.12446)
		(layer "F.Cu")
		(net "PHY_SCC_TO_IOC_42_DP")
	)
	(segment
		(start 149.018752 -38.301676)
		(end 149.140418 -38.327584)
		(width 0.12446)
		(layer "F.Cu")
		(net "PHY_SCC_TO_IOC_42_DP")
	)
	(segment
		(start 145.1483 -38.790626)
		(end 148.199348 -38.141402)
		(width 0.12446)
		(layer "F.Cu")
		(net "PHY_SCC_TO_IOC_42_DP")
	)
	(segment
		(start 143.344138 -40.283638)
		(end 143.65732 -40.080184)
		(width 0.12446)
		(layer "F.Cu")
		(net "PHY_SCC_TO_IOC_42_DP")
	)
	(arc
		(start 129.209546 -55.500016)
		(mid 129.128724 -55.466538)
		(end 129.095246 -55.385716)
		(width 0.0889)
		(layer "F.Cu")
		(net "PHY_SCC_TO_IOC_42_DP")
	)
	(arc
		(start 129.095246 -55.174896)
		(mid 129.122772 -55.108442)
		(end 129.189226 -55.080916)
		(width 0.0889)
		(layer "F.Cu")
		(net "PHY_SCC_TO_IOC_42_DP")
	)
	(segment
		(start 131.776216 -54.240684)
		(end 131.807458 -54.092094)
		(width 0.0889)
		(layer "F.Cu")
		(net "PHY_SCC_TO_IOC_42_DN")
	)
	(segment
		(start 130.794506 -54.890416)
		(end 131.774438 -54.241954)
		(width 0.0889)
		(layer "F.Cu")
		(net "PHY_SCC_TO_IOC_42_DN")
	)
	(segment
		(start 149.224746 -37.92982)
		(end 149.329902 -37.86124)
		(width 0.12446)
		(layer "F.Cu")
		(net "PHY_SCC_TO_IOC_42_DN")
	)
	(segment
		(start 149.329902 -37.86124)
		(end 149.685756 -37.937186)
		(width 0.12446)
		(layer "F.Cu")
		(net "PHY_SCC_TO_IOC_42_DN")
	)
	(segment
		(start 144.990058 -38.40861)
		(end 148.196046 -37.726366)
		(width 0.12446)
		(layer "F.Cu")
		(net "PHY_SCC_TO_IOC_42_DN")
	)
	(segment
		(start 149.16277 -37.916612)
		(end 149.224746 -37.92982)
		(width 0.12446)
		(layer "F.Cu")
		(net "PHY_SCC_TO_IOC_42_DN")
	)
	(segment
		(start 148.196046 -37.726366)
		(end 149.102318 -37.903912)
		(width 0.12446)
		(layer "F.Cu")
		(net "PHY_SCC_TO_IOC_42_DN")
	)
	(segment
		(start 128.904746 -55.385716)
		(end 128.904746 -55.174896)
		(width 0.0889)
		(layer "F.Cu")
		(net "PHY_SCC_TO_IOC_42_DN")
	)
	(segment
		(start 144.748758 -38.565074)
		(end 144.990058 -38.40861)
		(width 0.12446)
		(layer "F.Cu")
		(net "PHY_SCC_TO_IOC_42_DN")
	)
	(segment
		(start 133.241542 -53.157628)
		(end 141.235684 -40.847518)
		(width 0.12446)
		(layer "F.Cu")
		(net "PHY_SCC_TO_IOC_42_DN")
	)
	(segment
		(start 128.500124 -55.500016)
		(end 128.790446 -55.500016)
		(width 0.0889)
		(layer "F.Cu")
		(net "PHY_SCC_TO_IOC_42_DN")
	)
	(segment
		(start 141.235684 -40.847518)
		(end 144.748758 -38.565074)
		(width 0.12446)
		(layer "F.Cu")
		(net "PHY_SCC_TO_IOC_42_DN")
	)
	(segment
		(start 149.102318 -37.903912)
		(end 149.16277 -37.916612)
		(width 0.12446)
		(layer "F.Cu")
		(net "PHY_SCC_TO_IOC_42_DN")
	)
	(segment
		(start 129.189226 -54.890416)
		(end 130.794506 -54.890416)
		(width 0.0889)
		(layer "F.Cu")
		(net "PHY_SCC_TO_IOC_42_DN")
	)
	(segment
		(start 131.807458 -54.092094)
		(end 131.826 -54.080156)
		(width 0.0889)
		(layer "F.Cu")
		(net "PHY_SCC_TO_IOC_42_DN")
	)
	(segment
		(start 131.774438 -54.241954)
		(end 131.776216 -54.240684)
		(width 0.0889)
		(layer "F.Cu")
		(net "PHY_SCC_TO_IOC_42_DN")
	)
	(segment
		(start 131.826 -54.080156)
		(end 133.241542 -53.157628)
		(width 0.12446)
		(layer "F.Cu")
		(net "PHY_SCC_TO_IOC_42_DN")
	)
	(arc
		(start 128.790446 -55.500016)
		(mid 128.871268 -55.466538)
		(end 128.904746 -55.385716)
		(width 0.0889)
		(layer "F.Cu")
		(net "PHY_SCC_TO_IOC_42_DN")
	)
	(arc
		(start 128.904746 -55.174896)
		(mid 128.988068 -54.973738)
		(end 129.189226 -54.890416)
		(width 0.0889)
		(layer "F.Cu")
		(net "PHY_SCC_TO_IOC_42_DN")
	)
	(segment
		(start 131.96062 -52.772818)
		(end 132.890768 -52.168552)
		(width 0.12446)
		(layer "F.Cu")
		(net "PHY_SCC_TO_IOC_41_DP")
	)
	(segment
		(start 131.78409 -53.043836)
		(end 131.96062 -52.772818)
		(width 0.12446)
		(layer "F.Cu")
		(net "PHY_SCC_TO_IOC_41_DP")
	)
	(segment
		(start 131.771136 -53.062632)
		(end 131.772152 -53.062378)
		(width 0.0889)
		(layer "F.Cu")
		(net "PHY_SCC_TO_IOC_41_DP")
	)
	(segment
		(start 147.416266 -35.559492)
		(end 147.43811 -35.59302)
		(width 0.12446)
		(layer "F.Cu")
		(net "PHY_SCC_TO_IOC_41_DP")
	)
	(segment
		(start 141.79677 -38.455092)
		(end 142.883636 -37.74948)
		(width 0.12446)
		(layer "F.Cu")
		(net "PHY_SCC_TO_IOC_41_DP")
	)
	(segment
		(start 146.118072 -35.649408)
		(end 146.979894 -35.466528)
		(width 0.12446)
		(layer "F.Cu")
		(net "PHY_SCC_TO_IOC_41_DP")
	)
	(segment
		(start 146.979894 -35.466528)
		(end 147.416266 -35.559492)
		(width 0.12446)
		(layer "F.Cu")
		(net "PHY_SCC_TO_IOC_41_DP")
	)
	(segment
		(start 143.256 -37.828474)
		(end 143.569182 -37.625274)
		(width 0.12446)
		(layer "F.Cu")
		(net "PHY_SCC_TO_IOC_41_DP")
	)
	(segment
		(start 144.333976 -37.12845)
		(end 144.647158 -36.92525)
		(width 0.12446)
		(layer "F.Cu")
		(net "PHY_SCC_TO_IOC_41_DP")
	)
	(segment
		(start 145.725134 -36.225226)
		(end 145.804382 -35.852862)
		(width 0.12446)
		(layer "F.Cu")
		(net "PHY_SCC_TO_IOC_41_DP")
	)
	(segment
		(start 142.883636 -37.74948)
		(end 143.256 -37.828474)
		(width 0.12446)
		(layer "F.Cu")
		(net "PHY_SCC_TO_IOC_41_DP")
	)
	(segment
		(start 130.184144 -54.124098)
		(end 130.788918 -54.124098)
		(width 0.0889)
		(layer "F.Cu")
		(net "PHY_SCC_TO_IOC_41_DP")
	)
	(segment
		(start 130.095244 -54.385718)
		(end 130.095244 -54.212998)
		(width 0.0889)
		(layer "F.Cu")
		(net "PHY_SCC_TO_IOC_41_DP")
	)
	(segment
		(start 145.411952 -36.428426)
		(end 145.725134 -36.225226)
		(width 0.12446)
		(layer "F.Cu")
		(net "PHY_SCC_TO_IOC_41_DP")
	)
	(segment
		(start 143.64843 -37.25291)
		(end 143.961612 -37.049456)
		(width 0.12446)
		(layer "F.Cu")
		(net "PHY_SCC_TO_IOC_41_DP")
	)
	(segment
		(start 144.726406 -36.552886)
		(end 145.039588 -36.349432)
		(width 0.12446)
		(layer "F.Cu")
		(net "PHY_SCC_TO_IOC_41_DP")
	)
	(segment
		(start 130.50012 -54.500018)
		(end 130.209544 -54.500018)
		(width 0.0889)
		(layer "F.Cu")
		(net "PHY_SCC_TO_IOC_41_DP")
	)
	(segment
		(start 145.039588 -36.349432)
		(end 145.411952 -36.428426)
		(width 0.12446)
		(layer "F.Cu")
		(net "PHY_SCC_TO_IOC_41_DP")
	)
	(segment
		(start 130.788918 -54.124098)
		(end 131.297426 -53.794152)
		(width 0.0889)
		(layer "F.Cu")
		(net "PHY_SCC_TO_IOC_41_DP")
	)
	(segment
		(start 131.297426 -53.794152)
		(end 131.771136 -53.062632)
		(width 0.0889)
		(layer "F.Cu")
		(net "PHY_SCC_TO_IOC_41_DP")
	)
	(segment
		(start 146.117564 -35.649408)
		(end 146.118072 -35.649408)
		(width 0.12446)
		(layer "F.Cu")
		(net "PHY_SCC_TO_IOC_41_DP")
	)
	(segment
		(start 147.43811 -35.59302)
		(end 147.79625 -35.66922)
		(width 0.12446)
		(layer "F.Cu")
		(net "PHY_SCC_TO_IOC_41_DP")
	)
	(segment
		(start 143.569182 -37.625274)
		(end 143.64843 -37.25291)
		(width 0.12446)
		(layer "F.Cu")
		(net "PHY_SCC_TO_IOC_41_DP")
	)
	(segment
		(start 132.890768 -52.168552)
		(end 141.79677 -38.455092)
		(width 0.12446)
		(layer "F.Cu")
		(net "PHY_SCC_TO_IOC_41_DP")
	)
	(segment
		(start 145.804382 -35.852862)
		(end 146.117564 -35.649408)
		(width 0.12446)
		(layer "F.Cu")
		(net "PHY_SCC_TO_IOC_41_DP")
	)
	(segment
		(start 131.772152 -53.062378)
		(end 131.78409 -53.043836)
		(width 0.0889)
		(layer "F.Cu")
		(net "PHY_SCC_TO_IOC_41_DP")
	)
	(segment
		(start 144.647158 -36.92525)
		(end 144.726406 -36.552886)
		(width 0.12446)
		(layer "F.Cu")
		(net "PHY_SCC_TO_IOC_41_DP")
	)
	(segment
		(start 143.961612 -37.049456)
		(end 144.333976 -37.12845)
		(width 0.12446)
		(layer "F.Cu")
		(net "PHY_SCC_TO_IOC_41_DP")
	)
	(arc
		(start 130.209544 -54.500018)
		(mid 130.128722 -54.46654)
		(end 130.095244 -54.385718)
		(width 0.0889)
		(layer "F.Cu")
		(net "PHY_SCC_TO_IOC_41_DP")
	)
	(arc
		(start 130.095244 -54.212998)
		(mid 130.121282 -54.150136)
		(end 130.184144 -54.124098)
		(width 0.0889)
		(layer "F.Cu")
		(net "PHY_SCC_TO_IOC_41_DP")
	)
	(segment
		(start 146.980148 -35.050984)
		(end 147.46097 -35.153346)
		(width 0.12446)
		(layer "F.Cu")
		(net "PHY_SCC_TO_IOC_41_DN")
	)
	(segment
		(start 131.339844 -53.377592)
		(end 131.495038 -53.137816)
		(width 0.0889)
		(layer "F.Cu")
		(net "PHY_SCC_TO_IOC_41_DN")
	)
	(segment
		(start 147.638008 -35.038284)
		(end 147.917662 -35.097974)
		(width 0.12446)
		(layer "F.Cu")
		(net "PHY_SCC_TO_IOC_41_DN")
	)
	(segment
		(start 131.24942 -53.517546)
		(end 131.249674 -53.517292)
		(width 0.0889)
		(layer "F.Cu")
		(net "PHY_SCC_TO_IOC_41_DN")
	)
	(segment
		(start 130.184144 -53.933598)
		(end 130.732276 -53.933598)
		(width 0.0889)
		(layer "F.Cu")
		(net "PHY_SCC_TO_IOC_41_DN")
	)
	(segment
		(start 131.339844 -53.3781)
		(end 131.339844 -53.377592)
		(width 0.0889)
		(layer "F.Cu")
		(net "PHY_SCC_TO_IOC_41_DN")
	)
	(segment
		(start 147.46097 -35.153346)
		(end 147.638008 -35.038284)
		(width 0.12446)
		(layer "F.Cu")
		(net "PHY_SCC_TO_IOC_41_DN")
	)
	(segment
		(start 130.732276 -53.933598)
		(end 131.159504 -53.656484)
		(width 0.0889)
		(layer "F.Cu")
		(net "PHY_SCC_TO_IOC_41_DN")
	)
	(segment
		(start 146.033998 -35.251644)
		(end 146.980148 -35.050984)
		(width 0.12446)
		(layer "F.Cu")
		(net "PHY_SCC_TO_IOC_41_DN")
	)
	(segment
		(start 131.249674 -53.517292)
		(end 131.339844 -53.3781)
		(width 0.0889)
		(layer "F.Cu")
		(net "PHY_SCC_TO_IOC_41_DN")
	)
	(segment
		(start 132.59689 -51.874674)
		(end 141.502892 -38.161214)
		(width 0.12446)
		(layer "F.Cu")
		(net "PHY_SCC_TO_IOC_41_DN")
	)
	(segment
		(start 131.664964 -52.479702)
		(end 132.59689 -51.874674)
		(width 0.12446)
		(layer "F.Cu")
		(net "PHY_SCC_TO_IOC_41_DN")
	)
	(segment
		(start 145.959576 -35.267392)
		(end 146.033744 -35.251644)
		(width 0.12446)
		(layer "F.Cu")
		(net "PHY_SCC_TO_IOC_41_DN")
	)
	(segment
		(start 131.159504 -53.656484)
		(end 131.24942 -53.517546)
		(width 0.0889)
		(layer "F.Cu")
		(net "PHY_SCC_TO_IOC_41_DN")
	)
	(segment
		(start 131.495038 -53.137816)
		(end 131.431284 -52.84089)
		(width 0.0889)
		(layer "F.Cu")
		(net "PHY_SCC_TO_IOC_41_DN")
	)
	(segment
		(start 131.443476 -52.822094)
		(end 131.664964 -52.479702)
		(width 0.12446)
		(layer "F.Cu")
		(net "PHY_SCC_TO_IOC_41_DN")
	)
	(segment
		(start 141.502892 -38.161214)
		(end 145.959576 -35.267392)
		(width 0.12446)
		(layer "F.Cu")
		(net "PHY_SCC_TO_IOC_41_DN")
	)
	(segment
		(start 131.431284 -52.84089)
		(end 131.443222 -52.822348)
		(width 0.0889)
		(layer "F.Cu")
		(net "PHY_SCC_TO_IOC_41_DN")
	)
	(segment
		(start 129.904744 -54.385718)
		(end 129.904744 -54.212998)
		(width 0.0889)
		(layer "F.Cu")
		(net "PHY_SCC_TO_IOC_41_DN")
	)
	(segment
		(start 131.443222 -52.822348)
		(end 131.443476 -52.822094)
		(width 0.12446)
		(layer "F.Cu")
		(net "PHY_SCC_TO_IOC_41_DN")
	)
	(segment
		(start 146.033744 -35.251644)
		(end 146.033998 -35.251644)
		(width 0.12446)
		(layer "F.Cu")
		(net "PHY_SCC_TO_IOC_41_DN")
	)
	(segment
		(start 129.500122 -54.500018)
		(end 129.790444 -54.500018)
		(width 0.0889)
		(layer "F.Cu")
		(net "PHY_SCC_TO_IOC_41_DN")
	)
	(arc
		(start 129.790444 -54.500018)
		(mid 129.871266 -54.46654)
		(end 129.904744 -54.385718)
		(width 0.0889)
		(layer "F.Cu")
		(net "PHY_SCC_TO_IOC_41_DN")
	)
	(arc
		(start 129.904744 -54.212998)
		(mid 129.986578 -54.015432)
		(end 130.184144 -53.933598)
		(width 0.0889)
		(layer "F.Cu")
		(net "PHY_SCC_TO_IOC_41_DN")
	)
	(segment
		(start 132.696966 -50.20437)
		(end 130.869944 -51.410616)
		(width 0.12446)
		(layer "F.Cu")
		(net "PHY_SCC_TO_IOC_40_DP")
	)
	(segment
		(start 143.266668 -33.955228)
		(end 143.06296 -34.268156)
		(width 0.12446)
		(layer "F.Cu")
		(net "PHY_SCC_TO_IOC_40_DP")
	)
	(segment
		(start 144.975834 -32.921448)
		(end 144.617694 -32.845248)
		(width 0.12446)
		(layer "F.Cu")
		(net "PHY_SCC_TO_IOC_40_DP")
	)
	(segment
		(start 142.938246 -34.953702)
		(end 142.565882 -35.032696)
		(width 0.12446)
		(layer "F.Cu")
		(net "PHY_SCC_TO_IOC_40_DP")
	)
	(segment
		(start 144.548606 -32.740092)
		(end 144.548352 -32.739838)
		(width 0.12446)
		(layer "F.Cu")
		(net "PHY_SCC_TO_IOC_40_DP")
	)
	(segment
		(start 130.33248 -52.500022)
		(end 130.50012 -52.500022)
		(width 0.12446)
		(layer "F.Cu")
		(net "PHY_SCC_TO_IOC_40_DP")
	)
	(segment
		(start 142.362174 -35.345624)
		(end 142.450566 -35.762692)
		(width 0.12446)
		(layer "F.Cu")
		(net "PHY_SCC_TO_IOC_40_DP")
	)
	(segment
		(start 144.4752 -32.72409)
		(end 144.402302 -32.708596)
		(width 0.12446)
		(layer "F.Cu")
		(net "PHY_SCC_TO_IOC_40_DP")
	)
	(segment
		(start 143.639032 -33.876234)
		(end 143.266668 -33.955228)
		(width 0.12446)
		(layer "F.Cu")
		(net "PHY_SCC_TO_IOC_40_DP")
	)
	(segment
		(start 143.84274 -33.563306)
		(end 143.639032 -33.876234)
		(width 0.12446)
		(layer "F.Cu")
		(net "PHY_SCC_TO_IOC_40_DP")
	)
	(segment
		(start 142.450566 -35.762692)
		(end 142.246858 -36.07562)
		(width 0.12446)
		(layer "F.Cu")
		(net "PHY_SCC_TO_IOC_40_DP")
	)
	(segment
		(start 144.548352 -32.739838)
		(end 144.4752 -32.72409)
		(width 0.12446)
		(layer "F.Cu")
		(net "PHY_SCC_TO_IOC_40_DP")
	)
	(segment
		(start 143.06296 -34.268156)
		(end 143.141954 -34.640774)
		(width 0.12446)
		(layer "F.Cu")
		(net "PHY_SCC_TO_IOC_40_DP")
	)
	(segment
		(start 142.246858 -36.07562)
		(end 141.830298 -36.163758)
		(width 0.12446)
		(layer "F.Cu")
		(net "PHY_SCC_TO_IOC_40_DP")
	)
	(segment
		(start 143.763746 -33.190688)
		(end 143.84274 -33.563306)
		(width 0.12446)
		(layer "F.Cu")
		(net "PHY_SCC_TO_IOC_40_DP")
	)
	(segment
		(start 130.869944 -51.410616)
		(end 130.410712 -51.869848)
		(width 0.12446)
		(layer "F.Cu")
		(net "PHY_SCC_TO_IOC_40_DP")
	)
	(segment
		(start 141.830298 -36.163758)
		(end 132.696966 -50.20437)
		(width 0.12446)
		(layer "F.Cu")
		(net "PHY_SCC_TO_IOC_40_DP")
	)
	(segment
		(start 144.143222 -32.763968)
		(end 143.967454 -32.87776)
		(width 0.12446)
		(layer "F.Cu")
		(net "PHY_SCC_TO_IOC_40_DP")
	)
	(segment
		(start 144.402302 -32.708596)
		(end 144.143222 -32.763968)
		(width 0.12446)
		(layer "F.Cu")
		(net "PHY_SCC_TO_IOC_40_DP")
	)
	(segment
		(start 143.967454 -32.87776)
		(end 143.763746 -33.190688)
		(width 0.12446)
		(layer "F.Cu")
		(net "PHY_SCC_TO_IOC_40_DP")
	)
	(segment
		(start 143.141954 -34.640774)
		(end 142.938246 -34.953702)
		(width 0.12446)
		(layer "F.Cu")
		(net "PHY_SCC_TO_IOC_40_DP")
	)
	(segment
		(start 142.565882 -35.032696)
		(end 142.362174 -35.345624)
		(width 0.12446)
		(layer "F.Cu")
		(net "PHY_SCC_TO_IOC_40_DP")
	)
	(segment
		(start 144.617694 -32.845248)
		(end 144.548606 -32.740092)
		(width 0.12446)
		(layer "F.Cu")
		(net "PHY_SCC_TO_IOC_40_DP")
	)
	(arc
		(start 130.410712 -51.869848)
		(mid 130.257105 -52.099643)
		(end 130.203194 -52.370736)
		(width 0.12446)
		(layer "F.Cu")
		(net "PHY_SCC_TO_IOC_40_DP")
	)
	(arc
		(start 130.24104 -52.462176)
		(mid 130.282993 -52.490208)
		(end 130.33248 -52.500022)
		(width 0.12446)
		(layer "F.Cu")
		(net "PHY_SCC_TO_IOC_40_DP")
	)
	(arc
		(start 130.203194 -52.370736)
		(mid 130.213035 -52.420212)
		(end 130.24104 -52.462176)
		(width 0.12446)
		(layer "F.Cu")
		(net "PHY_SCC_TO_IOC_40_DP")
	)
	(segment
		(start 129.642362 -52.500022)
		(end 129.500122 -52.500022)
		(width 0.12446)
		(layer "F.Cu")
		(net "PHY_SCC_TO_IOC_40_DN")
	)
	(segment
		(start 130.611626 -51.094132)
		(end 130.123184 -51.582574)
		(width 0.12446)
		(layer "F.Cu")
		(net "PHY_SCC_TO_IOC_40_DN")
	)
	(segment
		(start 144.523206 -32.318706)
		(end 144.40154 -32.293052)
		(width 0.12446)
		(layer "F.Cu")
		(net "PHY_SCC_TO_IOC_40_DN")
	)
	(segment
		(start 143.67383 -32.583374)
		(end 132.402326 -49.911762)
		(width 0.12446)
		(layer "F.Cu")
		(net "PHY_SCC_TO_IOC_40_DN")
	)
	(segment
		(start 144.40154 -32.293052)
		(end 143.98498 -32.381952)
		(width 0.12446)
		(layer "F.Cu")
		(net "PHY_SCC_TO_IOC_40_DN")
	)
	(segment
		(start 144.739106 -32.273748)
		(end 144.633696 -32.342328)
		(width 0.12446)
		(layer "F.Cu")
		(net "PHY_SCC_TO_IOC_40_DN")
	)
	(segment
		(start 145.097246 -32.349948)
		(end 144.739106 -32.273748)
		(width 0.12446)
		(layer "F.Cu")
		(net "PHY_SCC_TO_IOC_40_DN")
	)
	(segment
		(start 143.98498 -32.381952)
		(end 143.67383 -32.583374)
		(width 0.12446)
		(layer "F.Cu")
		(net "PHY_SCC_TO_IOC_40_DN")
	)
	(segment
		(start 144.633696 -32.342328)
		(end 144.541748 -32.322516)
		(width 0.12446)
		(layer "F.Cu")
		(net "PHY_SCC_TO_IOC_40_DN")
	)
	(segment
		(start 144.541748 -32.322516)
		(end 144.523206 -32.318706)
		(width 0.12446)
		(layer "F.Cu")
		(net "PHY_SCC_TO_IOC_40_DN")
	)
	(segment
		(start 130.123184 -51.582574)
		(end 130.123184 -51.58232)
		(width 0.12446)
		(layer "F.Cu")
		(net "PHY_SCC_TO_IOC_40_DN")
	)
	(segment
		(start 132.402326 -49.911762)
		(end 130.611626 -51.094132)
		(width 0.12446)
		(layer "F.Cu")
		(net "PHY_SCC_TO_IOC_40_DN")
	)
	(arc
		(start 130.123184 -51.58232)
		(mid 129.886309 -51.932445)
		(end 129.796794 -52.34559)
		(width 0.12446)
		(layer "F.Cu")
		(net "PHY_SCC_TO_IOC_40_DN")
	)
	(arc
		(start 129.751582 -52.45481)
		(mid 129.701471 -52.488293)
		(end 129.642362 -52.500022)
		(width 0.12446)
		(layer "F.Cu")
		(net "PHY_SCC_TO_IOC_40_DN")
	)
	(arc
		(start 129.796794 -52.34559)
		(mid 129.785039 -52.404689)
		(end 129.751582 -52.45481)
		(width 0.12446)
		(layer "F.Cu")
		(net "PHY_SCC_TO_IOC_40_DN")
	)
	(segment
		(start 130.50012 -72.500236)
		(end 130.999992 -73.000108)
		(width 0.104902)
		(layer "F.Cu")
		(net "PHY_SCC_TO_DPB_7_DP")
	)
	(via
		(at 130.999992 -73.000108)
		(size 0.4572)
		(drill 0.2032)
		(layers "F.Cu" "B.Cu")
		(net "PHY_SCC_TO_DPB_7_DP")
	)
	(segment
		(start 148.471128 -10.347706)
		(end 148.820632 -10.347706)
		(width 0.1016)
		(layer "In5.Cu")
		(net "PHY_SCC_TO_DPB_7_DP")
	)
	(segment
		(start 148.999956 -10.168382)
		(end 148.999956 -9.800082)
		(width 0.1016)
		(layer "In5.Cu")
		(net "PHY_SCC_TO_DPB_7_DP")
	)
	(segment
		(start 141.969998 -69.750432)
		(end 142.233396 -69.806312)
		(width 0.1016)
		(layer "In5.Cu")
		(net "PHY_SCC_TO_DPB_7_DP")
	)
	(segment
		(start 144.292574 -68.469764)
		(end 146.10207 -65.684146)
		(width 0.1016)
		(layer "In5.Cu")
		(net "PHY_SCC_TO_DPB_7_DP")
	)
	(segment
		(start 142.233396 -69.806312)
		(end 142.489174 -69.64045)
		(width 0.1016)
		(layer "In5.Cu")
		(net "PHY_SCC_TO_DPB_7_DP")
	)
	(segment
		(start 139.11453 -71.8312)
		(end 140.827506 -70.719188)
		(width 0.1016)
		(layer "In5.Cu")
		(net "PHY_SCC_TO_DPB_7_DP")
	)
	(segment
		(start 142.489174 -69.64045)
		(end 142.545054 -69.377052)
		(width 0.1016)
		(layer "In5.Cu")
		(net "PHY_SCC_TO_DPB_7_DP")
	)
	(segment
		(start 143.06423 -69.26707)
		(end 144.292574 -68.469764)
		(width 0.1016)
		(layer "In5.Cu")
		(net "PHY_SCC_TO_DPB_7_DP")
	)
	(segment
		(start 130.671316 -73.826116)
		(end 130.8354 -73.9902)
		(width 0.1016)
		(layer "In5.Cu")
		(net "PHY_SCC_TO_DPB_7_DP")
	)
	(segment
		(start 130.999992 -73.000108)
		(end 130.684016 -73.000108)
		(width 0.0889)
		(layer "In5.Cu")
		(net "PHY_SCC_TO_DPB_7_DP")
	)
	(segment
		(start 134.463282 -71.8312)
		(end 139.11453 -71.8312)
		(width 0.1016)
		(layer "In5.Cu")
		(net "PHY_SCC_TO_DPB_7_DP")
	)
	(segment
		(start 130.671316 -73.5584)
		(end 130.671316 -73.605898)
		(width 0.0889)
		(layer "In5.Cu")
		(net "PHY_SCC_TO_DPB_7_DP")
	)
	(segment
		(start 132.304282 -73.9902)
		(end 134.463282 -71.8312)
		(width 0.1016)
		(layer "In5.Cu")
		(net "PHY_SCC_TO_DPB_7_DP")
	)
	(segment
		(start 147.947634 -13.493242)
		(end 147.947634 -10.8712)
		(width 0.1016)
		(layer "In5.Cu")
		(net "PHY_SCC_TO_DPB_7_DP")
	)
	(segment
		(start 140.883386 -70.45579)
		(end 141.139164 -70.289928)
		(width 0.1016)
		(layer "In5.Cu")
		(net "PHY_SCC_TO_DPB_7_DP")
	)
	(segment
		(start 143.920718 -32.438594)
		(end 147.947634 -13.493242)
		(width 0.1016)
		(layer "In5.Cu")
		(net "PHY_SCC_TO_DPB_7_DP")
	)
	(segment
		(start 141.65834 -70.179946)
		(end 141.714474 -69.916294)
		(width 0.1016)
		(layer "In5.Cu")
		(net "PHY_SCC_TO_DPB_7_DP")
	)
	(segment
		(start 144.849596 -49.933352)
		(end 146.24431 -43.371008)
		(width 0.1016)
		(layer "In5.Cu")
		(net "PHY_SCC_TO_DPB_7_DP")
	)
	(segment
		(start 146.10207 -65.684146)
		(end 147.149566 -60.752736)
		(width 0.1016)
		(layer "In5.Cu")
		(net "PHY_SCC_TO_DPB_7_DP")
	)
	(segment
		(start 130.595116 -73.089008)
		(end 130.595116 -73.4822)
		(width 0.0889)
		(layer "In5.Cu")
		(net "PHY_SCC_TO_DPB_7_DP")
	)
	(segment
		(start 130.671316 -73.605898)
		(end 130.671316 -73.826116)
		(width 0.1016)
		(layer "In5.Cu")
		(net "PHY_SCC_TO_DPB_7_DP")
	)
	(segment
		(start 140.827506 -70.719188)
		(end 140.883386 -70.45579)
		(width 0.1016)
		(layer "In5.Cu")
		(net "PHY_SCC_TO_DPB_7_DP")
	)
	(segment
		(start 141.714474 -69.916294)
		(end 141.969998 -69.750432)
		(width 0.1016)
		(layer "In5.Cu")
		(net "PHY_SCC_TO_DPB_7_DP")
	)
	(segment
		(start 142.800832 -69.21119)
		(end 143.06423 -69.26707)
		(width 0.1016)
		(layer "In5.Cu")
		(net "PHY_SCC_TO_DPB_7_DP")
	)
	(segment
		(start 130.8354 -73.9902)
		(end 132.304282 -73.9902)
		(width 0.1016)
		(layer "In5.Cu")
		(net "PHY_SCC_TO_DPB_7_DP")
	)
	(segment
		(start 146.24431 -43.371008)
		(end 143.920718 -32.438594)
		(width 0.1016)
		(layer "In5.Cu")
		(net "PHY_SCC_TO_DPB_7_DP")
	)
	(segment
		(start 147.149566 -60.752736)
		(end 144.849596 -49.933352)
		(width 0.1016)
		(layer "In5.Cu")
		(net "PHY_SCC_TO_DPB_7_DP")
	)
	(segment
		(start 141.139164 -70.289928)
		(end 141.402562 -70.345808)
		(width 0.1016)
		(layer "In5.Cu")
		(net "PHY_SCC_TO_DPB_7_DP")
	)
	(segment
		(start 142.545054 -69.377052)
		(end 142.800832 -69.21119)
		(width 0.1016)
		(layer "In5.Cu")
		(net "PHY_SCC_TO_DPB_7_DP")
	)
	(segment
		(start 141.402562 -70.345808)
		(end 141.65834 -70.179946)
		(width 0.1016)
		(layer "In5.Cu")
		(net "PHY_SCC_TO_DPB_7_DP")
	)
	(segment
		(start 130.595116 -73.4822)
		(end 130.671316 -73.5584)
		(width 0.0889)
		(layer "In5.Cu")
		(net "PHY_SCC_TO_DPB_7_DP")
	)
	(arc
		(start 147.947634 -10.8712)
		(mid 148.100962 -10.501034)
		(end 148.471128 -10.347706)
		(width 0.1016)
		(layer "In5.Cu")
		(net "PHY_SCC_TO_DPB_7_DP")
	)
	(arc
		(start 130.684016 -73.000108)
		(mid 130.621154 -73.026146)
		(end 130.595116 -73.089008)
		(width 0.0889)
		(layer "In5.Cu")
		(net "PHY_SCC_TO_DPB_7_DP")
	)
	(arc
		(start 148.820632 -10.347706)
		(mid 148.947433 -10.295183)
		(end 148.999956 -10.168382)
		(width 0.1016)
		(layer "In5.Cu")
		(net "PHY_SCC_TO_DPB_7_DP")
	)
	(segment
		(start 129.500122 -72.500236)
		(end 129.999994 -73.000108)
		(width 0.104902)
		(layer "F.Cu")
		(net "PHY_SCC_TO_DPB_7_DN")
	)
	(via
		(at 129.999994 -73.000108)
		(size 0.4572)
		(drill 0.2032)
		(layers "F.Cu" "B.Cu")
		(net "PHY_SCC_TO_DPB_7_DN")
	)
	(segment
		(start 148.471128 -10.652506)
		(end 148.820632 -10.652506)
		(width 0.1016)
		(layer "In5.Cu")
		(net "PHY_SCC_TO_DPB_7_DN")
	)
	(segment
		(start 130.366516 -73.605898)
		(end 130.366516 -73.952608)
		(width 0.1016)
		(layer "In5.Cu")
		(net "PHY_SCC_TO_DPB_7_DN")
	)
	(segment
		(start 146.388582 -65.802764)
		(end 147.461224 -60.752736)
		(width 0.1016)
		(layer "In5.Cu")
		(net "PHY_SCC_TO_DPB_7_DN")
	)
	(segment
		(start 145.161254 -49.933352)
		(end 146.555968 -43.371008)
		(width 0.1016)
		(layer "In5.Cu")
		(net "PHY_SCC_TO_DPB_7_DN")
	)
	(segment
		(start 148.252434 -13.5255)
		(end 148.252434 -10.8712)
		(width 0.1016)
		(layer "In5.Cu")
		(net "PHY_SCC_TO_DPB_7_DN")
	)
	(segment
		(start 132.430774 -74.295)
		(end 134.589774 -72.136)
		(width 0.1016)
		(layer "In5.Cu")
		(net "PHY_SCC_TO_DPB_7_DN")
	)
	(segment
		(start 139.204954 -72.136)
		(end 144.513046 -68.690236)
		(width 0.1016)
		(layer "In5.Cu")
		(net "PHY_SCC_TO_DPB_7_DN")
	)
	(segment
		(start 130.708908 -74.295)
		(end 132.430774 -74.295)
		(width 0.1016)
		(layer "In5.Cu")
		(net "PHY_SCC_TO_DPB_7_DN")
	)
	(segment
		(start 146.555968 -43.371008)
		(end 144.232376 -32.438594)
		(width 0.1016)
		(layer "In5.Cu")
		(net "PHY_SCC_TO_DPB_7_DN")
	)
	(segment
		(start 129.999994 -73.000108)
		(end 130.315716 -73.000108)
		(width 0.0889)
		(layer "In5.Cu")
		(net "PHY_SCC_TO_DPB_7_DN")
	)
	(segment
		(start 130.404616 -73.089008)
		(end 130.404616 -73.5457)
		(width 0.0889)
		(layer "In5.Cu")
		(net "PHY_SCC_TO_DPB_7_DN")
	)
	(segment
		(start 144.232376 -32.438594)
		(end 148.252434 -13.5255)
		(width 0.1016)
		(layer "In5.Cu")
		(net "PHY_SCC_TO_DPB_7_DN")
	)
	(segment
		(start 144.513046 -68.690236)
		(end 146.388582 -65.802764)
		(width 0.1016)
		(layer "In5.Cu")
		(net "PHY_SCC_TO_DPB_7_DN")
	)
	(segment
		(start 147.461224 -60.752736)
		(end 145.161254 -49.933352)
		(width 0.1016)
		(layer "In5.Cu")
		(net "PHY_SCC_TO_DPB_7_DN")
	)
	(segment
		(start 130.366516 -73.5838)
		(end 130.366516 -73.605898)
		(width 0.0889)
		(layer "In5.Cu")
		(net "PHY_SCC_TO_DPB_7_DN")
	)
	(segment
		(start 130.366516 -73.952608)
		(end 130.708908 -74.295)
		(width 0.1016)
		(layer "In5.Cu")
		(net "PHY_SCC_TO_DPB_7_DN")
	)
	(segment
		(start 130.404616 -73.5457)
		(end 130.366516 -73.5838)
		(width 0.0889)
		(layer "In5.Cu")
		(net "PHY_SCC_TO_DPB_7_DN")
	)
	(segment
		(start 134.589774 -72.136)
		(end 139.204954 -72.136)
		(width 0.1016)
		(layer "In5.Cu")
		(net "PHY_SCC_TO_DPB_7_DN")
	)
	(segment
		(start 148.999956 -10.83183)
		(end 148.999956 -11.20013)
		(width 0.1016)
		(layer "In5.Cu")
		(net "PHY_SCC_TO_DPB_7_DN")
	)
	(arc
		(start 130.315716 -73.000108)
		(mid 130.378578 -73.026146)
		(end 130.404616 -73.089008)
		(width 0.0889)
		(layer "In5.Cu")
		(net "PHY_SCC_TO_DPB_7_DN")
	)
	(arc
		(start 148.820632 -10.652506)
		(mid 148.947433 -10.705029)
		(end 148.999956 -10.83183)
		(width 0.1016)
		(layer "In5.Cu")
		(net "PHY_SCC_TO_DPB_7_DN")
	)
	(arc
		(start 148.252434 -10.8712)
		(mid 148.316488 -10.71656)
		(end 148.471128 -10.652506)
		(width 0.1016)
		(layer "In5.Cu")
		(net "PHY_SCC_TO_DPB_7_DN")
	)
	(segment
		(start 129.500122 -71.500238)
		(end 129.999994 -72.00011)
		(width 0.104902)
		(layer "F.Cu")
		(net "PHY_SCC_TO_DPB_6_DP")
	)
	(via
		(at 129.999994 -72.00011)
		(size 0.4572)
		(drill 0.2032)
		(layers "F.Cu" "B.Cu")
		(net "PHY_SCC_TO_DPB_6_DP")
	)
	(segment
		(start 147.200112 -11.368278)
		(end 147.200112 -10.999978)
		(width 0.1016)
		(layer "In5.Cu")
		(net "PHY_SCC_TO_DPB_6_DP")
	)
	(segment
		(start 141.929866 -68.24472)
		(end 143.473424 -67.242182)
		(width 0.1016)
		(layer "In5.Cu")
		(net "PHY_SCC_TO_DPB_6_DP")
	)
	(segment
		(start 131.331208 -72.346312)
		(end 131.445 -72.346312)
		(width 0.0889)
		(layer "In5.Cu")
		(net "PHY_SCC_TO_DPB_6_DP")
	)
	(segment
		(start 146.14779 -15.815564)
		(end 146.14779 -12.071096)
		(width 0.1016)
		(layer "In5.Cu")
		(net "PHY_SCC_TO_DPB_6_DP")
	)
	(segment
		(start 129.999994 -72.00011)
		(end 129.684018 -72.00011)
		(width 0.0889)
		(layer "In5.Cu")
		(net "PHY_SCC_TO_DPB_6_DP")
	)
	(segment
		(start 140.523976 -69.15785)
		(end 140.58011 -68.894452)
		(width 0.1016)
		(layer "In5.Cu")
		(net "PHY_SCC_TO_DPB_6_DP")
	)
	(segment
		(start 140.835634 -68.728336)
		(end 141.099286 -68.78447)
		(width 0.1016)
		(layer "In5.Cu")
		(net "PHY_SCC_TO_DPB_6_DP")
	)
	(segment
		(start 141.099286 -68.78447)
		(end 141.35481 -68.618354)
		(width 0.1016)
		(layer "In5.Cu")
		(net "PHY_SCC_TO_DPB_6_DP")
	)
	(segment
		(start 140.58011 -68.894452)
		(end 140.835634 -68.728336)
		(width 0.1016)
		(layer "In5.Cu")
		(net "PHY_SCC_TO_DPB_6_DP")
	)
	(segment
		(start 144.963134 -64.948562)
		(end 145.881852 -60.624466)
		(width 0.1016)
		(layer "In5.Cu")
		(net "PHY_SCC_TO_DPB_6_DP")
	)
	(segment
		(start 129.742946 -72.403462)
		(end 131.274058 -72.403462)
		(width 0.0889)
		(layer "In5.Cu")
		(net "PHY_SCC_TO_DPB_6_DP")
	)
	(segment
		(start 143.473424 -67.242182)
		(end 144.963134 -64.948562)
		(width 0.1016)
		(layer "In5.Cu")
		(net "PHY_SCC_TO_DPB_6_DP")
	)
	(segment
		(start 129.595118 -72.08901)
		(end 129.595118 -72.279764)
		(width 0.0889)
		(layer "In5.Cu")
		(net "PHY_SCC_TO_DPB_6_DP")
	)
	(segment
		(start 141.35481 -68.618354)
		(end 141.410944 -68.354702)
		(width 0.1016)
		(layer "In5.Cu")
		(net "PHY_SCC_TO_DPB_6_DP")
	)
	(segment
		(start 132.36702 -72.346312)
		(end 134.507732 -70.2056)
		(width 0.1016)
		(layer "In5.Cu")
		(net "PHY_SCC_TO_DPB_6_DP")
	)
	(segment
		(start 143.71828 -50.447956)
		(end 145.19021 -43.526964)
		(width 0.1016)
		(layer "In5.Cu")
		(net "PHY_SCC_TO_DPB_6_DP")
	)
	(segment
		(start 142.723616 -31.924244)
		(end 146.14779 -15.815564)
		(width 0.1016)
		(layer "In5.Cu")
		(net "PHY_SCC_TO_DPB_6_DP")
	)
	(segment
		(start 141.410944 -68.354702)
		(end 141.666468 -68.188586)
		(width 0.1016)
		(layer "In5.Cu")
		(net "PHY_SCC_TO_DPB_6_DP")
	)
	(segment
		(start 146.671284 -11.547602)
		(end 147.020788 -11.547602)
		(width 0.1016)
		(layer "In5.Cu")
		(net "PHY_SCC_TO_DPB_6_DP")
	)
	(segment
		(start 134.507732 -70.2056)
		(end 138.91133 -70.2056)
		(width 0.1016)
		(layer "In5.Cu")
		(net "PHY_SCC_TO_DPB_6_DP")
	)
	(segment
		(start 131.445 -72.346312)
		(end 132.36702 -72.346312)
		(width 0.1016)
		(layer "In5.Cu")
		(net "PHY_SCC_TO_DPB_6_DP")
	)
	(segment
		(start 145.19021 -43.526964)
		(end 142.723616 -31.924244)
		(width 0.1016)
		(layer "In5.Cu")
		(net "PHY_SCC_TO_DPB_6_DP")
	)
	(segment
		(start 145.881852 -60.624466)
		(end 143.71828 -50.447956)
		(width 0.1016)
		(layer "In5.Cu")
		(net "PHY_SCC_TO_DPB_6_DP")
	)
	(segment
		(start 131.274058 -72.403462)
		(end 131.331208 -72.346312)
		(width 0.0889)
		(layer "In5.Cu")
		(net "PHY_SCC_TO_DPB_6_DP")
	)
	(segment
		(start 138.91133 -70.2056)
		(end 140.523976 -69.15785)
		(width 0.1016)
		(layer "In5.Cu")
		(net "PHY_SCC_TO_DPB_6_DP")
	)
	(segment
		(start 141.666468 -68.188586)
		(end 141.929866 -68.24472)
		(width 0.1016)
		(layer "In5.Cu")
		(net "PHY_SCC_TO_DPB_6_DP")
	)
	(segment
		(start 129.62128 -72.34301)
		(end 129.638552 -72.360028)
		(width 0.0889)
		(layer "In5.Cu")
		(net "PHY_SCC_TO_DPB_6_DP")
	)
	(arc
		(start 129.595118 -72.279764)
		(mid 129.601871 -72.314004)
		(end 129.62128 -72.34301)
		(width 0.0889)
		(layer "In5.Cu")
		(net "PHY_SCC_TO_DPB_6_DP")
	)
	(arc
		(start 129.638552 -72.360028)
		(mid 129.686433 -72.392114)
		(end 129.742946 -72.403462)
		(width 0.0889)
		(layer "In5.Cu")
		(net "PHY_SCC_TO_DPB_6_DP")
	)
	(arc
		(start 146.14779 -12.071096)
		(mid 146.301118 -11.70093)
		(end 146.671284 -11.547602)
		(width 0.1016)
		(layer "In5.Cu")
		(net "PHY_SCC_TO_DPB_6_DP")
	)
	(arc
		(start 147.020788 -11.547602)
		(mid 147.147589 -11.495079)
		(end 147.200112 -11.368278)
		(width 0.1016)
		(layer "In5.Cu")
		(net "PHY_SCC_TO_DPB_6_DP")
	)
	(arc
		(start 129.684018 -72.00011)
		(mid 129.621156 -72.026148)
		(end 129.595118 -72.08901)
		(width 0.0889)
		(layer "In5.Cu")
		(net "PHY_SCC_TO_DPB_6_DP")
	)
	(segment
		(start 128.500124 -71.500238)
		(end 128.999996 -72.00011)
		(width 0.104902)
		(layer "F.Cu")
		(net "PHY_SCC_TO_DPB_6_DN")
	)
	(via
		(at 128.999996 -72.00011)
		(size 0.4572)
		(drill 0.2032)
		(layers "F.Cu" "B.Cu")
		(net "PHY_SCC_TO_DPB_6_DN")
	)
	(segment
		(start 129.487168 -72.478646)
		(end 129.504186 -72.49541)
		(width 0.0889)
		(layer "In5.Cu")
		(net "PHY_SCC_TO_DPB_6_DN")
	)
	(segment
		(start 146.45259 -15.847822)
		(end 146.45259 -12.071096)
		(width 0.1016)
		(layer "In5.Cu")
		(net "PHY_SCC_TO_DPB_6_DN")
	)
	(segment
		(start 129.742692 -72.593962)
		(end 131.274058 -72.593962)
		(width 0.0889)
		(layer "In5.Cu")
		(net "PHY_SCC_TO_DPB_6_DN")
	)
	(segment
		(start 128.999996 -72.00011)
		(end 129.315718 -72.00011)
		(width 0.0889)
		(layer "In5.Cu")
		(net "PHY_SCC_TO_DPB_6_DN")
	)
	(segment
		(start 146.19351 -60.624466)
		(end 144.029938 -50.447956)
		(width 0.1016)
		(layer "In5.Cu")
		(net "PHY_SCC_TO_DPB_6_DN")
	)
	(segment
		(start 134.634224 -70.5104)
		(end 139.001754 -70.5104)
		(width 0.1016)
		(layer "In5.Cu")
		(net "PHY_SCC_TO_DPB_6_DN")
	)
	(segment
		(start 131.331208 -72.651112)
		(end 131.353306 -72.651112)
		(width 0.0889)
		(layer "In5.Cu")
		(net "PHY_SCC_TO_DPB_6_DN")
	)
	(segment
		(start 147.200112 -12.031726)
		(end 147.200112 -12.400026)
		(width 0.1016)
		(layer "In5.Cu")
		(net "PHY_SCC_TO_DPB_6_DN")
	)
	(segment
		(start 144.029938 -50.447956)
		(end 145.501868 -43.526964)
		(width 0.1016)
		(layer "In5.Cu")
		(net "PHY_SCC_TO_DPB_6_DN")
	)
	(segment
		(start 145.249646 -65.06718)
		(end 146.19351 -60.624466)
		(width 0.1016)
		(layer "In5.Cu")
		(net "PHY_SCC_TO_DPB_6_DN")
	)
	(segment
		(start 146.671284 -11.852402)
		(end 147.020788 -11.852402)
		(width 0.1016)
		(layer "In5.Cu")
		(net "PHY_SCC_TO_DPB_6_DN")
	)
	(segment
		(start 132.493512 -72.651112)
		(end 134.634224 -70.5104)
		(width 0.1016)
		(layer "In5.Cu")
		(net "PHY_SCC_TO_DPB_6_DN")
	)
	(segment
		(start 143.693896 -67.462654)
		(end 145.249646 -65.06718)
		(width 0.1016)
		(layer "In5.Cu")
		(net "PHY_SCC_TO_DPB_6_DN")
	)
	(segment
		(start 131.353306 -72.651112)
		(end 132.493512 -72.651112)
		(width 0.1016)
		(layer "In5.Cu")
		(net "PHY_SCC_TO_DPB_6_DN")
	)
	(segment
		(start 129.404618 -72.08901)
		(end 129.404618 -72.27951)
		(width 0.0889)
		(layer "In5.Cu")
		(net "PHY_SCC_TO_DPB_6_DN")
	)
	(segment
		(start 143.035274 -31.924244)
		(end 146.45259 -15.847822)
		(width 0.1016)
		(layer "In5.Cu")
		(net "PHY_SCC_TO_DPB_6_DN")
	)
	(segment
		(start 145.501868 -43.526964)
		(end 143.035274 -31.924244)
		(width 0.1016)
		(layer "In5.Cu")
		(net "PHY_SCC_TO_DPB_6_DN")
	)
	(segment
		(start 139.001754 -70.5104)
		(end 143.693896 -67.462654)
		(width 0.1016)
		(layer "In5.Cu")
		(net "PHY_SCC_TO_DPB_6_DN")
	)
	(segment
		(start 131.274058 -72.593962)
		(end 131.331208 -72.651112)
		(width 0.0889)
		(layer "In5.Cu")
		(net "PHY_SCC_TO_DPB_6_DN")
	)
	(arc
		(start 146.45259 -12.071096)
		(mid 146.516644 -11.916456)
		(end 146.671284 -11.852402)
		(width 0.1016)
		(layer "In5.Cu")
		(net "PHY_SCC_TO_DPB_6_DN")
	)
	(arc
		(start 129.404618 -72.27951)
		(mid 129.425945 -72.38734)
		(end 129.487168 -72.478646)
		(width 0.0889)
		(layer "In5.Cu")
		(net "PHY_SCC_TO_DPB_6_DN")
	)
	(arc
		(start 129.504186 -72.49541)
		(mid 129.613669 -72.568342)
		(end 129.742692 -72.593962)
		(width 0.0889)
		(layer "In5.Cu")
		(net "PHY_SCC_TO_DPB_6_DN")
	)
	(arc
		(start 129.315718 -72.00011)
		(mid 129.37858 -72.026148)
		(end 129.404618 -72.08901)
		(width 0.0889)
		(layer "In5.Cu")
		(net "PHY_SCC_TO_DPB_6_DN")
	)
	(arc
		(start 147.020788 -11.852402)
		(mid 147.147589 -11.904925)
		(end 147.200112 -12.031726)
		(width 0.1016)
		(layer "In5.Cu")
		(net "PHY_SCC_TO_DPB_6_DN")
	)
	(segment
		(start 130.50012 -70.50024)
		(end 130.999992 -71.000112)
		(width 0.104902)
		(layer "F.Cu")
		(net "PHY_SCC_TO_DPB_5_DP")
	)
	(via
		(at 130.999992 -71.000112)
		(size 0.4572)
		(drill 0.2032)
		(layers "F.Cu" "B.Cu")
		(net "PHY_SCC_TO_DPB_5_DP")
	)
	(segment
		(start 144.347692 -10.8712)
		(end 144.347692 -18.469356)
		(width 0.1016)
		(layer "In5.Cu")
		(net "PHY_SCC_TO_DPB_5_DP")
	)
	(segment
		(start 142.553944 -50.734468)
		(end 144.640808 -60.553092)
		(width 0.1016)
		(layer "In5.Cu")
		(net "PHY_SCC_TO_DPB_5_DP")
	)
	(segment
		(start 130.634994 -71.367142)
		(end 130.63474 -71.366888)
		(width 0.0889)
		(layer "In5.Cu")
		(net "PHY_SCC_TO_DPB_5_DP")
	)
	(segment
		(start 144.347692 -18.469356)
		(end 141.547342 -31.645098)
		(width 0.1016)
		(layer "In5.Cu")
		(net "PHY_SCC_TO_DPB_5_DP")
	)
	(segment
		(start 130.684016 -71.000112)
		(end 130.999992 -71.000112)
		(width 0.0889)
		(layer "In5.Cu")
		(net "PHY_SCC_TO_DPB_5_DP")
	)
	(segment
		(start 141.547342 -31.645098)
		(end 144.079468 -43.557952)
		(width 0.1016)
		(layer "In5.Cu")
		(net "PHY_SCC_TO_DPB_5_DP")
	)
	(segment
		(start 143.772382 -64.640968)
		(end 142.93215 -65.935098)
		(width 0.1016)
		(layer "In5.Cu")
		(net "PHY_SCC_TO_DPB_5_DP")
	)
	(segment
		(start 139.80922 -67.962526)
		(end 139.553696 -68.128388)
		(width 0.1016)
		(layer "In5.Cu")
		(net "PHY_SCC_TO_DPB_5_DP")
	)
	(segment
		(start 131.346194 -71.349362)
		(end 131.289044 -71.406512)
		(width 0.0889)
		(layer "In5.Cu")
		(net "PHY_SCC_TO_DPB_5_DP")
	)
	(segment
		(start 131.459986 -71.349362)
		(end 131.346194 -71.349362)
		(width 0.0889)
		(layer "In5.Cu")
		(net "PHY_SCC_TO_DPB_5_DP")
	)
	(segment
		(start 140.38453 -67.588892)
		(end 140.121132 -67.533012)
		(width 0.1016)
		(layer "In5.Cu")
		(net "PHY_SCC_TO_DPB_5_DP")
	)
	(segment
		(start 140.121132 -67.533012)
		(end 139.865354 -67.698874)
		(width 0.1016)
		(layer "In5.Cu")
		(net "PHY_SCC_TO_DPB_5_DP")
	)
	(segment
		(start 142.93215 -65.935098)
		(end 140.38453 -67.588892)
		(width 0.1016)
		(layer "In5.Cu")
		(net "PHY_SCC_TO_DPB_5_DP")
	)
	(segment
		(start 131.289044 -71.406512)
		(end 130.730498 -71.406512)
		(width 0.0889)
		(layer "In5.Cu")
		(net "PHY_SCC_TO_DPB_5_DP")
	)
	(segment
		(start 145.22069 -10.347706)
		(end 144.871186 -10.347706)
		(width 0.1016)
		(layer "In5.Cu")
		(net "PHY_SCC_TO_DPB_5_DP")
	)
	(segment
		(start 139.034774 -68.238116)
		(end 138.97864 -68.501768)
		(width 0.1016)
		(layer "In5.Cu")
		(net "PHY_SCC_TO_DPB_5_DP")
	)
	(segment
		(start 134.67588 -68.6816)
		(end 132.008118 -71.349362)
		(width 0.1016)
		(layer "In5.Cu")
		(net "PHY_SCC_TO_DPB_5_DP")
	)
	(segment
		(start 139.553696 -68.128388)
		(end 139.290298 -68.072254)
		(width 0.1016)
		(layer "In5.Cu")
		(net "PHY_SCC_TO_DPB_5_DP")
	)
	(segment
		(start 144.079468 -43.557952)
		(end 142.553944 -50.734468)
		(width 0.1016)
		(layer "In5.Cu")
		(net "PHY_SCC_TO_DPB_5_DP")
	)
	(segment
		(start 139.290298 -68.072254)
		(end 139.034774 -68.238116)
		(width 0.1016)
		(layer "In5.Cu")
		(net "PHY_SCC_TO_DPB_5_DP")
	)
	(segment
		(start 139.865354 -67.698874)
		(end 139.80922 -67.962526)
		(width 0.1016)
		(layer "In5.Cu")
		(net "PHY_SCC_TO_DPB_5_DP")
	)
	(segment
		(start 132.008118 -71.349362)
		(end 131.459986 -71.349362)
		(width 0.1016)
		(layer "In5.Cu")
		(net "PHY_SCC_TO_DPB_5_DP")
	)
	(segment
		(start 138.97864 -68.501768)
		(end 138.701526 -68.6816)
		(width 0.1016)
		(layer "In5.Cu")
		(net "PHY_SCC_TO_DPB_5_DP")
	)
	(segment
		(start 138.701526 -68.6816)
		(end 134.67588 -68.6816)
		(width 0.1016)
		(layer "In5.Cu")
		(net "PHY_SCC_TO_DPB_5_DP")
	)
	(segment
		(start 145.400014 -9.800082)
		(end 145.400014 -10.168382)
		(width 0.1016)
		(layer "In5.Cu")
		(net "PHY_SCC_TO_DPB_5_DP")
	)
	(segment
		(start 130.595116 -71.270876)
		(end 130.595116 -71.089012)
		(width 0.0889)
		(layer "In5.Cu")
		(net "PHY_SCC_TO_DPB_5_DP")
	)
	(segment
		(start 144.640808 -60.553092)
		(end 143.772382 -64.640968)
		(width 0.1016)
		(layer "In5.Cu")
		(net "PHY_SCC_TO_DPB_5_DP")
	)
	(arc
		(start 130.730498 -71.406512)
		(mid 130.678841 -71.39629)
		(end 130.634994 -71.367142)
		(width 0.0889)
		(layer "In5.Cu")
		(net "PHY_SCC_TO_DPB_5_DP")
	)
	(arc
		(start 144.871186 -10.347706)
		(mid 144.50102 -10.501034)
		(end 144.347692 -10.8712)
		(width 0.1016)
		(layer "In5.Cu")
		(net "PHY_SCC_TO_DPB_5_DP")
	)
	(arc
		(start 130.63474 -71.366888)
		(mid 130.60536 -71.322823)
		(end 130.595116 -71.270876)
		(width 0.0889)
		(layer "In5.Cu")
		(net "PHY_SCC_TO_DPB_5_DP")
	)
	(arc
		(start 130.595116 -71.089012)
		(mid 130.621154 -71.02615)
		(end 130.684016 -71.000112)
		(width 0.0889)
		(layer "In5.Cu")
		(net "PHY_SCC_TO_DPB_5_DP")
	)
	(arc
		(start 145.400014 -10.168382)
		(mid 145.347491 -10.295183)
		(end 145.22069 -10.347706)
		(width 0.1016)
		(layer "In5.Cu")
		(net "PHY_SCC_TO_DPB_5_DP")
	)
	(segment
		(start 129.500122 -70.50024)
		(end 129.999994 -71.000112)
		(width 0.104902)
		(layer "F.Cu")
		(net "PHY_SCC_TO_DPB_5_DN")
	)
	(via
		(at 129.999994 -71.000112)
		(size 0.4572)
		(drill 0.2032)
		(layers "F.Cu" "B.Cu")
		(net "PHY_SCC_TO_DPB_5_DN")
	)
	(segment
		(start 142.865602 -50.734468)
		(end 144.952466 -60.553092)
		(width 0.1016)
		(layer "In5.Cu")
		(net "PHY_SCC_TO_DPB_5_DN")
	)
	(segment
		(start 134.802372 -68.9864)
		(end 132.13461 -71.654162)
		(width 0.1016)
		(layer "In5.Cu")
		(net "PHY_SCC_TO_DPB_5_DN")
	)
	(segment
		(start 144.391126 -43.557952)
		(end 142.865602 -50.734468)
		(width 0.1016)
		(layer "In5.Cu")
		(net "PHY_SCC_TO_DPB_5_DN")
	)
	(segment
		(start 144.058894 -64.759586)
		(end 143.152622 -66.15557)
		(width 0.1016)
		(layer "In5.Cu")
		(net "PHY_SCC_TO_DPB_5_DN")
	)
	(segment
		(start 141.859 -31.645098)
		(end 144.391126 -43.557952)
		(width 0.1016)
		(layer "In5.Cu")
		(net "PHY_SCC_TO_DPB_5_DN")
	)
	(segment
		(start 130.500374 -71.502016)
		(end 130.499866 -71.501508)
		(width 0.0889)
		(layer "In5.Cu")
		(net "PHY_SCC_TO_DPB_5_DN")
	)
	(segment
		(start 144.652492 -10.8712)
		(end 144.652492 -18.501614)
		(width 0.1016)
		(layer "In5.Cu")
		(net "PHY_SCC_TO_DPB_5_DN")
	)
	(segment
		(start 131.368292 -71.654162)
		(end 131.346194 -71.654162)
		(width 0.0889)
		(layer "In5.Cu")
		(net "PHY_SCC_TO_DPB_5_DN")
	)
	(segment
		(start 130.315716 -71.000112)
		(end 129.999994 -71.000112)
		(width 0.0889)
		(layer "In5.Cu")
		(net "PHY_SCC_TO_DPB_5_DN")
	)
	(segment
		(start 144.952466 -60.553092)
		(end 144.058894 -64.759586)
		(width 0.1016)
		(layer "In5.Cu")
		(net "PHY_SCC_TO_DPB_5_DN")
	)
	(segment
		(start 131.289044 -71.597012)
		(end 130.730498 -71.597012)
		(width 0.0889)
		(layer "In5.Cu")
		(net "PHY_SCC_TO_DPB_5_DN")
	)
	(segment
		(start 144.652492 -18.501614)
		(end 141.859 -31.645098)
		(width 0.1016)
		(layer "In5.Cu")
		(net "PHY_SCC_TO_DPB_5_DN")
	)
	(segment
		(start 145.400014 -11.20013)
		(end 145.400014 -10.83183)
		(width 0.1016)
		(layer "In5.Cu")
		(net "PHY_SCC_TO_DPB_5_DN")
	)
	(segment
		(start 145.22069 -10.652506)
		(end 144.871186 -10.652506)
		(width 0.1016)
		(layer "In5.Cu")
		(net "PHY_SCC_TO_DPB_5_DN")
	)
	(segment
		(start 130.404616 -71.270622)
		(end 130.404616 -71.089012)
		(width 0.0889)
		(layer "In5.Cu")
		(net "PHY_SCC_TO_DPB_5_DN")
	)
	(segment
		(start 143.152622 -66.15557)
		(end 140.444728 -67.91325)
		(width 0.1016)
		(layer "In5.Cu")
		(net "PHY_SCC_TO_DPB_5_DN")
	)
	(segment
		(start 132.13461 -71.654162)
		(end 131.368292 -71.654162)
		(width 0.1016)
		(layer "In5.Cu")
		(net "PHY_SCC_TO_DPB_5_DN")
	)
	(segment
		(start 140.444728 -67.913504)
		(end 138.79195 -68.9864)
		(width 0.1016)
		(layer "In5.Cu")
		(net "PHY_SCC_TO_DPB_5_DN")
	)
	(segment
		(start 138.79195 -68.9864)
		(end 134.802372 -68.9864)
		(width 0.1016)
		(layer "In5.Cu")
		(net "PHY_SCC_TO_DPB_5_DN")
	)
	(segment
		(start 131.346194 -71.654162)
		(end 131.289044 -71.597012)
		(width 0.0889)
		(layer "In5.Cu")
		(net "PHY_SCC_TO_DPB_5_DN")
	)
	(segment
		(start 140.444728 -67.91325)
		(end 140.444728 -67.913504)
		(width 0.1016)
		(layer "In5.Cu")
		(net "PHY_SCC_TO_DPB_5_DN")
	)
	(arc
		(start 130.730498 -71.597012)
		(mid 130.606023 -71.572324)
		(end 130.500374 -71.502016)
		(width 0.0889)
		(layer "In5.Cu")
		(net "PHY_SCC_TO_DPB_5_DN")
	)
	(arc
		(start 130.404616 -71.089012)
		(mid 130.378578 -71.02615)
		(end 130.315716 -71.000112)
		(width 0.0889)
		(layer "In5.Cu")
		(net "PHY_SCC_TO_DPB_5_DN")
	)
	(arc
		(start 145.400014 -10.83183)
		(mid 145.347491 -10.705029)
		(end 145.22069 -10.652506)
		(width 0.1016)
		(layer "In5.Cu")
		(net "PHY_SCC_TO_DPB_5_DN")
	)
	(arc
		(start 144.871186 -10.652506)
		(mid 144.716546 -10.71656)
		(end 144.652492 -10.8712)
		(width 0.1016)
		(layer "In5.Cu")
		(net "PHY_SCC_TO_DPB_5_DN")
	)
	(arc
		(start 130.499866 -71.501508)
		(mid 130.429305 -71.395532)
		(end 130.404616 -71.270622)
		(width 0.0889)
		(layer "In5.Cu")
		(net "PHY_SCC_TO_DPB_5_DN")
	)
	(segment
		(start 129.500122 -69.500242)
		(end 129.999994 -70.000114)
		(width 0.104902)
		(layer "F.Cu")
		(net "PHY_SCC_TO_DPB_4_DP")
	)
	(via
		(at 129.999994 -70.000114)
		(size 0.4572)
		(drill 0.2032)
		(layers "F.Cu" "B.Cu")
		(net "PHY_SCC_TO_DPB_4_DP")
	)
	(segment
		(start 129.684018 -70.000114)
		(end 129.999994 -70.000114)
		(width 0.0889)
		(layer "In5.Cu")
		(net "PHY_SCC_TO_DPB_4_DP")
	)
	(segment
		(start 140.96365 -65.46088)
		(end 140.708126 -65.626742)
		(width 0.1016)
		(layer "In5.Cu")
		(net "PHY_SCC_TO_DPB_4_DP")
	)
	(segment
		(start 142.978886 -63.69939)
		(end 142.215362 -64.875664)
		(width 0.1016)
		(layer "In5.Cu")
		(net "PHY_SCC_TO_DPB_4_DP")
	)
	(segment
		(start 143.509238 -61.203332)
		(end 142.978886 -63.69939)
		(width 0.1016)
		(layer "In5.Cu")
		(net "PHY_SCC_TO_DPB_4_DP")
	)
	(segment
		(start 140.396214 -66.056256)
		(end 140.132816 -66.000376)
		(width 0.1016)
		(layer "In5.Cu")
		(net "PHY_SCC_TO_DPB_4_DP")
	)
	(segment
		(start 142.547848 -12.071096)
		(end 142.547848 -17.01292)
		(width 0.1016)
		(layer "In5.Cu")
		(net "PHY_SCC_TO_DPB_4_DP")
	)
	(segment
		(start 138.660632 -67.183)
		(end 135.142224 -67.183)
		(width 0.1016)
		(layer "In5.Cu")
		(net "PHY_SCC_TO_DPB_4_DP")
	)
	(segment
		(start 131.367022 -70.347078)
		(end 131.344924 -70.347078)
		(width 0.0889)
		(layer "In5.Cu")
		(net "PHY_SCC_TO_DPB_4_DP")
	)
	(segment
		(start 140.184124 -31.661354)
		(end 142.922498 -44.544488)
		(width 0.1016)
		(layer "In5.Cu")
		(net "PHY_SCC_TO_DPB_4_DP")
	)
	(segment
		(start 142.922498 -44.544488)
		(end 141.477238 -51.343306)
		(width 0.1016)
		(layer "In5.Cu")
		(net "PHY_SCC_TO_DPB_4_DP")
	)
	(segment
		(start 140.708126 -65.626742)
		(end 140.651992 -65.890394)
		(width 0.1016)
		(layer "In5.Cu")
		(net "PHY_SCC_TO_DPB_4_DP")
	)
	(segment
		(start 143.60017 -10.999978)
		(end 143.60017 -11.368278)
		(width 0.1016)
		(layer "In5.Cu")
		(net "PHY_SCC_TO_DPB_4_DP")
	)
	(segment
		(start 131.287774 -70.404228)
		(end 129.73939 -70.404228)
		(width 0.0889)
		(layer "In5.Cu")
		(net "PHY_SCC_TO_DPB_4_DP")
	)
	(segment
		(start 139.821158 -66.429636)
		(end 138.660632 -67.183)
		(width 0.1016)
		(layer "In5.Cu")
		(net "PHY_SCC_TO_DPB_4_DP")
	)
	(segment
		(start 141.477238 -51.343306)
		(end 143.509238 -61.203332)
		(width 0.1016)
		(layer "In5.Cu")
		(net "PHY_SCC_TO_DPB_4_DP")
	)
	(segment
		(start 131.344924 -70.347078)
		(end 131.287774 -70.404228)
		(width 0.0889)
		(layer "In5.Cu")
		(net "PHY_SCC_TO_DPB_4_DP")
	)
	(segment
		(start 139.877038 -66.166238)
		(end 139.821158 -66.429636)
		(width 0.1016)
		(layer "In5.Cu")
		(net "PHY_SCC_TO_DPB_4_DP")
	)
	(segment
		(start 142.922498 -18.775426)
		(end 140.184124 -31.661354)
		(width 0.1016)
		(layer "In5.Cu")
		(net "PHY_SCC_TO_DPB_4_DP")
	)
	(segment
		(start 140.132816 -66.000376)
		(end 139.877038 -66.166238)
		(width 0.1016)
		(layer "In5.Cu")
		(net "PHY_SCC_TO_DPB_4_DP")
	)
	(segment
		(start 140.651992 -65.890394)
		(end 140.396214 -66.056256)
		(width 0.1016)
		(layer "In5.Cu")
		(net "PHY_SCC_TO_DPB_4_DP")
	)
	(segment
		(start 141.227302 -65.517014)
		(end 140.96365 -65.46088)
		(width 0.1016)
		(layer "In5.Cu")
		(net "PHY_SCC_TO_DPB_4_DP")
	)
	(segment
		(start 143.420846 -11.547602)
		(end 143.071342 -11.547602)
		(width 0.1016)
		(layer "In5.Cu")
		(net "PHY_SCC_TO_DPB_4_DP")
	)
	(segment
		(start 129.595118 -70.259702)
		(end 129.595118 -70.089014)
		(width 0.0889)
		(layer "In5.Cu")
		(net "PHY_SCC_TO_DPB_4_DP")
	)
	(segment
		(start 142.215362 -64.875664)
		(end 141.227302 -65.517014)
		(width 0.1016)
		(layer "In5.Cu")
		(net "PHY_SCC_TO_DPB_4_DP")
	)
	(segment
		(start 131.978146 -70.347078)
		(end 131.367022 -70.347078)
		(width 0.1016)
		(layer "In5.Cu")
		(net "PHY_SCC_TO_DPB_4_DP")
	)
	(segment
		(start 135.142224 -67.183)
		(end 131.978146 -70.347078)
		(width 0.1016)
		(layer "In5.Cu")
		(net "PHY_SCC_TO_DPB_4_DP")
	)
	(segment
		(start 142.547848 -17.01292)
		(end 142.922498 -18.775426)
		(width 0.1016)
		(layer "In5.Cu")
		(net "PHY_SCC_TO_DPB_4_DP")
	)
	(arc
		(start 143.071342 -11.547602)
		(mid 142.701176 -11.70093)
		(end 142.547848 -12.071096)
		(width 0.1016)
		(layer "In5.Cu")
		(net "PHY_SCC_TO_DPB_4_DP")
	)
	(arc
		(start 129.73939 -70.404228)
		(mid 129.684277 -70.393265)
		(end 129.637536 -70.362064)
		(width 0.0889)
		(layer "In5.Cu")
		(net "PHY_SCC_TO_DPB_4_DP")
	)
	(arc
		(start 129.637536 -70.362064)
		(mid 129.606156 -70.3151)
		(end 129.595118 -70.259702)
		(width 0.0889)
		(layer "In5.Cu")
		(net "PHY_SCC_TO_DPB_4_DP")
	)
	(arc
		(start 129.595118 -70.089014)
		(mid 129.621156 -70.026152)
		(end 129.684018 -70.000114)
		(width 0.0889)
		(layer "In5.Cu")
		(net "PHY_SCC_TO_DPB_4_DP")
	)
	(arc
		(start 143.60017 -11.368278)
		(mid 143.547647 -11.495079)
		(end 143.420846 -11.547602)
		(width 0.1016)
		(layer "In5.Cu")
		(net "PHY_SCC_TO_DPB_4_DP")
	)
	(segment
		(start 128.500124 -69.500242)
		(end 128.999996 -70.000114)
		(width 0.104902)
		(layer "F.Cu")
		(net "PHY_SCC_TO_DPB_4_DN")
	)
	(via
		(at 128.999996 -70.000114)
		(size 0.4572)
		(drill 0.2032)
		(layers "F.Cu" "B.Cu")
		(net "PHY_SCC_TO_DPB_4_DN")
	)
	(segment
		(start 132.104638 -70.651878)
		(end 135.268716 -67.4878)
		(width 0.1016)
		(layer "In5.Cu")
		(net "PHY_SCC_TO_DPB_4_DN")
	)
	(segment
		(start 142.852648 -16.980662)
		(end 142.852648 -12.071096)
		(width 0.1016)
		(layer "In5.Cu")
		(net "PHY_SCC_TO_DPB_4_DN")
	)
	(segment
		(start 140.495782 -31.661354)
		(end 143.234156 -18.775426)
		(width 0.1016)
		(layer "In5.Cu")
		(net "PHY_SCC_TO_DPB_4_DN")
	)
	(segment
		(start 138.751056 -67.4878)
		(end 142.435834 -65.096136)
		(width 0.1016)
		(layer "In5.Cu")
		(net "PHY_SCC_TO_DPB_4_DN")
	)
	(segment
		(start 143.234156 -18.775426)
		(end 142.852648 -16.980662)
		(width 0.1016)
		(layer "In5.Cu")
		(net "PHY_SCC_TO_DPB_4_DN")
	)
	(segment
		(start 135.268716 -67.4878)
		(end 138.751056 -67.4878)
		(width 0.1016)
		(layer "In5.Cu")
		(net "PHY_SCC_TO_DPB_4_DN")
	)
	(segment
		(start 131.458716 -70.651878)
		(end 132.104638 -70.651878)
		(width 0.1016)
		(layer "In5.Cu")
		(net "PHY_SCC_TO_DPB_4_DN")
	)
	(segment
		(start 131.287774 -70.594728)
		(end 131.344924 -70.651878)
		(width 0.0889)
		(layer "In5.Cu")
		(net "PHY_SCC_TO_DPB_4_DN")
	)
	(segment
		(start 143.234156 -44.544488)
		(end 140.495782 -31.661354)
		(width 0.1016)
		(layer "In5.Cu")
		(net "PHY_SCC_TO_DPB_4_DN")
	)
	(segment
		(start 141.788896 -51.344322)
		(end 143.234156 -44.544488)
		(width 0.1016)
		(layer "In5.Cu")
		(net "PHY_SCC_TO_DPB_4_DN")
	)
	(segment
		(start 143.071342 -11.852402)
		(end 143.420846 -11.852402)
		(width 0.1016)
		(layer "In5.Cu")
		(net "PHY_SCC_TO_DPB_4_DN")
	)
	(segment
		(start 142.435834 -65.096136)
		(end 143.265398 -63.818008)
		(width 0.1016)
		(layer "In5.Cu")
		(net "PHY_SCC_TO_DPB_4_DN")
	)
	(segment
		(start 128.999996 -70.000114)
		(end 129.315718 -70.000114)
		(width 0.0889)
		(layer "In5.Cu")
		(net "PHY_SCC_TO_DPB_4_DN")
	)
	(segment
		(start 143.265398 -63.818008)
		(end 143.820896 -61.204348)
		(width 0.1016)
		(layer "In5.Cu")
		(net "PHY_SCC_TO_DPB_4_DN")
	)
	(segment
		(start 129.73939 -70.594728)
		(end 131.287774 -70.594728)
		(width 0.0889)
		(layer "In5.Cu")
		(net "PHY_SCC_TO_DPB_4_DN")
	)
	(segment
		(start 129.404618 -70.089014)
		(end 129.404618 -70.259702)
		(width 0.0889)
		(layer "In5.Cu")
		(net "PHY_SCC_TO_DPB_4_DN")
	)
	(segment
		(start 143.820896 -61.204348)
		(end 141.788896 -51.344322)
		(width 0.1016)
		(layer "In5.Cu")
		(net "PHY_SCC_TO_DPB_4_DN")
	)
	(segment
		(start 143.60017 -12.031726)
		(end 143.60017 -12.400026)
		(width 0.1016)
		(layer "In5.Cu")
		(net "PHY_SCC_TO_DPB_4_DN")
	)
	(segment
		(start 131.344924 -70.651878)
		(end 131.458716 -70.651878)
		(width 0.0889)
		(layer "In5.Cu")
		(net "PHY_SCC_TO_DPB_4_DN")
	)
	(arc
		(start 129.315718 -70.000114)
		(mid 129.37858 -70.026152)
		(end 129.404618 -70.089014)
		(width 0.0889)
		(layer "In5.Cu")
		(net "PHY_SCC_TO_DPB_4_DN")
	)
	(arc
		(start 129.502916 -70.496938)
		(mid 129.61144 -70.569325)
		(end 129.73939 -70.594728)
		(width 0.0889)
		(layer "In5.Cu")
		(net "PHY_SCC_TO_DPB_4_DN")
	)
	(arc
		(start 142.852648 -12.071096)
		(mid 142.916702 -11.916456)
		(end 143.071342 -11.852402)
		(width 0.1016)
		(layer "In5.Cu")
		(net "PHY_SCC_TO_DPB_4_DN")
	)
	(arc
		(start 143.420846 -11.852402)
		(mid 143.547647 -11.904925)
		(end 143.60017 -12.031726)
		(width 0.1016)
		(layer "In5.Cu")
		(net "PHY_SCC_TO_DPB_4_DN")
	)
	(arc
		(start 129.404618 -70.259702)
		(mid 129.430159 -70.388105)
		(end 129.502916 -70.496938)
		(width 0.0889)
		(layer "In5.Cu")
		(net "PHY_SCC_TO_DPB_4_DN")
	)
	(segment
		(start 123.500134 -52.500022)
		(end 124.000006 -52.00015)
		(width 0.104902)
		(layer "F.Cu")
		(net "PHY_SCC_TO_DPB_39_DP")
	)
	(via
		(at 124.000006 -52.00015)
		(size 0.4572)
		(drill 0.2032)
		(layers "F.Cu" "B.Cu")
		(net "PHY_SCC_TO_DPB_39_DP")
	)
	(segment
		(start 129.533904 -50.34915)
		(end 130.398012 -49.485042)
		(width 0.1016)
		(layer "In5.Cu")
		(net "PHY_SCC_TO_DPB_39_DP")
	)
	(segment
		(start 133.05028 -46.623224)
		(end 126.347728 -15.089124)
		(width 0.1016)
		(layer "In5.Cu")
		(net "PHY_SCC_TO_DPB_39_DP")
	)
	(segment
		(start 128.718818 -50.4063)
		(end 129.25425 -50.4063)
		(width 0.0889)
		(layer "In5.Cu")
		(net "PHY_SCC_TO_DPB_39_DP")
	)
	(segment
		(start 127.40005 -10.168382)
		(end 127.40005 -9.800082)
		(width 0.1016)
		(layer "In5.Cu")
		(net "PHY_SCC_TO_DPB_39_DP")
	)
	(segment
		(start 132.722112 -48.167798)
		(end 133.05028 -46.623224)
		(width 0.1016)
		(layer "In5.Cu")
		(net "PHY_SCC_TO_DPB_39_DP")
	)
	(segment
		(start 131.265676 -49.300892)
		(end 132.5118 -48.491394)
		(width 0.1016)
		(layer "In5.Cu")
		(net "PHY_SCC_TO_DPB_39_DP")
	)
	(segment
		(start 128.408684 -52.255928)
		(end 128.408684 -50.716434)
		(width 0.0889)
		(layer "In5.Cu")
		(net "PHY_SCC_TO_DPB_39_DP")
	)
	(segment
		(start 124.088906 -52.404772)
		(end 128.25984 -52.404772)
		(width 0.0889)
		(layer "In5.Cu")
		(net "PHY_SCC_TO_DPB_39_DP")
	)
	(segment
		(start 130.398012 -49.485042)
		(end 131.265676 -49.300892)
		(width 0.1016)
		(layer "In5.Cu")
		(net "PHY_SCC_TO_DPB_39_DP")
	)
	(segment
		(start 129.25425 -50.4063)
		(end 129.3114 -50.34915)
		(width 0.0889)
		(layer "In5.Cu")
		(net "PHY_SCC_TO_DPB_39_DP")
	)
	(segment
		(start 132.5118 -48.491394)
		(end 132.722112 -48.167798)
		(width 0.1016)
		(layer "In5.Cu")
		(net "PHY_SCC_TO_DPB_39_DP")
	)
	(segment
		(start 128.25984 -52.404772)
		(end 128.408684 -52.255928)
		(width 0.0889)
		(layer "In5.Cu")
		(net "PHY_SCC_TO_DPB_39_DP")
	)
	(segment
		(start 124.000006 -52.00015)
		(end 124.000006 -52.315872)
		(width 0.0889)
		(layer "In5.Cu")
		(net "PHY_SCC_TO_DPB_39_DP")
	)
	(segment
		(start 128.408684 -50.716434)
		(end 128.718818 -50.4063)
		(width 0.0889)
		(layer "In5.Cu")
		(net "PHY_SCC_TO_DPB_39_DP")
	)
	(segment
		(start 129.3114 -50.34915)
		(end 129.333498 -50.34915)
		(width 0.0889)
		(layer "In5.Cu")
		(net "PHY_SCC_TO_DPB_39_DP")
	)
	(segment
		(start 126.871222 -10.347706)
		(end 127.220726 -10.347706)
		(width 0.1016)
		(layer "In5.Cu")
		(net "PHY_SCC_TO_DPB_39_DP")
	)
	(segment
		(start 129.333498 -50.34915)
		(end 129.533904 -50.34915)
		(width 0.1016)
		(layer "In5.Cu")
		(net "PHY_SCC_TO_DPB_39_DP")
	)
	(segment
		(start 126.347728 -15.089124)
		(end 126.347728 -10.8712)
		(width 0.1016)
		(layer "In5.Cu")
		(net "PHY_SCC_TO_DPB_39_DP")
	)
	(arc
		(start 124.000006 -52.315872)
		(mid 124.026044 -52.378734)
		(end 124.088906 -52.404772)
		(width 0.0889)
		(layer "In5.Cu")
		(net "PHY_SCC_TO_DPB_39_DP")
	)
	(arc
		(start 126.347728 -10.8712)
		(mid 126.501056 -10.501034)
		(end 126.871222 -10.347706)
		(width 0.1016)
		(layer "In5.Cu")
		(net "PHY_SCC_TO_DPB_39_DP")
	)
	(arc
		(start 127.220726 -10.347706)
		(mid 127.347527 -10.295183)
		(end 127.40005 -10.168382)
		(width 0.1016)
		(layer "In5.Cu")
		(net "PHY_SCC_TO_DPB_39_DP")
	)
	(segment
		(start 123.500134 -53.50002)
		(end 124.000006 -53.000148)
		(width 0.104902)
		(layer "F.Cu")
		(net "PHY_SCC_TO_DPB_39_DN")
	)
	(via
		(at 124.000006 -53.000148)
		(size 0.4572)
		(drill 0.2032)
		(layers "F.Cu" "B.Cu")
		(net "PHY_SCC_TO_DPB_39_DN")
	)
	(segment
		(start 129.25425 -50.5968)
		(end 129.3114 -50.65395)
		(width 0.0889)
		(layer "In5.Cu")
		(net "PHY_SCC_TO_DPB_39_DN")
	)
	(segment
		(start 128.599184 -52.334922)
		(end 128.599184 -50.795428)
		(width 0.0889)
		(layer "In5.Cu")
		(net "PHY_SCC_TO_DPB_39_DN")
	)
	(segment
		(start 128.338834 -52.595272)
		(end 128.599184 -52.334922)
		(width 0.0889)
		(layer "In5.Cu")
		(net "PHY_SCC_TO_DPB_39_DN")
	)
	(segment
		(start 126.652528 -15.056866)
		(end 126.652528 -10.8712)
		(width 0.1016)
		(layer "In5.Cu")
		(net "PHY_SCC_TO_DPB_39_DN")
	)
	(segment
		(start 126.871222 -10.652506)
		(end 127.220726 -10.652506)
		(width 0.1016)
		(layer "In5.Cu")
		(net "PHY_SCC_TO_DPB_39_DN")
	)
	(segment
		(start 129.333498 -50.65395)
		(end 129.660396 -50.65395)
		(width 0.1016)
		(layer "In5.Cu")
		(net "PHY_SCC_TO_DPB_39_DN")
	)
	(segment
		(start 127.40005 -10.83183)
		(end 127.40005 -11.20013)
		(width 0.1016)
		(layer "In5.Cu")
		(net "PHY_SCC_TO_DPB_39_DN")
	)
	(segment
		(start 132.732272 -48.711866)
		(end 133.008624 -48.286416)
		(width 0.1016)
		(layer "In5.Cu")
		(net "PHY_SCC_TO_DPB_39_DN")
	)
	(segment
		(start 133.361938 -46.623224)
		(end 126.652528 -15.056866)
		(width 0.1016)
		(layer "In5.Cu")
		(net "PHY_SCC_TO_DPB_39_DN")
	)
	(segment
		(start 130.549904 -49.764696)
		(end 131.384294 -49.587404)
		(width 0.1016)
		(layer "In5.Cu")
		(net "PHY_SCC_TO_DPB_39_DN")
	)
	(segment
		(start 129.3114 -50.65395)
		(end 129.333498 -50.65395)
		(width 0.0889)
		(layer "In5.Cu")
		(net "PHY_SCC_TO_DPB_39_DN")
	)
	(segment
		(start 133.008624 -48.286416)
		(end 133.361938 -46.623224)
		(width 0.1016)
		(layer "In5.Cu")
		(net "PHY_SCC_TO_DPB_39_DN")
	)
	(segment
		(start 131.384294 -49.587404)
		(end 132.732272 -48.711866)
		(width 0.1016)
		(layer "In5.Cu")
		(net "PHY_SCC_TO_DPB_39_DN")
	)
	(segment
		(start 124.088906 -52.595272)
		(end 128.338834 -52.595272)
		(width 0.0889)
		(layer "In5.Cu")
		(net "PHY_SCC_TO_DPB_39_DN")
	)
	(segment
		(start 128.599184 -50.795428)
		(end 128.797812 -50.5968)
		(width 0.0889)
		(layer "In5.Cu")
		(net "PHY_SCC_TO_DPB_39_DN")
	)
	(segment
		(start 124.000006 -53.000148)
		(end 124.000006 -52.684172)
		(width 0.0889)
		(layer "In5.Cu")
		(net "PHY_SCC_TO_DPB_39_DN")
	)
	(segment
		(start 128.797812 -50.5968)
		(end 129.25425 -50.5968)
		(width 0.0889)
		(layer "In5.Cu")
		(net "PHY_SCC_TO_DPB_39_DN")
	)
	(segment
		(start 129.660396 -50.65395)
		(end 130.549904 -49.764696)
		(width 0.1016)
		(layer "In5.Cu")
		(net "PHY_SCC_TO_DPB_39_DN")
	)
	(arc
		(start 124.000006 -52.684172)
		(mid 124.026044 -52.62131)
		(end 124.088906 -52.595272)
		(width 0.0889)
		(layer "In5.Cu")
		(net "PHY_SCC_TO_DPB_39_DN")
	)
	(arc
		(start 126.652528 -10.8712)
		(mid 126.716582 -10.71656)
		(end 126.871222 -10.652506)
		(width 0.1016)
		(layer "In5.Cu")
		(net "PHY_SCC_TO_DPB_39_DN")
	)
	(arc
		(start 127.220726 -10.652506)
		(mid 127.347527 -10.705029)
		(end 127.40005 -10.83183)
		(width 0.1016)
		(layer "In5.Cu")
		(net "PHY_SCC_TO_DPB_39_DN")
	)
	(segment
		(start 122.500136 -51.500024)
		(end 123.000008 -51.000152)
		(width 0.104902)
		(layer "F.Cu")
		(net "PHY_SCC_TO_DPB_38_DP")
	)
	(via
		(at 123.000008 -51.000152)
		(size 0.4572)
		(drill 0.2032)
		(layers "F.Cu" "B.Cu")
		(net "PHY_SCC_TO_DPB_38_DP")
	)
	(segment
		(start 127.259842 -51.404774)
		(end 123.088908 -51.404774)
		(width 0.0889)
		(layer "In5.Cu")
		(net "PHY_SCC_TO_DPB_38_DP")
	)
	(segment
		(start 127.34925 -50.404268)
		(end 127.34925 -50.643028)
		(width 0.1016)
		(layer "In5.Cu")
		(net "PHY_SCC_TO_DPB_38_DP")
	)
	(segment
		(start 127.4064 -50.722276)
		(end 127.4064 -51.258216)
		(width 0.0889)
		(layer "In5.Cu")
		(net "PHY_SCC_TO_DPB_38_DP")
	)
	(segment
		(start 130.360928 -45.839888)
		(end 130.50012 -46.53661)
		(width 0.1016)
		(layer "In5.Cu")
		(net "PHY_SCC_TO_DPB_38_DP")
	)
	(segment
		(start 130.03149 -48.35906)
		(end 129.910078 -48.54575)
		(width 0.1016)
		(layer "In5.Cu")
		(net "PHY_SCC_TO_DPB_38_DP")
	)
	(segment
		(start 127.4064 -51.258216)
		(end 127.259842 -51.404774)
		(width 0.0889)
		(layer "In5.Cu")
		(net "PHY_SCC_TO_DPB_38_DP")
	)
	(segment
		(start 129.910078 -48.54575)
		(end 129.447798 -48.84547)
		(width 0.1016)
		(layer "In5.Cu")
		(net "PHY_SCC_TO_DPB_38_DP")
	)
	(segment
		(start 129.447798 -48.84547)
		(end 128.98501 -49.145698)
		(width 0.1016)
		(layer "In5.Cu")
		(net "PHY_SCC_TO_DPB_38_DP")
	)
	(segment
		(start 124.547884 -14.066266)
		(end 124.88545 -15.65783)
		(width 0.1016)
		(layer "In5.Cu")
		(net "PHY_SCC_TO_DPB_38_DP")
	)
	(segment
		(start 130.50012 -46.53661)
		(end 130.15214 -48.172878)
		(width 0.1016)
		(layer "In5.Cu")
		(net "PHY_SCC_TO_DPB_38_DP")
	)
	(segment
		(start 125.600206 -10.999978)
		(end 125.600206 -11.368278)
		(width 0.1016)
		(layer "In5.Cu")
		(net "PHY_SCC_TO_DPB_38_DP")
	)
	(segment
		(start 127.34925 -50.643028)
		(end 127.34925 -50.665126)
		(width 0.0889)
		(layer "In5.Cu")
		(net "PHY_SCC_TO_DPB_38_DP")
	)
	(segment
		(start 124.88545 -15.65783)
		(end 124.885704 -15.65783)
		(width 0.1016)
		(layer "In5.Cu")
		(net "PHY_SCC_TO_DPB_38_DP")
	)
	(segment
		(start 127.704596 -49.856644)
		(end 127.34925 -50.404268)
		(width 0.1016)
		(layer "In5.Cu")
		(net "PHY_SCC_TO_DPB_38_DP")
	)
	(segment
		(start 124.547884 -12.071096)
		(end 124.547884 -14.066266)
		(width 0.1016)
		(layer "In5.Cu")
		(net "PHY_SCC_TO_DPB_38_DP")
	)
	(segment
		(start 125.420882 -11.547602)
		(end 125.071378 -11.547602)
		(width 0.1016)
		(layer "In5.Cu")
		(net "PHY_SCC_TO_DPB_38_DP")
	)
	(segment
		(start 123.000008 -51.315874)
		(end 123.000008 -51.000152)
		(width 0.0889)
		(layer "In5.Cu")
		(net "PHY_SCC_TO_DPB_38_DP")
	)
	(segment
		(start 128.708912 -49.204372)
		(end 127.704596 -49.856644)
		(width 0.1016)
		(layer "In5.Cu")
		(net "PHY_SCC_TO_DPB_38_DP")
	)
	(segment
		(start 124.885704 -15.65783)
		(end 125.223778 -17.250156)
		(width 0.1016)
		(layer "In5.Cu")
		(net "PHY_SCC_TO_DPB_38_DP")
	)
	(segment
		(start 124.75337 -19.463512)
		(end 130.269488 -45.417994)
		(width 0.1016)
		(layer "In5.Cu")
		(net "PHY_SCC_TO_DPB_38_DP")
	)
	(segment
		(start 130.269488 -45.417994)
		(end 130.360928 -45.839888)
		(width 0.1016)
		(layer "In5.Cu")
		(net "PHY_SCC_TO_DPB_38_DP")
	)
	(segment
		(start 125.223778 -17.250156)
		(end 124.75337 -19.463512)
		(width 0.1016)
		(layer "In5.Cu")
		(net "PHY_SCC_TO_DPB_38_DP")
	)
	(segment
		(start 130.15214 -48.172878)
		(end 130.03149 -48.35906)
		(width 0.1016)
		(layer "In5.Cu")
		(net "PHY_SCC_TO_DPB_38_DP")
	)
	(segment
		(start 127.34925 -50.665126)
		(end 127.4064 -50.722276)
		(width 0.0889)
		(layer "In5.Cu")
		(net "PHY_SCC_TO_DPB_38_DP")
	)
	(segment
		(start 128.98501 -49.145698)
		(end 128.708912 -49.204372)
		(width 0.1016)
		(layer "In5.Cu")
		(net "PHY_SCC_TO_DPB_38_DP")
	)
	(arc
		(start 125.071378 -11.547602)
		(mid 124.701212 -11.70093)
		(end 124.547884 -12.071096)
		(width 0.1016)
		(layer "In5.Cu")
		(net "PHY_SCC_TO_DPB_38_DP")
	)
	(arc
		(start 123.088908 -51.404774)
		(mid 123.026046 -51.378736)
		(end 123.000008 -51.315874)
		(width 0.0889)
		(layer "In5.Cu")
		(net "PHY_SCC_TO_DPB_38_DP")
	)
	(arc
		(start 125.600206 -11.368278)
		(mid 125.547683 -11.495079)
		(end 125.420882 -11.547602)
		(width 0.1016)
		(layer "In5.Cu")
		(net "PHY_SCC_TO_DPB_38_DP")
	)
	(segment
		(start 122.500136 -52.500022)
		(end 123.000008 -52.00015)
		(width 0.104902)
		(layer "F.Cu")
		(net "PHY_SCC_TO_DPB_38_DN")
	)
	(via
		(at 123.000008 -52.00015)
		(size 0.4572)
		(drill 0.2032)
		(layers "F.Cu" "B.Cu")
		(net "PHY_SCC_TO_DPB_38_DN")
	)
	(segment
		(start 125.071378 -11.852402)
		(end 125.420882 -11.852402)
		(width 0.1016)
		(layer "In5.Cu")
		(net "PHY_SCC_TO_DPB_38_DN")
	)
	(segment
		(start 129.103628 -49.43221)
		(end 130.13055 -48.766222)
		(width 0.1016)
		(layer "In5.Cu")
		(net "PHY_SCC_TO_DPB_38_DN")
	)
	(segment
		(start 123.000008 -52.00015)
		(end 123.000008 -51.684174)
		(width 0.0889)
		(layer "In5.Cu")
		(net "PHY_SCC_TO_DPB_38_DN")
	)
	(segment
		(start 130.13055 -48.766222)
		(end 130.438652 -48.291242)
		(width 0.1016)
		(layer "In5.Cu")
		(net "PHY_SCC_TO_DPB_38_DN")
	)
	(segment
		(start 128.82753 -49.490884)
		(end 129.103628 -49.43221)
		(width 0.1016)
		(layer "In5.Cu")
		(net "PHY_SCC_TO_DPB_38_DN")
	)
	(segment
		(start 130.541522 -45.23105)
		(end 125.065028 -19.463512)
		(width 0.1016)
		(layer "In5.Cu")
		(net "PHY_SCC_TO_DPB_38_DN")
	)
	(segment
		(start 125.600206 -12.031726)
		(end 125.600206 -12.400026)
		(width 0.1016)
		(layer "In5.Cu")
		(net "PHY_SCC_TO_DPB_38_DN")
	)
	(segment
		(start 127.65405 -50.665126)
		(end 127.65405 -50.643028)
		(width 0.0889)
		(layer "In5.Cu")
		(net "PHY_SCC_TO_DPB_38_DN")
	)
	(segment
		(start 127.338836 -51.595274)
		(end 127.5969 -51.33721)
		(width 0.0889)
		(layer "In5.Cu")
		(net "PHY_SCC_TO_DPB_38_DN")
	)
	(segment
		(start 123.088908 -51.595274)
		(end 127.338836 -51.595274)
		(width 0.0889)
		(layer "In5.Cu")
		(net "PHY_SCC_TO_DPB_38_DN")
	)
	(segment
		(start 130.811524 -46.538642)
		(end 130.68427 -45.901864)
		(width 0.1016)
		(layer "In5.Cu")
		(net "PHY_SCC_TO_DPB_38_DN")
	)
	(segment
		(start 130.767582 -45.377862)
		(end 130.541522 -45.23105)
		(width 0.1016)
		(layer "In5.Cu")
		(net "PHY_SCC_TO_DPB_38_DN")
	)
	(segment
		(start 125.535436 -17.250156)
		(end 124.852684 -14.034262)
		(width 0.1016)
		(layer "In5.Cu")
		(net "PHY_SCC_TO_DPB_38_DN")
	)
	(segment
		(start 127.65405 -50.643028)
		(end 127.65405 -50.494692)
		(width 0.1016)
		(layer "In5.Cu")
		(net "PHY_SCC_TO_DPB_38_DN")
	)
	(segment
		(start 130.68427 -45.901864)
		(end 130.830828 -45.676058)
		(width 0.1016)
		(layer "In5.Cu")
		(net "PHY_SCC_TO_DPB_38_DN")
	)
	(segment
		(start 127.925068 -50.077116)
		(end 128.82753 -49.490884)
		(width 0.1016)
		(layer "In5.Cu")
		(net "PHY_SCC_TO_DPB_38_DN")
	)
	(segment
		(start 127.65405 -50.494692)
		(end 127.925068 -50.077116)
		(width 0.1016)
		(layer "In5.Cu")
		(net "PHY_SCC_TO_DPB_38_DN")
	)
	(segment
		(start 130.438652 -48.291242)
		(end 130.811524 -46.538642)
		(width 0.1016)
		(layer "In5.Cu")
		(net "PHY_SCC_TO_DPB_38_DN")
	)
	(segment
		(start 124.852684 -14.034262)
		(end 124.852684 -12.071096)
		(width 0.1016)
		(layer "In5.Cu")
		(net "PHY_SCC_TO_DPB_38_DN")
	)
	(segment
		(start 127.5969 -51.33721)
		(end 127.5969 -50.722276)
		(width 0.0889)
		(layer "In5.Cu")
		(net "PHY_SCC_TO_DPB_38_DN")
	)
	(segment
		(start 125.065028 -19.463512)
		(end 125.535436 -17.250156)
		(width 0.1016)
		(layer "In5.Cu")
		(net "PHY_SCC_TO_DPB_38_DN")
	)
	(segment
		(start 130.830828 -45.676058)
		(end 130.767582 -45.377862)
		(width 0.1016)
		(layer "In5.Cu")
		(net "PHY_SCC_TO_DPB_38_DN")
	)
	(segment
		(start 127.5969 -50.722276)
		(end 127.65405 -50.665126)
		(width 0.0889)
		(layer "In5.Cu")
		(net "PHY_SCC_TO_DPB_38_DN")
	)
	(arc
		(start 125.420882 -11.852402)
		(mid 125.547683 -11.904925)
		(end 125.600206 -12.031726)
		(width 0.1016)
		(layer "In5.Cu")
		(net "PHY_SCC_TO_DPB_38_DN")
	)
	(arc
		(start 123.000008 -51.684174)
		(mid 123.026046 -51.621312)
		(end 123.088908 -51.595274)
		(width 0.0889)
		(layer "In5.Cu")
		(net "PHY_SCC_TO_DPB_38_DN")
	)
	(arc
		(start 124.852684 -12.071096)
		(mid 124.916738 -11.916456)
		(end 125.071378 -11.852402)
		(width 0.1016)
		(layer "In5.Cu")
		(net "PHY_SCC_TO_DPB_38_DN")
	)
	(segment
		(start 121.500138 -52.500022)
		(end 122.00001 -52.00015)
		(width 0.104902)
		(layer "F.Cu")
		(net "PHY_SCC_TO_DPB_37_DP")
	)
	(via
		(at 122.00001 -52.00015)
		(size 0.4572)
		(drill 0.2032)
		(layers "F.Cu" "B.Cu")
		(net "PHY_SCC_TO_DPB_37_DP")
	)
	(segment
		(start 122.509026 -50.051208)
		(end 122.76455 -49.885854)
		(width 0.1016)
		(layer "In5.Cu")
		(net "PHY_SCC_TO_DPB_37_DP")
	)
	(segment
		(start 122.08891 -52.404772)
		(end 122.196606 -52.404772)
		(width 0.0889)
		(layer "In5.Cu")
		(net "PHY_SCC_TO_DPB_37_DP")
	)
	(segment
		(start 123.453652 -16.359886)
		(end 122.747532 -13.03782)
		(width 0.1016)
		(layer "In5.Cu")
		(net "PHY_SCC_TO_DPB_37_DP")
	)
	(segment
		(start 128.34747 -46.01464)
		(end 127.70739 -43.0022)
		(width 0.1016)
		(layer "In5.Cu")
		(net "PHY_SCC_TO_DPB_37_DP")
	)
	(segment
		(start 123.156218 -49.802034)
		(end 124.068586 -49.99609)
		(width 0.1016)
		(layer "In5.Cu")
		(net "PHY_SCC_TO_DPB_37_DP")
	)
	(segment
		(start 123.800108 -10.168382)
		(end 123.800108 -9.800082)
		(width 0.1016)
		(layer "In5.Cu")
		(net "PHY_SCC_TO_DPB_37_DP")
	)
	(segment
		(start 122.34926 -50.446686)
		(end 122.395996 -50.225706)
		(width 0.1016)
		(layer "In5.Cu")
		(net "PHY_SCC_TO_DPB_37_DP")
	)
	(segment
		(start 128.023874 -47.534068)
		(end 128.34747 -46.01464)
		(width 0.1016)
		(layer "In5.Cu")
		(net "PHY_SCC_TO_DPB_37_DP")
	)
	(segment
		(start 122.40641 -52.194968)
		(end 122.40641 -50.691288)
		(width 0.0889)
		(layer "In5.Cu")
		(net "PHY_SCC_TO_DPB_37_DP")
	)
	(segment
		(start 126.035816 -49.57826)
		(end 127.12319 -48.921162)
		(width 0.1016)
		(layer "In5.Cu")
		(net "PHY_SCC_TO_DPB_37_DP")
	)
	(segment
		(start 122.747532 -13.03782)
		(end 122.747532 -10.871454)
		(width 0.1016)
		(layer "In5.Cu")
		(net "PHY_SCC_TO_DPB_37_DP")
	)
	(segment
		(start 122.40641 -50.691288)
		(end 122.34926 -50.634138)
		(width 0.0889)
		(layer "In5.Cu")
		(net "PHY_SCC_TO_DPB_37_DP")
	)
	(segment
		(start 124.068586 -49.99609)
		(end 126.035816 -49.57826)
		(width 0.1016)
		(layer "In5.Cu")
		(net "PHY_SCC_TO_DPB_37_DP")
	)
	(segment
		(start 123.27128 -10.347706)
		(end 123.620784 -10.347706)
		(width 0.1016)
		(layer "In5.Cu")
		(net "PHY_SCC_TO_DPB_37_DP")
	)
	(segment
		(start 127.70739 -43.0022)
		(end 126.382018 -40.961564)
		(width 0.1016)
		(layer "In5.Cu")
		(net "PHY_SCC_TO_DPB_37_DP")
	)
	(segment
		(start 122.00001 -52.00015)
		(end 122.00001 -52.315872)
		(width 0.0889)
		(layer "In5.Cu")
		(net "PHY_SCC_TO_DPB_37_DP")
	)
	(segment
		(start 122.34926 -50.61204)
		(end 122.34926 -50.446686)
		(width 0.1016)
		(layer "In5.Cu")
		(net "PHY_SCC_TO_DPB_37_DP")
	)
	(segment
		(start 122.395996 -50.225706)
		(end 122.509026 -50.051208)
		(width 0.1016)
		(layer "In5.Cu")
		(net "PHY_SCC_TO_DPB_37_DP")
	)
	(segment
		(start 122.34926 -50.634138)
		(end 122.34926 -50.61204)
		(width 0.0889)
		(layer "In5.Cu")
		(net "PHY_SCC_TO_DPB_37_DP")
	)
	(segment
		(start 126.382018 -40.961564)
		(end 122.303286 -21.772118)
		(width 0.1016)
		(layer "In5.Cu")
		(net "PHY_SCC_TO_DPB_37_DP")
	)
	(segment
		(start 122.76455 -49.885854)
		(end 123.156218 -49.802034)
		(width 0.1016)
		(layer "In5.Cu")
		(net "PHY_SCC_TO_DPB_37_DP")
	)
	(segment
		(start 127.12319 -48.921162)
		(end 128.023874 -47.534068)
		(width 0.1016)
		(layer "In5.Cu")
		(net "PHY_SCC_TO_DPB_37_DP")
	)
	(segment
		(start 122.303286 -21.772118)
		(end 123.453652 -16.359886)
		(width 0.1016)
		(layer "In5.Cu")
		(net "PHY_SCC_TO_DPB_37_DP")
	)
	(arc
		(start 123.620784 -10.347706)
		(mid 123.747585 -10.295183)
		(end 123.800108 -10.168382)
		(width 0.1016)
		(layer "In5.Cu")
		(net "PHY_SCC_TO_DPB_37_DP")
	)
	(arc
		(start 122.747532 -10.871454)
		(mid 122.900934 -10.501108)
		(end 123.27128 -10.347706)
		(width 0.1016)
		(layer "In5.Cu")
		(net "PHY_SCC_TO_DPB_37_DP")
	)
	(arc
		(start 122.196606 -52.404772)
		(mid 122.276895 -52.388802)
		(end 122.344942 -52.343304)
		(width 0.0889)
		(layer "In5.Cu")
		(net "PHY_SCC_TO_DPB_37_DP")
	)
	(arc
		(start 122.344942 -52.343304)
		(mid 122.390416 -52.275247)
		(end 122.40641 -52.194968)
		(width 0.0889)
		(layer "In5.Cu")
		(net "PHY_SCC_TO_DPB_37_DP")
	)
	(arc
		(start 122.00001 -52.315872)
		(mid 122.026048 -52.378734)
		(end 122.08891 -52.404772)
		(width 0.0889)
		(layer "In5.Cu")
		(net "PHY_SCC_TO_DPB_37_DP")
	)
	(segment
		(start 121.500138 -53.50002)
		(end 122.00001 -53.000148)
		(width 0.104902)
		(layer "F.Cu")
		(net "PHY_SCC_TO_DPB_37_DN")
	)
	(via
		(at 122.00001 -53.000148)
		(size 0.4572)
		(drill 0.2032)
		(layers "F.Cu" "B.Cu")
		(net "PHY_SCC_TO_DPB_37_DN")
	)
	(segment
		(start 126.15037 -49.86528)
		(end 127.340868 -49.145952)
		(width 0.1016)
		(layer "In5.Cu")
		(net "PHY_SCC_TO_DPB_37_DN")
	)
	(segment
		(start 122.59691 -50.691288)
		(end 122.65406 -50.634138)
		(width 0.0889)
		(layer "In5.Cu")
		(net "PHY_SCC_TO_DPB_37_DN")
	)
	(segment
		(start 122.65406 -50.47869)
		(end 122.682508 -50.344324)
		(width 0.1016)
		(layer "In5.Cu")
		(net "PHY_SCC_TO_DPB_37_DN")
	)
	(segment
		(start 123.156472 -50.113946)
		(end 124.068586 -50.307748)
		(width 0.1016)
		(layer "In5.Cu")
		(net "PHY_SCC_TO_DPB_37_DN")
	)
	(segment
		(start 122.00001 -53.000148)
		(end 122.00001 -52.684172)
		(width 0.0889)
		(layer "In5.Cu")
		(net "PHY_SCC_TO_DPB_37_DN")
	)
	(segment
		(start 123.052332 -13.005562)
		(end 123.052332 -10.871454)
		(width 0.1016)
		(layer "In5.Cu")
		(net "PHY_SCC_TO_DPB_37_DN")
	)
	(segment
		(start 127.506984 -48.890428)
		(end 127.770382 -48.834294)
		(width 0.1016)
		(layer "In5.Cu")
		(net "PHY_SCC_TO_DPB_37_DN")
	)
	(segment
		(start 122.883168 -50.172366)
		(end 123.156472 -50.113946)
		(width 0.1016)
		(layer "In5.Cu")
		(net "PHY_SCC_TO_DPB_37_DN")
	)
	(segment
		(start 123.76531 -16.359886)
		(end 123.052332 -13.005562)
		(width 0.1016)
		(layer "In5.Cu")
		(net "PHY_SCC_TO_DPB_37_DN")
	)
	(segment
		(start 122.65406 -50.61204)
		(end 122.65406 -50.47869)
		(width 0.1016)
		(layer "In5.Cu")
		(net "PHY_SCC_TO_DPB_37_DN")
	)
	(segment
		(start 126.150624 -49.865534)
		(end 126.15037 -49.86528)
		(width 0.1016)
		(layer "In5.Cu")
		(net "PHY_SCC_TO_DPB_37_DN")
	)
	(segment
		(start 122.59691 -52.194968)
		(end 122.59691 -50.691288)
		(width 0.0889)
		(layer "In5.Cu")
		(net "PHY_SCC_TO_DPB_37_DN")
	)
	(segment
		(start 122.08891 -52.595272)
		(end 122.196606 -52.595272)
		(width 0.0889)
		(layer "In5.Cu")
		(net "PHY_SCC_TO_DPB_37_DN")
	)
	(segment
		(start 127.340868 -49.145952)
		(end 127.506984 -48.890428)
		(width 0.1016)
		(layer "In5.Cu")
		(net "PHY_SCC_TO_DPB_37_DN")
	)
	(segment
		(start 127.880364 -48.315118)
		(end 128.310386 -47.65294)
		(width 0.1016)
		(layer "In5.Cu")
		(net "PHY_SCC_TO_DPB_37_DN")
	)
	(segment
		(start 124.068586 -50.307748)
		(end 126.150624 -49.865534)
		(width 0.1016)
		(layer "In5.Cu")
		(net "PHY_SCC_TO_DPB_37_DN")
	)
	(segment
		(start 127.936498 -48.57877)
		(end 127.880364 -48.315118)
		(width 0.1016)
		(layer "In5.Cu")
		(net "PHY_SCC_TO_DPB_37_DN")
	)
	(segment
		(start 126.66853 -40.842946)
		(end 122.614944 -21.771864)
		(width 0.1016)
		(layer "In5.Cu")
		(net "PHY_SCC_TO_DPB_37_DN")
	)
	(segment
		(start 128.310386 -47.65294)
		(end 128.659128 -46.01464)
		(width 0.1016)
		(layer "In5.Cu")
		(net "PHY_SCC_TO_DPB_37_DN")
	)
	(segment
		(start 127.770382 -48.834294)
		(end 127.936498 -48.57877)
		(width 0.1016)
		(layer "In5.Cu")
		(net "PHY_SCC_TO_DPB_37_DN")
	)
	(segment
		(start 122.614944 -21.771864)
		(end 123.76531 -16.359886)
		(width 0.1016)
		(layer "In5.Cu")
		(net "PHY_SCC_TO_DPB_37_DN")
	)
	(segment
		(start 123.27128 -10.652506)
		(end 123.620784 -10.652506)
		(width 0.1016)
		(layer "In5.Cu")
		(net "PHY_SCC_TO_DPB_37_DN")
	)
	(segment
		(start 123.800108 -10.83183)
		(end 123.800108 -11.20013)
		(width 0.1016)
		(layer "In5.Cu")
		(net "PHY_SCC_TO_DPB_37_DN")
	)
	(segment
		(start 122.65406 -50.634138)
		(end 122.65406 -50.61204)
		(width 0.0889)
		(layer "In5.Cu")
		(net "PHY_SCC_TO_DPB_37_DN")
	)
	(segment
		(start 128.659128 -46.01464)
		(end 127.993902 -42.883582)
		(width 0.1016)
		(layer "In5.Cu")
		(net "PHY_SCC_TO_DPB_37_DN")
	)
	(segment
		(start 122.729498 -50.271934)
		(end 122.883168 -50.172366)
		(width 0.1016)
		(layer "In5.Cu")
		(net "PHY_SCC_TO_DPB_37_DN")
	)
	(segment
		(start 122.682508 -50.344324)
		(end 122.729498 -50.271934)
		(width 0.1016)
		(layer "In5.Cu")
		(net "PHY_SCC_TO_DPB_37_DN")
	)
	(segment
		(start 127.993902 -42.883582)
		(end 126.66853 -40.842946)
		(width 0.1016)
		(layer "In5.Cu")
		(net "PHY_SCC_TO_DPB_37_DN")
	)
	(arc
		(start 122.479816 -52.478178)
		(mid 122.566555 -52.348225)
		(end 122.59691 -52.194968)
		(width 0.0889)
		(layer "In5.Cu")
		(net "PHY_SCC_TO_DPB_37_DN")
	)
	(arc
		(start 123.620784 -10.652506)
		(mid 123.747585 -10.705029)
		(end 123.800108 -10.83183)
		(width 0.1016)
		(layer "In5.Cu")
		(net "PHY_SCC_TO_DPB_37_DN")
	)
	(arc
		(start 122.00001 -52.684172)
		(mid 122.026048 -52.62131)
		(end 122.08891 -52.595272)
		(width 0.0889)
		(layer "In5.Cu")
		(net "PHY_SCC_TO_DPB_37_DN")
	)
	(arc
		(start 123.052332 -10.871454)
		(mid 123.11646 -10.716634)
		(end 123.27128 -10.652506)
		(width 0.1016)
		(layer "In5.Cu")
		(net "PHY_SCC_TO_DPB_37_DN")
	)
	(arc
		(start 122.196606 -52.595272)
		(mid 122.349849 -52.564884)
		(end 122.479816 -52.478178)
		(width 0.0889)
		(layer "In5.Cu")
		(net "PHY_SCC_TO_DPB_37_DN")
	)
	(segment
		(start 120.50014 -51.500024)
		(end 121.000012 -51.000152)
		(width 0.104902)
		(layer "F.Cu")
		(net "PHY_SCC_TO_DPB_36_DP")
	)
	(via
		(at 121.000012 -51.000152)
		(size 0.4572)
		(drill 0.2032)
		(layers "F.Cu" "B.Cu")
		(net "PHY_SCC_TO_DPB_36_DP")
	)
	(segment
		(start 121.408698 -51.16322)
		(end 121.408698 -50.620676)
		(width 0.0889)
		(layer "In5.Cu")
		(net "PHY_SCC_TO_DPB_36_DP")
	)
	(segment
		(start 125.540262 -46.72838)
		(end 125.826012 -45.374306)
		(width 0.1016)
		(layer "In5.Cu")
		(net "PHY_SCC_TO_DPB_36_DP")
	)
	(segment
		(start 122.28322 -49.106328)
		(end 124.794264 -48.572674)
		(width 0.1016)
		(layer "In5.Cu")
		(net "PHY_SCC_TO_DPB_36_DP")
	)
	(segment
		(start 125.22581 -48.183038)
		(end 125.254512 -48.082962)
		(width 0.1016)
		(layer "In5.Cu")
		(net "PHY_SCC_TO_DPB_36_DP")
	)
	(segment
		(start 121.351548 -50.207672)
		(end 121.430288 -49.836578)
		(width 0.1016)
		(layer "In5.Cu")
		(net "PHY_SCC_TO_DPB_36_DP")
	)
	(segment
		(start 124.83338 -42.096182)
		(end 120.427496 -21.368258)
		(width 0.1016)
		(layer "In5.Cu")
		(net "PHY_SCC_TO_DPB_36_DP")
	)
	(segment
		(start 121.330212 -51.341782)
		(end 121.338086 -51.333908)
		(width 0.0889)
		(layer "In5.Cu")
		(net "PHY_SCC_TO_DPB_36_DP")
	)
	(segment
		(start 121.000012 -51.000152)
		(end 121.000012 -51.315874)
		(width 0.0889)
		(layer "In5.Cu")
		(net "PHY_SCC_TO_DPB_36_DP")
	)
	(segment
		(start 124.794264 -48.572674)
		(end 125.102366 -48.372776)
		(width 0.1016)
		(layer "In5.Cu")
		(net "PHY_SCC_TO_DPB_36_DP")
	)
	(segment
		(start 120.427496 -21.368258)
		(end 121.518934 -16.233648)
		(width 0.1016)
		(layer "In5.Cu")
		(net "PHY_SCC_TO_DPB_36_DP")
	)
	(segment
		(start 125.102366 -48.372776)
		(end 125.22581 -48.183038)
		(width 0.1016)
		(layer "In5.Cu")
		(net "PHY_SCC_TO_DPB_36_DP")
	)
	(segment
		(start 120.947688 -13.54582)
		(end 120.947688 -12.071096)
		(width 0.1016)
		(layer "In5.Cu")
		(net "PHY_SCC_TO_DPB_36_DP")
	)
	(segment
		(start 121.408698 -50.620676)
		(end 121.351548 -50.563526)
		(width 0.0889)
		(layer "In5.Cu")
		(net "PHY_SCC_TO_DPB_36_DP")
	)
	(segment
		(start 121.518934 -16.233648)
		(end 120.947688 -13.54582)
		(width 0.1016)
		(layer "In5.Cu")
		(net "PHY_SCC_TO_DPB_36_DP")
	)
	(segment
		(start 121.430288 -49.836578)
		(end 121.628408 -49.53127)
		(width 0.1016)
		(layer "In5.Cu")
		(net "PHY_SCC_TO_DPB_36_DP")
	)
	(segment
		(start 121.351548 -50.541428)
		(end 121.351548 -50.207672)
		(width 0.1016)
		(layer "In5.Cu")
		(net "PHY_SCC_TO_DPB_36_DP")
	)
	(segment
		(start 122.00001 -11.368278)
		(end 122.00001 -10.999978)
		(width 0.1016)
		(layer "In5.Cu")
		(net "PHY_SCC_TO_DPB_36_DP")
	)
	(segment
		(start 121.088912 -51.404774)
		(end 121.178066 -51.404774)
		(width 0.0889)
		(layer "In5.Cu")
		(net "PHY_SCC_TO_DPB_36_DP")
	)
	(segment
		(start 121.471182 -11.547602)
		(end 121.820686 -11.547602)
		(width 0.1016)
		(layer "In5.Cu")
		(net "PHY_SCC_TO_DPB_36_DP")
	)
	(segment
		(start 125.270768 -42.770044)
		(end 124.83338 -42.096182)
		(width 0.1016)
		(layer "In5.Cu")
		(net "PHY_SCC_TO_DPB_36_DP")
	)
	(segment
		(start 125.254512 -48.082962)
		(end 125.382528 -47.476156)
		(width 0.1016)
		(layer "In5.Cu")
		(net "PHY_SCC_TO_DPB_36_DP")
	)
	(segment
		(start 125.826012 -45.374306)
		(end 125.270768 -42.770044)
		(width 0.1016)
		(layer "In5.Cu")
		(net "PHY_SCC_TO_DPB_36_DP")
	)
	(segment
		(start 121.628408 -49.53127)
		(end 122.28322 -49.106328)
		(width 0.1016)
		(layer "In5.Cu")
		(net "PHY_SCC_TO_DPB_36_DP")
	)
	(segment
		(start 121.351548 -50.563526)
		(end 121.351548 -50.541428)
		(width 0.0889)
		(layer "In5.Cu")
		(net "PHY_SCC_TO_DPB_36_DP")
	)
	(segment
		(start 125.382528 -47.476156)
		(end 125.540262 -46.72838)
		(width 0.1016)
		(layer "In5.Cu")
		(net "PHY_SCC_TO_DPB_36_DP")
	)
	(arc
		(start 121.820686 -11.547602)
		(mid 121.947487 -11.495079)
		(end 122.00001 -11.368278)
		(width 0.1016)
		(layer "In5.Cu")
		(net "PHY_SCC_TO_DPB_36_DP")
	)
	(arc
		(start 121.178066 -51.404774)
		(mid 121.260396 -51.388398)
		(end 121.330212 -51.341782)
		(width 0.0889)
		(layer "In5.Cu")
		(net "PHY_SCC_TO_DPB_36_DP")
	)
	(arc
		(start 121.338086 -51.333908)
		(mid 121.390359 -51.255581)
		(end 121.408698 -51.16322)
		(width 0.0889)
		(layer "In5.Cu")
		(net "PHY_SCC_TO_DPB_36_DP")
	)
	(arc
		(start 121.000012 -51.315874)
		(mid 121.02605 -51.378736)
		(end 121.088912 -51.404774)
		(width 0.0889)
		(layer "In5.Cu")
		(net "PHY_SCC_TO_DPB_36_DP")
	)
	(arc
		(start 120.947688 -12.071096)
		(mid 121.101016 -11.70093)
		(end 121.471182 -11.547602)
		(width 0.1016)
		(layer "In5.Cu")
		(net "PHY_SCC_TO_DPB_36_DP")
	)
	(segment
		(start 120.50014 -52.500022)
		(end 121.000012 -52.00015)
		(width 0.104902)
		(layer "F.Cu")
		(net "PHY_SCC_TO_DPB_36_DN")
	)
	(via
		(at 121.000012 -52.00015)
		(size 0.4572)
		(drill 0.2032)
		(layers "F.Cu" "B.Cu")
		(net "PHY_SCC_TO_DPB_36_DN")
	)
	(segment
		(start 121.717054 -49.955196)
		(end 121.84888 -49.751742)
		(width 0.1016)
		(layer "In5.Cu")
		(net "PHY_SCC_TO_DPB_36_DN")
	)
	(segment
		(start 120.739154 -21.368258)
		(end 121.830592 -16.233648)
		(width 0.1016)
		(layer "In5.Cu")
		(net "PHY_SCC_TO_DPB_36_DN")
	)
	(segment
		(start 121.84888 -49.751742)
		(end 122.401838 -49.39284)
		(width 0.1016)
		(layer "In5.Cu")
		(net "PHY_SCC_TO_DPB_36_DN")
	)
	(segment
		(start 125.119892 -41.977564)
		(end 120.739154 -21.368258)
		(width 0.1016)
		(layer "In5.Cu")
		(net "PHY_SCC_TO_DPB_36_DN")
	)
	(segment
		(start 121.830592 -16.233648)
		(end 121.252488 -13.513562)
		(width 0.1016)
		(layer "In5.Cu")
		(net "PHY_SCC_TO_DPB_36_DN")
	)
	(segment
		(start 121.088912 -51.595274)
		(end 121.178066 -51.595274)
		(width 0.0889)
		(layer "In5.Cu")
		(net "PHY_SCC_TO_DPB_36_DN")
	)
	(segment
		(start 125.322838 -48.593502)
		(end 125.50648 -48.3108)
		(width 0.1016)
		(layer "In5.Cu")
		(net "PHY_SCC_TO_DPB_36_DN")
	)
	(segment
		(start 121.000012 -52.00015)
		(end 121.000012 -51.684174)
		(width 0.0889)
		(layer "In5.Cu")
		(net "PHY_SCC_TO_DPB_36_DN")
	)
	(segment
		(start 121.656348 -50.239676)
		(end 121.717054 -49.955196)
		(width 0.1016)
		(layer "In5.Cu")
		(net "PHY_SCC_TO_DPB_36_DN")
	)
	(segment
		(start 122.401838 -49.39284)
		(end 123.453652 -49.16932)
		(width 0.1016)
		(layer "In5.Cu")
		(net "PHY_SCC_TO_DPB_36_DN")
	)
	(segment
		(start 123.453652 -49.16932)
		(end 123.679458 -49.316132)
		(width 0.1016)
		(layer "In5.Cu")
		(net "PHY_SCC_TO_DPB_36_DN")
	)
	(segment
		(start 121.252488 -13.513562)
		(end 121.252488 -12.071096)
		(width 0.1016)
		(layer "In5.Cu")
		(net "PHY_SCC_TO_DPB_36_DN")
	)
	(segment
		(start 125.55728 -42.651172)
		(end 125.119892 -41.977564)
		(width 0.1016)
		(layer "In5.Cu")
		(net "PHY_SCC_TO_DPB_36_DN")
	)
	(segment
		(start 121.599198 -51.16322)
		(end 121.599198 -50.620676)
		(width 0.0889)
		(layer "In5.Cu")
		(net "PHY_SCC_TO_DPB_36_DN")
	)
	(segment
		(start 122.00001 -12.031726)
		(end 122.00001 -12.400026)
		(width 0.1016)
		(layer "In5.Cu")
		(net "PHY_SCC_TO_DPB_36_DN")
	)
	(segment
		(start 121.656348 -50.563526)
		(end 121.656348 -50.541428)
		(width 0.0889)
		(layer "In5.Cu")
		(net "PHY_SCC_TO_DPB_36_DN")
	)
	(segment
		(start 125.50648 -48.3108)
		(end 125.551184 -48.154336)
		(width 0.1016)
		(layer "In5.Cu")
		(net "PHY_SCC_TO_DPB_36_DN")
	)
	(segment
		(start 126.13767 -45.374052)
		(end 125.55728 -42.651172)
		(width 0.1016)
		(layer "In5.Cu")
		(net "PHY_SCC_TO_DPB_36_DN")
	)
	(segment
		(start 121.656348 -50.541428)
		(end 121.656348 -50.239676)
		(width 0.1016)
		(layer "In5.Cu")
		(net "PHY_SCC_TO_DPB_36_DN")
	)
	(segment
		(start 123.977654 -49.252632)
		(end 124.124466 -49.026826)
		(width 0.1016)
		(layer "In5.Cu")
		(net "PHY_SCC_TO_DPB_36_DN")
	)
	(segment
		(start 121.465086 -51.476656)
		(end 121.47296 -51.468528)
		(width 0.0889)
		(layer "In5.Cu")
		(net "PHY_SCC_TO_DPB_36_DN")
	)
	(segment
		(start 124.912882 -48.859186)
		(end 125.322838 -48.593502)
		(width 0.1016)
		(layer "In5.Cu")
		(net "PHY_SCC_TO_DPB_36_DN")
	)
	(segment
		(start 121.471182 -11.852402)
		(end 121.820686 -11.852402)
		(width 0.1016)
		(layer "In5.Cu")
		(net "PHY_SCC_TO_DPB_36_DN")
	)
	(segment
		(start 124.124466 -49.026826)
		(end 124.912882 -48.859186)
		(width 0.1016)
		(layer "In5.Cu")
		(net "PHY_SCC_TO_DPB_36_DN")
	)
	(segment
		(start 125.551184 -48.154336)
		(end 126.13767 -45.374052)
		(width 0.1016)
		(layer "In5.Cu")
		(net "PHY_SCC_TO_DPB_36_DN")
	)
	(segment
		(start 123.679458 -49.316132)
		(end 123.977654 -49.252632)
		(width 0.1016)
		(layer "In5.Cu")
		(net "PHY_SCC_TO_DPB_36_DN")
	)
	(segment
		(start 121.599198 -50.620676)
		(end 121.656348 -50.563526)
		(width 0.0889)
		(layer "In5.Cu")
		(net "PHY_SCC_TO_DPB_36_DN")
	)
	(arc
		(start 121.47296 -51.468528)
		(mid 121.566395 -51.328409)
		(end 121.599198 -51.16322)
		(width 0.0889)
		(layer "In5.Cu")
		(net "PHY_SCC_TO_DPB_36_DN")
	)
	(arc
		(start 121.000012 -51.684174)
		(mid 121.02605 -51.621312)
		(end 121.088912 -51.595274)
		(width 0.0889)
		(layer "In5.Cu")
		(net "PHY_SCC_TO_DPB_36_DN")
	)
	(arc
		(start 121.178066 -51.595274)
		(mid 121.333365 -51.564495)
		(end 121.465086 -51.476656)
		(width 0.0889)
		(layer "In5.Cu")
		(net "PHY_SCC_TO_DPB_36_DN")
	)
	(arc
		(start 121.252488 -12.071096)
		(mid 121.316542 -11.916456)
		(end 121.471182 -11.852402)
		(width 0.1016)
		(layer "In5.Cu")
		(net "PHY_SCC_TO_DPB_36_DN")
	)
	(arc
		(start 121.820686 -11.852402)
		(mid 121.947487 -11.904925)
		(end 122.00001 -12.031726)
		(width 0.1016)
		(layer "In5.Cu")
		(net "PHY_SCC_TO_DPB_36_DN")
	)
	(segment
		(start 119.500142 -52.500022)
		(end 120.000014 -52.00015)
		(width 0.104902)
		(layer "F.Cu")
		(net "PHY_SCC_TO_DPB_35_DP")
	)
	(via
		(at 120.000014 -52.00015)
		(size 0.4572)
		(drill 0.2032)
		(layers "F.Cu" "B.Cu")
		(net "PHY_SCC_TO_DPB_35_DP")
	)
	(segment
		(start 118.836186 -22.49043)
		(end 123.519184 -44.509436)
		(width 0.1016)
		(layer "In5.Cu")
		(net "PHY_SCC_TO_DPB_35_DP")
	)
	(segment
		(start 119.14759 -10.871454)
		(end 119.14759 -16.124936)
		(width 0.1016)
		(layer "In5.Cu")
		(net "PHY_SCC_TO_DPB_35_DP")
	)
	(segment
		(start 123.141486 -45.748448)
		(end 120.347232 -50.05197)
		(width 0.1016)
		(layer "In5.Cu")
		(net "PHY_SCC_TO_DPB_35_DP")
	)
	(segment
		(start 120.347232 -50.523902)
		(end 120.347232 -50.546)
		(width 0.0889)
		(layer "In5.Cu")
		(net "PHY_SCC_TO_DPB_35_DP")
	)
	(segment
		(start 120.347232 -50.546)
		(end 120.404382 -50.60315)
		(width 0.0889)
		(layer "In5.Cu")
		(net "PHY_SCC_TO_DPB_35_DP")
	)
	(segment
		(start 119.14759 -16.124936)
		(end 119.668544 -18.57629)
		(width 0.1016)
		(layer "In5.Cu")
		(net "PHY_SCC_TO_DPB_35_DP")
	)
	(segment
		(start 120.020842 -10.347706)
		(end 119.671338 -10.347706)
		(width 0.1016)
		(layer "In5.Cu")
		(net "PHY_SCC_TO_DPB_35_DP")
	)
	(segment
		(start 120.277636 -52.404772)
		(end 120.088914 -52.404772)
		(width 0.0889)
		(layer "In5.Cu")
		(net "PHY_SCC_TO_DPB_35_DP")
	)
	(segment
		(start 120.347232 -50.05197)
		(end 120.347232 -50.523902)
		(width 0.1016)
		(layer "In5.Cu")
		(net "PHY_SCC_TO_DPB_35_DP")
	)
	(segment
		(start 120.404382 -50.60315)
		(end 120.404382 -52.277772)
		(width 0.0889)
		(layer "In5.Cu")
		(net "PHY_SCC_TO_DPB_35_DP")
	)
	(segment
		(start 120.000014 -52.315872)
		(end 120.000014 -52.00015)
		(width 0.0889)
		(layer "In5.Cu")
		(net "PHY_SCC_TO_DPB_35_DP")
	)
	(segment
		(start 123.405138 -45.37329)
		(end 123.141486 -45.748448)
		(width 0.1016)
		(layer "In5.Cu")
		(net "PHY_SCC_TO_DPB_35_DP")
	)
	(segment
		(start 123.519184 -44.509436)
		(end 123.519184 -44.726352)
		(width 0.1016)
		(layer "In5.Cu")
		(net "PHY_SCC_TO_DPB_35_DP")
	)
	(segment
		(start 119.668544 -18.57629)
		(end 118.836186 -22.49043)
		(width 0.1016)
		(layer "In5.Cu")
		(net "PHY_SCC_TO_DPB_35_DP")
	)
	(segment
		(start 120.200166 -9.800082)
		(end 120.200166 -10.168382)
		(width 0.1016)
		(layer "In5.Cu")
		(net "PHY_SCC_TO_DPB_35_DP")
	)
	(segment
		(start 123.519184 -44.726352)
		(end 123.405138 -45.37329)
		(width 0.1016)
		(layer "In5.Cu")
		(net "PHY_SCC_TO_DPB_35_DP")
	)
	(arc
		(start 120.367044 -52.367688)
		(mid 120.326038 -52.395151)
		(end 120.277636 -52.404772)
		(width 0.0889)
		(layer "In5.Cu")
		(net "PHY_SCC_TO_DPB_35_DP")
	)
	(arc
		(start 120.088914 -52.404772)
		(mid 120.026052 -52.378734)
		(end 120.000014 -52.315872)
		(width 0.0889)
		(layer "In5.Cu")
		(net "PHY_SCC_TO_DPB_35_DP")
	)
	(arc
		(start 120.404382 -52.277772)
		(mid 120.39468 -52.326456)
		(end 120.367044 -52.367688)
		(width 0.0889)
		(layer "In5.Cu")
		(net "PHY_SCC_TO_DPB_35_DP")
	)
	(arc
		(start 119.671338 -10.347706)
		(mid 119.300992 -10.501108)
		(end 119.14759 -10.871454)
		(width 0.1016)
		(layer "In5.Cu")
		(net "PHY_SCC_TO_DPB_35_DP")
	)
	(arc
		(start 120.200166 -10.168382)
		(mid 120.147643 -10.295183)
		(end 120.020842 -10.347706)
		(width 0.1016)
		(layer "In5.Cu")
		(net "PHY_SCC_TO_DPB_35_DP")
	)
	(segment
		(start 119.500142 -53.50002)
		(end 120.000014 -53.000148)
		(width 0.104902)
		(layer "F.Cu")
		(net "PHY_SCC_TO_DPB_35_DN")
	)
	(via
		(at 120.000014 -53.000148)
		(size 0.4572)
		(drill 0.2032)
		(layers "F.Cu" "B.Cu")
		(net "PHY_SCC_TO_DPB_35_DN")
	)
	(segment
		(start 123.027948 -46.833282)
		(end 122.862086 -47.088806)
		(width 0.1016)
		(layer "In5.Cu")
		(net "PHY_SCC_TO_DPB_35_DN")
	)
	(segment
		(start 119.980202 -18.57629)
		(end 119.147844 -22.49043)
		(width 0.1016)
		(layer "In5.Cu")
		(net "PHY_SCC_TO_DPB_35_DN")
	)
	(segment
		(start 120.594882 -50.60315)
		(end 120.594882 -52.277772)
		(width 0.0889)
		(layer "In5.Cu")
		(net "PHY_SCC_TO_DPB_35_DN")
	)
	(segment
		(start 122.598434 -47.14494)
		(end 120.652032 -50.142394)
		(width 0.1016)
		(layer "In5.Cu")
		(net "PHY_SCC_TO_DPB_35_DN")
	)
	(segment
		(start 122.972068 -46.56963)
		(end 123.027948 -46.833282)
		(width 0.1016)
		(layer "In5.Cu")
		(net "PHY_SCC_TO_DPB_35_DN")
	)
	(segment
		(start 120.020842 -10.652506)
		(end 119.671338 -10.652506)
		(width 0.1016)
		(layer "In5.Cu")
		(net "PHY_SCC_TO_DPB_35_DN")
	)
	(segment
		(start 120.000014 -52.684172)
		(end 120.000014 -53.000148)
		(width 0.0889)
		(layer "In5.Cu")
		(net "PHY_SCC_TO_DPB_35_DN")
	)
	(segment
		(start 120.277636 -52.595272)
		(end 120.088914 -52.595272)
		(width 0.0889)
		(layer "In5.Cu")
		(net "PHY_SCC_TO_DPB_35_DN")
	)
	(segment
		(start 122.862086 -47.088806)
		(end 122.598434 -47.14494)
		(width 0.1016)
		(layer "In5.Cu")
		(net "PHY_SCC_TO_DPB_35_DN")
	)
	(segment
		(start 120.652032 -50.523902)
		(end 120.652032 -50.546)
		(width 0.0889)
		(layer "In5.Cu")
		(net "PHY_SCC_TO_DPB_35_DN")
	)
	(segment
		(start 120.652032 -50.546)
		(end 120.594882 -50.60315)
		(width 0.0889)
		(layer "In5.Cu")
		(net "PHY_SCC_TO_DPB_35_DN")
	)
	(segment
		(start 123.39447 -45.919136)
		(end 122.972068 -46.56963)
		(width 0.1016)
		(layer "In5.Cu")
		(net "PHY_SCC_TO_DPB_35_DN")
	)
	(segment
		(start 120.652032 -50.142394)
		(end 120.652032 -50.523902)
		(width 0.1016)
		(layer "In5.Cu")
		(net "PHY_SCC_TO_DPB_35_DN")
	)
	(segment
		(start 120.200166 -11.20013)
		(end 120.200166 -10.83183)
		(width 0.1016)
		(layer "In5.Cu")
		(net "PHY_SCC_TO_DPB_35_DN")
	)
	(segment
		(start 119.147844 -22.49043)
		(end 123.823984 -44.477178)
		(width 0.1016)
		(layer "In5.Cu")
		(net "PHY_SCC_TO_DPB_35_DN")
	)
	(segment
		(start 123.823984 -44.753022)
		(end 123.693682 -45.493178)
		(width 0.1016)
		(layer "In5.Cu")
		(net "PHY_SCC_TO_DPB_35_DN")
	)
	(segment
		(start 123.693682 -45.493178)
		(end 123.39447 -45.919136)
		(width 0.1016)
		(layer "In5.Cu")
		(net "PHY_SCC_TO_DPB_35_DN")
	)
	(segment
		(start 119.45239 -16.092678)
		(end 119.980202 -18.57629)
		(width 0.1016)
		(layer "In5.Cu")
		(net "PHY_SCC_TO_DPB_35_DN")
	)
	(segment
		(start 123.823984 -44.477178)
		(end 123.823984 -44.753022)
		(width 0.1016)
		(layer "In5.Cu")
		(net "PHY_SCC_TO_DPB_35_DN")
	)
	(segment
		(start 119.45239 -10.871454)
		(end 119.45239 -16.092678)
		(width 0.1016)
		(layer "In5.Cu")
		(net "PHY_SCC_TO_DPB_35_DN")
	)
	(arc
		(start 120.501664 -52.502562)
		(mid 120.398865 -52.571187)
		(end 120.277636 -52.595272)
		(width 0.0889)
		(layer "In5.Cu")
		(net "PHY_SCC_TO_DPB_35_DN")
	)
	(arc
		(start 120.594882 -52.277772)
		(mid 120.57066 -52.399454)
		(end 120.501664 -52.502562)
		(width 0.0889)
		(layer "In5.Cu")
		(net "PHY_SCC_TO_DPB_35_DN")
	)
	(arc
		(start 120.088914 -52.595272)
		(mid 120.026052 -52.62131)
		(end 120.000014 -52.684172)
		(width 0.0889)
		(layer "In5.Cu")
		(net "PHY_SCC_TO_DPB_35_DN")
	)
	(arc
		(start 120.200166 -10.83183)
		(mid 120.147643 -10.705029)
		(end 120.020842 -10.652506)
		(width 0.1016)
		(layer "In5.Cu")
		(net "PHY_SCC_TO_DPB_35_DN")
	)
	(arc
		(start 119.671338 -10.652506)
		(mid 119.516518 -10.716634)
		(end 119.45239 -10.871454)
		(width 0.1016)
		(layer "In5.Cu")
		(net "PHY_SCC_TO_DPB_35_DN")
	)
	(segment
		(start 118.500144 -51.500024)
		(end 119.000016 -51.000152)
		(width 0.104902)
		(layer "F.Cu")
		(net "PHY_SCC_TO_DPB_34_DP")
	)
	(via
		(at 119.000016 -51.000152)
		(size 0.4572)
		(drill 0.2032)
		(layers "F.Cu" "B.Cu")
		(net "PHY_SCC_TO_DPB_34_DP")
	)
	(segment
		(start 121.98477 -42.29354)
		(end 121.984262 -42.293032)
		(width 0.1016)
		(layer "In5.Cu")
		(net "PHY_SCC_TO_DPB_34_DP")
	)
	(segment
		(start 121.97588 -45.964856)
		(end 122.477784 -44.760388)
		(width 0.1016)
		(layer "In5.Cu")
		(net "PHY_SCC_TO_DPB_34_DP")
	)
	(segment
		(start 119.000016 -51.000152)
		(end 119.000016 -51.315874)
		(width 0.0889)
		(layer "In5.Cu")
		(net "PHY_SCC_TO_DPB_34_DP")
	)
	(segment
		(start 118.400068 -11.368278)
		(end 118.400068 -10.999978)
		(width 0.1016)
		(layer "In5.Cu")
		(net "PHY_SCC_TO_DPB_34_DP")
	)
	(segment
		(start 116.98732 -22.862286)
		(end 117.987064 -18.159984)
		(width 0.1016)
		(layer "In5.Cu")
		(net "PHY_SCC_TO_DPB_34_DP")
	)
	(segment
		(start 119.351552 -50.563526)
		(end 119.351552 -50.541428)
		(width 0.0889)
		(layer "In5.Cu")
		(net "PHY_SCC_TO_DPB_34_DP")
	)
	(segment
		(start 117.987064 -18.159984)
		(end 117.347746 -15.153132)
		(width 0.1016)
		(layer "In5.Cu")
		(net "PHY_SCC_TO_DPB_34_DP")
	)
	(segment
		(start 119.351552 -50.005234)
		(end 121.97588 -45.964856)
		(width 0.1016)
		(layer "In5.Cu")
		(net "PHY_SCC_TO_DPB_34_DP")
	)
	(segment
		(start 121.985278 -42.293286)
		(end 121.98477 -42.29354)
		(width 0.1016)
		(layer "In5.Cu")
		(net "PHY_SCC_TO_DPB_34_DP")
	)
	(segment
		(start 122.477784 -44.760388)
		(end 122.477784 -43.690794)
		(width 0.1016)
		(layer "In5.Cu")
		(net "PHY_SCC_TO_DPB_34_DP")
	)
	(segment
		(start 121.984262 -42.293032)
		(end 120.69699 -40.31107)
		(width 0.1016)
		(layer "In5.Cu")
		(net "PHY_SCC_TO_DPB_34_DP")
	)
	(segment
		(start 119.341138 -51.378612)
		(end 119.361712 -51.357784)
		(width 0.0889)
		(layer "In5.Cu")
		(net "PHY_SCC_TO_DPB_34_DP")
	)
	(segment
		(start 119.408702 -50.620676)
		(end 119.351552 -50.563526)
		(width 0.0889)
		(layer "In5.Cu")
		(net "PHY_SCC_TO_DPB_34_DP")
	)
	(segment
		(start 119.408702 -51.244754)
		(end 119.408702 -50.620676)
		(width 0.0889)
		(layer "In5.Cu")
		(net "PHY_SCC_TO_DPB_34_DP")
	)
	(segment
		(start 119.088916 -51.404774)
		(end 119.277892 -51.404774)
		(width 0.0889)
		(layer "In5.Cu")
		(net "PHY_SCC_TO_DPB_34_DP")
	)
	(segment
		(start 122.477784 -43.690794)
		(end 122.356118 -43.000676)
		(width 0.1016)
		(layer "In5.Cu")
		(net "PHY_SCC_TO_DPB_34_DP")
	)
	(segment
		(start 117.347746 -15.153132)
		(end 117.347746 -12.071096)
		(width 0.1016)
		(layer "In5.Cu")
		(net "PHY_SCC_TO_DPB_34_DP")
	)
	(segment
		(start 122.356118 -43.000676)
		(end 121.985278 -42.293286)
		(width 0.1016)
		(layer "In5.Cu")
		(net "PHY_SCC_TO_DPB_34_DP")
	)
	(segment
		(start 117.87124 -11.547602)
		(end 118.220744 -11.547602)
		(width 0.1016)
		(layer "In5.Cu")
		(net "PHY_SCC_TO_DPB_34_DP")
	)
	(segment
		(start 120.69699 -40.31107)
		(end 116.98732 -22.862286)
		(width 0.1016)
		(layer "In5.Cu")
		(net "PHY_SCC_TO_DPB_34_DP")
	)
	(segment
		(start 119.351552 -50.541428)
		(end 119.351552 -50.005234)
		(width 0.1016)
		(layer "In5.Cu")
		(net "PHY_SCC_TO_DPB_34_DP")
	)
	(arc
		(start 119.277892 -51.404774)
		(mid 119.312132 -51.398021)
		(end 119.341138 -51.378612)
		(width 0.0889)
		(layer "In5.Cu")
		(net "PHY_SCC_TO_DPB_34_DP")
	)
	(arc
		(start 118.220744 -11.547602)
		(mid 118.347545 -11.495079)
		(end 118.400068 -11.368278)
		(width 0.1016)
		(layer "In5.Cu")
		(net "PHY_SCC_TO_DPB_34_DP")
	)
	(arc
		(start 119.361712 -51.357784)
		(mid 119.396446 -51.30594)
		(end 119.408702 -51.244754)
		(width 0.0889)
		(layer "In5.Cu")
		(net "PHY_SCC_TO_DPB_34_DP")
	)
	(arc
		(start 117.347746 -12.071096)
		(mid 117.501074 -11.70093)
		(end 117.87124 -11.547602)
		(width 0.1016)
		(layer "In5.Cu")
		(net "PHY_SCC_TO_DPB_34_DP")
	)
	(arc
		(start 119.000016 -51.315874)
		(mid 119.026054 -51.378736)
		(end 119.088916 -51.404774)
		(width 0.0889)
		(layer "In5.Cu")
		(net "PHY_SCC_TO_DPB_34_DP")
	)
	(segment
		(start 118.500144 -52.500022)
		(end 119.000016 -52.00015)
		(width 0.104902)
		(layer "F.Cu")
		(net "PHY_SCC_TO_DPB_34_DN")
	)
	(via
		(at 119.000016 -52.00015)
		(size 0.4572)
		(drill 0.2032)
		(layers "F.Cu" "B.Cu")
		(net "PHY_SCC_TO_DPB_34_DN")
	)
	(segment
		(start 119.599202 -51.245008)
		(end 119.599202 -50.620676)
		(width 0.0889)
		(layer "In5.Cu")
		(net "PHY_SCC_TO_DPB_34_DN")
	)
	(segment
		(start 118.400068 -12.031726)
		(end 118.400068 -12.400026)
		(width 0.1016)
		(layer "In5.Cu")
		(net "PHY_SCC_TO_DPB_34_DN")
	)
	(segment
		(start 118.298722 -18.159984)
		(end 117.652546 -15.120874)
		(width 0.1016)
		(layer "In5.Cu")
		(net "PHY_SCC_TO_DPB_34_DN")
	)
	(segment
		(start 121.647204 -41.214294)
		(end 120.983502 -40.192452)
		(width 0.1016)
		(layer "In5.Cu")
		(net "PHY_SCC_TO_DPB_34_DN")
	)
	(segment
		(start 122.246898 -46.107604)
		(end 122.383042 -45.780706)
		(width 0.1016)
		(layer "In5.Cu")
		(net "PHY_SCC_TO_DPB_34_DN")
	)
	(segment
		(start 117.87124 -11.852402)
		(end 118.220744 -11.852402)
		(width 0.1016)
		(layer "In5.Cu")
		(net "PHY_SCC_TO_DPB_34_DN")
	)
	(segment
		(start 120.983502 -40.192452)
		(end 117.298978 -22.862286)
		(width 0.1016)
		(layer "In5.Cu")
		(net "PHY_SCC_TO_DPB_34_DN")
	)
	(segment
		(start 119.656352 -50.563526)
		(end 119.656352 -50.449734)
		(width 0.0889)
		(layer "In5.Cu")
		(net "PHY_SCC_TO_DPB_34_DN")
	)
	(segment
		(start 117.298978 -22.862286)
		(end 118.298722 -18.159984)
		(width 0.1016)
		(layer "In5.Cu")
		(net "PHY_SCC_TO_DPB_34_DN")
	)
	(segment
		(start 119.47652 -51.512724)
		(end 119.49684 -51.49215)
		(width 0.0889)
		(layer "In5.Cu")
		(net "PHY_SCC_TO_DPB_34_DN")
	)
	(segment
		(start 117.652546 -15.120874)
		(end 117.652546 -12.071096)
		(width 0.1016)
		(layer "In5.Cu")
		(net "PHY_SCC_TO_DPB_34_DN")
	)
	(segment
		(start 119.656352 -50.095658)
		(end 122.246898 -46.107604)
		(width 0.1016)
		(layer "In5.Cu")
		(net "PHY_SCC_TO_DPB_34_DN")
	)
	(segment
		(start 122.383042 -45.780706)
		(end 122.782584 -44.821602)
		(width 0.1016)
		(layer "In5.Cu")
		(net "PHY_SCC_TO_DPB_34_DN")
	)
	(segment
		(start 119.088916 -51.595274)
		(end 119.277638 -51.595274)
		(width 0.0889)
		(layer "In5.Cu")
		(net "PHY_SCC_TO_DPB_34_DN")
	)
	(segment
		(start 121.910856 -41.270174)
		(end 121.647204 -41.214294)
		(width 0.1016)
		(layer "In5.Cu")
		(net "PHY_SCC_TO_DPB_34_DN")
	)
	(segment
		(start 122.25528 -42.152062)
		(end 122.256296 -42.151554)
		(width 0.1016)
		(layer "In5.Cu")
		(net "PHY_SCC_TO_DPB_34_DN")
	)
	(segment
		(start 122.020838 -41.78935)
		(end 122.076718 -41.525698)
		(width 0.1016)
		(layer "In5.Cu")
		(net "PHY_SCC_TO_DPB_34_DN")
	)
	(segment
		(start 119.599202 -50.620676)
		(end 119.656352 -50.563526)
		(width 0.0889)
		(layer "In5.Cu")
		(net "PHY_SCC_TO_DPB_34_DN")
	)
	(segment
		(start 119.000016 -52.00015)
		(end 119.000016 -51.684174)
		(width 0.0889)
		(layer "In5.Cu")
		(net "PHY_SCC_TO_DPB_34_DN")
	)
	(segment
		(start 119.656352 -50.449734)
		(end 119.656352 -50.095658)
		(width 0.1016)
		(layer "In5.Cu")
		(net "PHY_SCC_TO_DPB_34_DN")
	)
	(segment
		(start 122.648218 -42.901108)
		(end 122.25528 -42.152062)
		(width 0.1016)
		(layer "In5.Cu")
		(net "PHY_SCC_TO_DPB_34_DN")
	)
	(segment
		(start 122.782584 -44.821602)
		(end 122.782584 -43.664124)
		(width 0.1016)
		(layer "In5.Cu")
		(net "PHY_SCC_TO_DPB_34_DN")
	)
	(segment
		(start 122.256296 -42.151554)
		(end 122.255788 -42.151046)
		(width 0.1016)
		(layer "In5.Cu")
		(net "PHY_SCC_TO_DPB_34_DN")
	)
	(segment
		(start 122.255788 -42.151046)
		(end 122.020838 -41.78935)
		(width 0.1016)
		(layer "In5.Cu")
		(net "PHY_SCC_TO_DPB_34_DN")
	)
	(segment
		(start 122.782584 -43.664124)
		(end 122.648218 -42.901108)
		(width 0.1016)
		(layer "In5.Cu")
		(net "PHY_SCC_TO_DPB_34_DN")
	)
	(segment
		(start 122.076718 -41.525698)
		(end 121.910856 -41.270174)
		(width 0.1016)
		(layer "In5.Cu")
		(net "PHY_SCC_TO_DPB_34_DN")
	)
	(arc
		(start 119.49684 -51.49215)
		(mid 119.572556 -51.378734)
		(end 119.599202 -51.245008)
		(width 0.0889)
		(layer "In5.Cu")
		(net "PHY_SCC_TO_DPB_34_DN")
	)
	(arc
		(start 119.000016 -51.684174)
		(mid 119.026054 -51.621312)
		(end 119.088916 -51.595274)
		(width 0.0889)
		(layer "In5.Cu")
		(net "PHY_SCC_TO_DPB_34_DN")
	)
	(arc
		(start 118.220744 -11.852402)
		(mid 118.347545 -11.904925)
		(end 118.400068 -12.031726)
		(width 0.1016)
		(layer "In5.Cu")
		(net "PHY_SCC_TO_DPB_34_DN")
	)
	(arc
		(start 119.277638 -51.595274)
		(mid 119.385331 -51.573897)
		(end 119.47652 -51.512724)
		(width 0.0889)
		(layer "In5.Cu")
		(net "PHY_SCC_TO_DPB_34_DN")
	)
	(arc
		(start 117.652546 -12.071096)
		(mid 117.7166 -11.916456)
		(end 117.87124 -11.852402)
		(width 0.1016)
		(layer "In5.Cu")
		(net "PHY_SCC_TO_DPB_34_DN")
	)
	(segment
		(start 117.500146 -52.500022)
		(end 118.000018 -52.00015)
		(width 0.104902)
		(layer "F.Cu")
		(net "PHY_SCC_TO_DPB_33_DP")
	)
	(via
		(at 118.000018 -52.00015)
		(size 0.4572)
		(drill 0.2032)
		(layers "F.Cu" "B.Cu")
		(net "PHY_SCC_TO_DPB_33_DP")
	)
	(segment
		(start 121.436384 -44.774866)
		(end 121.34215 -45.309536)
		(width 0.1016)
		(layer "In5.Cu")
		(net "PHY_SCC_TO_DPB_33_DP")
	)
	(segment
		(start 118.28907 -52.404772)
		(end 118.088918 -52.404772)
		(width 0.0889)
		(layer "In5.Cu")
		(net "PHY_SCC_TO_DPB_33_DP")
	)
	(segment
		(start 119.662956 -40.636698)
		(end 121.071894 -42.805858)
		(width 0.1016)
		(layer "In5.Cu")
		(net "PHY_SCC_TO_DPB_33_DP")
	)
	(segment
		(start 121.361962 -43.220132)
		(end 121.436384 -43.641264)
		(width 0.1016)
		(layer "In5.Cu")
		(net "PHY_SCC_TO_DPB_33_DP")
	)
	(segment
		(start 118.432834 -49.789334)
		(end 118.347236 -50.19167)
		(width 0.1016)
		(layer "In5.Cu")
		(net "PHY_SCC_TO_DPB_33_DP")
	)
	(segment
		(start 116.420646 -10.347706)
		(end 116.071142 -10.347706)
		(width 0.1016)
		(layer "In5.Cu")
		(net "PHY_SCC_TO_DPB_33_DP")
	)
	(segment
		(start 121.436384 -43.641264)
		(end 121.436384 -44.774866)
		(width 0.1016)
		(layer "In5.Cu")
		(net "PHY_SCC_TO_DPB_33_DP")
	)
	(segment
		(start 121.34215 -45.309536)
		(end 118.432834 -49.789334)
		(width 0.1016)
		(layer "In5.Cu")
		(net "PHY_SCC_TO_DPB_33_DP")
	)
	(segment
		(start 115.547648 -10.8712)
		(end 115.547648 -21.274532)
		(width 0.1016)
		(layer "In5.Cu")
		(net "PHY_SCC_TO_DPB_33_DP")
	)
	(segment
		(start 118.347236 -50.19167)
		(end 118.347236 -50.523902)
		(width 0.1016)
		(layer "In5.Cu")
		(net "PHY_SCC_TO_DPB_33_DP")
	)
	(segment
		(start 115.547648 -21.274532)
		(end 119.662956 -40.636698)
		(width 0.1016)
		(layer "In5.Cu")
		(net "PHY_SCC_TO_DPB_33_DP")
	)
	(segment
		(start 121.071894 -42.805858)
		(end 121.361962 -43.220132)
		(width 0.1016)
		(layer "In5.Cu")
		(net "PHY_SCC_TO_DPB_33_DP")
	)
	(segment
		(start 118.347236 -50.523902)
		(end 118.347236 -50.546)
		(width 0.0889)
		(layer "In5.Cu")
		(net "PHY_SCC_TO_DPB_33_DP")
	)
	(segment
		(start 116.59997 -9.800082)
		(end 116.59997 -10.168382)
		(width 0.1016)
		(layer "In5.Cu")
		(net "PHY_SCC_TO_DPB_33_DP")
	)
	(segment
		(start 118.404386 -50.60315)
		(end 118.404386 -52.289456)
		(width 0.0889)
		(layer "In5.Cu")
		(net "PHY_SCC_TO_DPB_33_DP")
	)
	(segment
		(start 118.347236 -50.546)
		(end 118.404386 -50.60315)
		(width 0.0889)
		(layer "In5.Cu")
		(net "PHY_SCC_TO_DPB_33_DP")
	)
	(segment
		(start 118.000018 -52.315872)
		(end 118.000018 -52.00015)
		(width 0.0889)
		(layer "In5.Cu")
		(net "PHY_SCC_TO_DPB_33_DP")
	)
	(arc
		(start 118.088918 -52.404772)
		(mid 118.026056 -52.378734)
		(end 118.000018 -52.315872)
		(width 0.0889)
		(layer "In5.Cu")
		(net "PHY_SCC_TO_DPB_33_DP")
	)
	(arc
		(start 116.071142 -10.347706)
		(mid 115.700976 -10.501034)
		(end 115.547648 -10.8712)
		(width 0.1016)
		(layer "In5.Cu")
		(net "PHY_SCC_TO_DPB_33_DP")
	)
	(arc
		(start 118.370604 -52.37099)
		(mid 118.333196 -52.395985)
		(end 118.28907 -52.404772)
		(width 0.0889)
		(layer "In5.Cu")
		(net "PHY_SCC_TO_DPB_33_DP")
	)
	(arc
		(start 118.404386 -52.289456)
		(mid 118.395608 -52.333586)
		(end 118.370604 -52.37099)
		(width 0.0889)
		(layer "In5.Cu")
		(net "PHY_SCC_TO_DPB_33_DP")
	)
	(arc
		(start 116.59997 -10.168382)
		(mid 116.547447 -10.295183)
		(end 116.420646 -10.347706)
		(width 0.1016)
		(layer "In5.Cu")
		(net "PHY_SCC_TO_DPB_33_DP")
	)
	(segment
		(start 117.500146 -53.50002)
		(end 118.000018 -53.000148)
		(width 0.104902)
		(layer "F.Cu")
		(net "PHY_SCC_TO_DPB_33_DN")
	)
	(via
		(at 118.000018 -53.000148)
		(size 0.4572)
		(drill 0.2032)
		(layers "F.Cu" "B.Cu")
		(net "PHY_SCC_TO_DPB_33_DN")
	)
	(segment
		(start 118.719346 -49.908206)
		(end 118.652036 -50.223928)
		(width 0.1016)
		(layer "In5.Cu")
		(net "PHY_SCC_TO_DPB_33_DN")
	)
	(segment
		(start 119.743474 -39.54907)
		(end 119.969534 -39.695882)
		(width 0.1016)
		(layer "In5.Cu")
		(net "PHY_SCC_TO_DPB_33_DN")
	)
	(segment
		(start 121.63171 -45.423582)
		(end 118.719346 -49.908206)
		(width 0.1016)
		(layer "In5.Cu")
		(net "PHY_SCC_TO_DPB_33_DN")
	)
	(segment
		(start 116.59997 -11.20013)
		(end 116.59997 -10.83183)
		(width 0.1016)
		(layer "In5.Cu")
		(net "PHY_SCC_TO_DPB_33_DN")
	)
	(segment
		(start 119.886222 -40.219884)
		(end 119.949468 -40.51808)
		(width 0.1016)
		(layer "In5.Cu")
		(net "PHY_SCC_TO_DPB_33_DN")
	)
	(segment
		(start 121.358406 -42.68724)
		(end 121.651268 -43.105578)
		(width 0.1016)
		(layer "In5.Cu")
		(net "PHY_SCC_TO_DPB_33_DN")
	)
	(segment
		(start 121.741184 -43.61434)
		(end 121.741184 -44.80179)
		(width 0.1016)
		(layer "In5.Cu")
		(net "PHY_SCC_TO_DPB_33_DN")
	)
	(segment
		(start 118.594886 -50.60315)
		(end 118.594886 -52.289456)
		(width 0.0889)
		(layer "In5.Cu")
		(net "PHY_SCC_TO_DPB_33_DN")
	)
	(segment
		(start 120.03278 -39.994078)
		(end 119.886222 -40.219884)
		(width 0.1016)
		(layer "In5.Cu")
		(net "PHY_SCC_TO_DPB_33_DN")
	)
	(segment
		(start 118.000018 -52.684172)
		(end 118.000018 -53.000148)
		(width 0.0889)
		(layer "In5.Cu")
		(net "PHY_SCC_TO_DPB_33_DN")
	)
	(segment
		(start 118.652036 -50.223928)
		(end 118.652036 -50.523902)
		(width 0.1016)
		(layer "In5.Cu")
		(net "PHY_SCC_TO_DPB_33_DN")
	)
	(segment
		(start 115.852448 -10.8712)
		(end 115.852448 -21.242274)
		(width 0.1016)
		(layer "In5.Cu")
		(net "PHY_SCC_TO_DPB_33_DN")
	)
	(segment
		(start 119.949468 -40.51808)
		(end 121.358406 -42.68724)
		(width 0.1016)
		(layer "In5.Cu")
		(net "PHY_SCC_TO_DPB_33_DN")
	)
	(segment
		(start 118.652036 -50.523902)
		(end 118.652036 -50.546)
		(width 0.0889)
		(layer "In5.Cu")
		(net "PHY_SCC_TO_DPB_33_DN")
	)
	(segment
		(start 121.651268 -43.105578)
		(end 121.741184 -43.61434)
		(width 0.1016)
		(layer "In5.Cu")
		(net "PHY_SCC_TO_DPB_33_DN")
	)
	(segment
		(start 116.420646 -10.652506)
		(end 116.071142 -10.652506)
		(width 0.1016)
		(layer "In5.Cu")
		(net "PHY_SCC_TO_DPB_33_DN")
	)
	(segment
		(start 118.28907 -52.595272)
		(end 118.088918 -52.595272)
		(width 0.0889)
		(layer "In5.Cu")
		(net "PHY_SCC_TO_DPB_33_DN")
	)
	(segment
		(start 118.652036 -50.546)
		(end 118.594886 -50.60315)
		(width 0.0889)
		(layer "In5.Cu")
		(net "PHY_SCC_TO_DPB_33_DN")
	)
	(segment
		(start 119.969534 -39.695882)
		(end 120.03278 -39.994078)
		(width 0.1016)
		(layer "In5.Cu")
		(net "PHY_SCC_TO_DPB_33_DN")
	)
	(segment
		(start 115.852448 -21.242274)
		(end 119.743474 -39.54907)
		(width 0.1016)
		(layer "In5.Cu")
		(net "PHY_SCC_TO_DPB_33_DN")
	)
	(segment
		(start 121.741184 -44.80179)
		(end 121.63171 -45.423582)
		(width 0.1016)
		(layer "In5.Cu")
		(net "PHY_SCC_TO_DPB_33_DN")
	)
	(arc
		(start 116.59997 -10.83183)
		(mid 116.547447 -10.705029)
		(end 116.420646 -10.652506)
		(width 0.1016)
		(layer "In5.Cu")
		(net "PHY_SCC_TO_DPB_33_DN")
	)
	(arc
		(start 116.071142 -10.652506)
		(mid 115.916502 -10.71656)
		(end 115.852448 -10.8712)
		(width 0.1016)
		(layer "In5.Cu")
		(net "PHY_SCC_TO_DPB_33_DN")
	)
	(arc
		(start 118.088918 -52.595272)
		(mid 118.026056 -52.62131)
		(end 118.000018 -52.684172)
		(width 0.0889)
		(layer "In5.Cu")
		(net "PHY_SCC_TO_DPB_33_DN")
	)
	(arc
		(start 118.594886 -52.289456)
		(mid 118.57169 -52.40654)
		(end 118.505478 -52.505864)
		(width 0.0889)
		(layer "In5.Cu")
		(net "PHY_SCC_TO_DPB_33_DN")
	)
	(arc
		(start 118.505478 -52.505864)
		(mid 118.406174 -52.572124)
		(end 118.28907 -52.595272)
		(width 0.0889)
		(layer "In5.Cu")
		(net "PHY_SCC_TO_DPB_33_DN")
	)
	(segment
		(start 116.500148 -51.500024)
		(end 117.00002 -51.000152)
		(width 0.104902)
		(layer "F.Cu")
		(net "PHY_SCC_TO_DPB_32_DP")
	)
	(via
		(at 117.00002 -51.000152)
		(size 0.4572)
		(drill 0.2032)
		(layers "F.Cu" "B.Cu")
		(net "PHY_SCC_TO_DPB_32_DP")
	)
	(segment
		(start 120.366028 -44.939458)
		(end 120.365774 -44.939458)
		(width 0.1016)
		(layer "In5.Cu")
		(net "PHY_SCC_TO_DPB_32_DP")
	)
	(segment
		(start 117.00002 -51.000152)
		(end 117.00002 -51.315874)
		(width 0.0889)
		(layer "In5.Cu")
		(net "PHY_SCC_TO_DPB_32_DP")
	)
	(segment
		(start 113.747804 -18.466308)
		(end 113.747804 -12.071096)
		(width 0.1016)
		(layer "In5.Cu")
		(net "PHY_SCC_TO_DPB_32_DP")
	)
	(segment
		(start 117.408706 -51.272186)
		(end 117.408706 -50.620676)
		(width 0.0889)
		(layer "In5.Cu")
		(net "PHY_SCC_TO_DPB_32_DP")
	)
	(segment
		(start 119.953278 -45.5295)
		(end 120.366028 -44.939458)
		(width 0.1016)
		(layer "In5.Cu")
		(net "PHY_SCC_TO_DPB_32_DP")
	)
	(segment
		(start 118.475252 -40.69715)
		(end 113.747804 -18.466308)
		(width 0.1016)
		(layer "In5.Cu")
		(net "PHY_SCC_TO_DPB_32_DP")
	)
	(segment
		(start 117.351556 -50.541428)
		(end 117.351556 -49.996598)
		(width 0.1016)
		(layer "In5.Cu")
		(net "PHY_SCC_TO_DPB_32_DP")
	)
	(segment
		(start 119.652796 -45.762672)
		(end 119.688864 -45.714666)
		(width 0.1016)
		(layer "In5.Cu")
		(net "PHY_SCC_TO_DPB_32_DP")
	)
	(segment
		(start 117.08892 -51.404774)
		(end 117.276118 -51.404774)
		(width 0.0889)
		(layer "In5.Cu")
		(net "PHY_SCC_TO_DPB_32_DP")
	)
	(segment
		(start 119.688864 -45.714666)
		(end 119.953278 -45.5295)
		(width 0.1016)
		(layer "In5.Cu")
		(net "PHY_SCC_TO_DPB_32_DP")
	)
	(segment
		(start 117.568472 -48.971454)
		(end 119.652796 -45.762672)
		(width 0.1016)
		(layer "In5.Cu")
		(net "PHY_SCC_TO_DPB_32_DP")
	)
	(segment
		(start 114.271298 -11.547602)
		(end 114.620802 -11.547602)
		(width 0.1016)
		(layer "In5.Cu")
		(net "PHY_SCC_TO_DPB_32_DP")
	)
	(segment
		(start 114.800126 -11.368278)
		(end 114.800126 -10.999978)
		(width 0.1016)
		(layer "In5.Cu")
		(net "PHY_SCC_TO_DPB_32_DP")
	)
	(segment
		(start 120.394984 -44.774866)
		(end 120.394984 -43.641264)
		(width 0.1016)
		(layer "In5.Cu")
		(net "PHY_SCC_TO_DPB_32_DP")
	)
	(segment
		(start 117.408706 -50.620676)
		(end 117.351556 -50.563526)
		(width 0.0889)
		(layer "In5.Cu")
		(net "PHY_SCC_TO_DPB_32_DP")
	)
	(segment
		(start 117.351556 -50.563526)
		(end 117.351556 -50.541428)
		(width 0.0889)
		(layer "In5.Cu")
		(net "PHY_SCC_TO_DPB_32_DP")
	)
	(segment
		(start 120.380252 -44.857416)
		(end 120.394984 -44.774866)
		(width 0.1016)
		(layer "In5.Cu")
		(net "PHY_SCC_TO_DPB_32_DP")
	)
	(segment
		(start 120.394984 -43.641264)
		(end 120.281192 -43.479212)
		(width 0.1016)
		(layer "In5.Cu")
		(net "PHY_SCC_TO_DPB_32_DP")
	)
	(segment
		(start 120.281192 -43.479212)
		(end 118.475252 -40.69715)
		(width 0.1016)
		(layer "In5.Cu")
		(net "PHY_SCC_TO_DPB_32_DP")
	)
	(segment
		(start 120.365774 -44.939458)
		(end 120.380252 -44.857416)
		(width 0.1016)
		(layer "In5.Cu")
		(net "PHY_SCC_TO_DPB_32_DP")
	)
	(segment
		(start 117.351556 -49.996598)
		(end 117.568472 -48.971454)
		(width 0.1016)
		(layer "In5.Cu")
		(net "PHY_SCC_TO_DPB_32_DP")
	)
	(arc
		(start 117.276118 -51.404774)
		(mid 117.326843 -51.394666)
		(end 117.369844 -51.365912)
		(width 0.0889)
		(layer "In5.Cu")
		(net "PHY_SCC_TO_DPB_32_DP")
	)
	(arc
		(start 117.369844 -51.365912)
		(mid 117.398631 -51.322924)
		(end 117.408706 -51.272186)
		(width 0.0889)
		(layer "In5.Cu")
		(net "PHY_SCC_TO_DPB_32_DP")
	)
	(arc
		(start 117.00002 -51.315874)
		(mid 117.026058 -51.378736)
		(end 117.08892 -51.404774)
		(width 0.0889)
		(layer "In5.Cu")
		(net "PHY_SCC_TO_DPB_32_DP")
	)
	(arc
		(start 114.620802 -11.547602)
		(mid 114.747603 -11.495079)
		(end 114.800126 -11.368278)
		(width 0.1016)
		(layer "In5.Cu")
		(net "PHY_SCC_TO_DPB_32_DP")
	)
	(arc
		(start 113.747804 -12.071096)
		(mid 113.901132 -11.70093)
		(end 114.271298 -11.547602)
		(width 0.1016)
		(layer "In5.Cu")
		(net "PHY_SCC_TO_DPB_32_DP")
	)
	(segment
		(start 116.500148 -52.500022)
		(end 117.00002 -52.00015)
		(width 0.104902)
		(layer "F.Cu")
		(net "PHY_SCC_TO_DPB_32_DN")
	)
	(via
		(at 117.00002 -52.00015)
		(size 0.4572)
		(drill 0.2032)
		(layers "F.Cu" "B.Cu")
		(net "PHY_SCC_TO_DPB_32_DN")
	)
	(segment
		(start 117.656356 -50.541428)
		(end 117.656356 -50.028602)
		(width 0.1016)
		(layer "In5.Cu")
		(net "PHY_SCC_TO_DPB_32_DN")
	)
	(segment
		(start 118.914418 -47.459138)
		(end 119.177816 -47.403004)
		(width 0.1016)
		(layer "In5.Cu")
		(net "PHY_SCC_TO_DPB_32_DN")
	)
	(segment
		(start 117.599206 -50.620676)
		(end 117.656356 -50.563526)
		(width 0.0889)
		(layer "In5.Cu")
		(net "PHY_SCC_TO_DPB_32_DN")
	)
	(segment
		(start 117.00002 -52.00015)
		(end 117.00002 -51.684174)
		(width 0.0889)
		(layer "In5.Cu")
		(net "PHY_SCC_TO_DPB_32_DN")
	)
	(segment
		(start 117.656356 -50.028602)
		(end 117.854984 -49.090072)
		(width 0.1016)
		(layer "In5.Cu")
		(net "PHY_SCC_TO_DPB_32_DN")
	)
	(segment
		(start 114.800126 -12.031726)
		(end 114.800126 -12.400026)
		(width 0.1016)
		(layer "In5.Cu")
		(net "PHY_SCC_TO_DPB_32_DN")
	)
	(segment
		(start 118.761764 -40.578532)
		(end 114.052604 -18.43405)
		(width 0.1016)
		(layer "In5.Cu")
		(net "PHY_SCC_TO_DPB_32_DN")
	)
	(segment
		(start 114.271298 -11.852402)
		(end 114.620802 -11.852402)
		(width 0.1016)
		(layer "In5.Cu")
		(net "PHY_SCC_TO_DPB_32_DN")
	)
	(segment
		(start 117.656356 -50.563526)
		(end 117.656356 -50.541428)
		(width 0.0889)
		(layer "In5.Cu")
		(net "PHY_SCC_TO_DPB_32_DN")
	)
	(segment
		(start 120.699784 -43.544998)
		(end 120.534176 -43.308524)
		(width 0.1016)
		(layer "In5.Cu")
		(net "PHY_SCC_TO_DPB_32_DN")
	)
	(segment
		(start 119.903494 -45.936662)
		(end 120.17248 -45.748448)
		(width 0.1016)
		(layer "In5.Cu")
		(net "PHY_SCC_TO_DPB_32_DN")
	)
	(segment
		(start 117.08892 -51.595274)
		(end 117.276118 -51.595274)
		(width 0.0889)
		(layer "In5.Cu")
		(net "PHY_SCC_TO_DPB_32_DN")
	)
	(segment
		(start 114.052604 -18.43405)
		(end 114.052604 -12.071096)
		(width 0.1016)
		(layer "In5.Cu")
		(net "PHY_SCC_TO_DPB_32_DN")
	)
	(segment
		(start 120.534176 -43.308524)
		(end 118.761764 -40.578532)
		(width 0.1016)
		(layer "In5.Cu")
		(net "PHY_SCC_TO_DPB_32_DN")
	)
	(segment
		(start 119.343932 -47.14748)
		(end 119.287798 -46.88459)
		(width 0.1016)
		(layer "In5.Cu")
		(net "PHY_SCC_TO_DPB_32_DN")
	)
	(segment
		(start 120.699784 -44.80179)
		(end 120.699784 -43.544998)
		(width 0.1016)
		(layer "In5.Cu")
		(net "PHY_SCC_TO_DPB_32_DN")
	)
	(segment
		(start 119.902986 -45.937678)
		(end 119.903494 -45.936662)
		(width 0.1016)
		(layer "In5.Cu")
		(net "PHY_SCC_TO_DPB_32_DN")
	)
	(segment
		(start 120.17248 -45.748448)
		(end 120.654572 -45.058838)
		(width 0.1016)
		(layer "In5.Cu")
		(net "PHY_SCC_TO_DPB_32_DN")
	)
	(segment
		(start 117.599206 -51.272186)
		(end 117.599206 -50.620676)
		(width 0.0889)
		(layer "In5.Cu")
		(net "PHY_SCC_TO_DPB_32_DN")
	)
	(segment
		(start 119.287798 -46.88459)
		(end 119.902986 -45.937678)
		(width 0.1016)
		(layer "In5.Cu")
		(net "PHY_SCC_TO_DPB_32_DN")
	)
	(segment
		(start 119.177816 -47.403004)
		(end 119.343932 -47.14748)
		(width 0.1016)
		(layer "In5.Cu")
		(net "PHY_SCC_TO_DPB_32_DN")
	)
	(segment
		(start 117.854984 -49.090072)
		(end 118.914418 -47.459138)
		(width 0.1016)
		(layer "In5.Cu")
		(net "PHY_SCC_TO_DPB_32_DN")
	)
	(segment
		(start 120.654572 -45.058838)
		(end 120.699784 -44.80179)
		(width 0.1016)
		(layer "In5.Cu")
		(net "PHY_SCC_TO_DPB_32_DN")
	)
	(arc
		(start 117.00002 -51.684174)
		(mid 117.026058 -51.621312)
		(end 117.08892 -51.595274)
		(width 0.0889)
		(layer "In5.Cu")
		(net "PHY_SCC_TO_DPB_32_DN")
	)
	(arc
		(start 117.276118 -51.595274)
		(mid 117.399812 -51.570763)
		(end 117.504718 -51.500786)
		(width 0.0889)
		(layer "In5.Cu")
		(net "PHY_SCC_TO_DPB_32_DN")
	)
	(arc
		(start 114.052604 -12.071096)
		(mid 114.116658 -11.916456)
		(end 114.271298 -11.852402)
		(width 0.1016)
		(layer "In5.Cu")
		(net "PHY_SCC_TO_DPB_32_DN")
	)
	(arc
		(start 117.504718 -51.500786)
		(mid 117.574715 -51.395888)
		(end 117.599206 -51.272186)
		(width 0.0889)
		(layer "In5.Cu")
		(net "PHY_SCC_TO_DPB_32_DN")
	)
	(arc
		(start 114.620802 -11.852402)
		(mid 114.747603 -11.904925)
		(end 114.800126 -12.031726)
		(width 0.1016)
		(layer "In5.Cu")
		(net "PHY_SCC_TO_DPB_32_DN")
	)
	(segment
		(start 130.50012 -64.499998)
		(end 130.999992 -64.000126)
		(width 0.104902)
		(layer "F.Cu")
		(net "PHY_SCC_TO_DPB_31_DP")
	)
	(via
		(at 130.999992 -64.000126)
		(size 0.4572)
		(drill 0.2032)
		(layers "F.Cu" "B.Cu")
		(net "PHY_SCC_TO_DPB_31_DP")
	)
	(segment
		(start 133.547612 -10.871454)
		(end 133.547612 -17.089374)
		(width 0.1016)
		(layer "In5.Cu")
		(net "PHY_SCC_TO_DPB_31_DP")
	)
	(segment
		(start 134.16153 -29.113734)
		(end 137.584688 -45.224192)
		(width 0.1016)
		(layer "In5.Cu")
		(net "PHY_SCC_TO_DPB_31_DP")
	)
	(segment
		(start 130.595116 -64.223392)
		(end 130.595116 -64.089026)
		(width 0.0889)
		(layer "In5.Cu")
		(net "PHY_SCC_TO_DPB_31_DP")
	)
	(segment
		(start 134.340092 -20.81657)
		(end 135.132826 -24.544528)
		(width 0.1016)
		(layer "In5.Cu")
		(net "PHY_SCC_TO_DPB_31_DP")
	)
	(segment
		(start 130.684016 -64.000126)
		(end 130.999992 -64.000126)
		(width 0.0889)
		(layer "In5.Cu")
		(net "PHY_SCC_TO_DPB_31_DP")
	)
	(segment
		(start 132.136388 -63.900812)
		(end 131.69011 -64.34709)
		(width 0.1016)
		(layer "In5.Cu")
		(net "PHY_SCC_TO_DPB_31_DP")
	)
	(segment
		(start 131.566412 -64.34709)
		(end 131.509262 -64.40424)
		(width 0.0889)
		(layer "In5.Cu")
		(net "PHY_SCC_TO_DPB_31_DP")
	)
	(segment
		(start 131.69011 -64.34709)
		(end 131.58851 -64.34709)
		(width 0.1016)
		(layer "In5.Cu")
		(net "PHY_SCC_TO_DPB_31_DP")
	)
	(segment
		(start 134.61619 -51.89474)
		(end 134.450328 -52.150518)
		(width 0.1016)
		(layer "In5.Cu")
		(net "PHY_SCC_TO_DPB_31_DP")
	)
	(segment
		(start 134.420864 -10.347706)
		(end 134.07136 -10.347706)
		(width 0.1016)
		(layer "In5.Cu")
		(net "PHY_SCC_TO_DPB_31_DP")
	)
	(segment
		(start 135.132826 -24.544528)
		(end 134.16153 -29.113734)
		(width 0.1016)
		(layer "In5.Cu")
		(net "PHY_SCC_TO_DPB_31_DP")
	)
	(segment
		(start 134.600188 -9.800082)
		(end 134.600188 -10.168382)
		(width 0.1016)
		(layer "In5.Cu")
		(net "PHY_SCC_TO_DPB_31_DP")
	)
	(segment
		(start 135.155432 -51.06416)
		(end 134.98957 -51.319684)
		(width 0.1016)
		(layer "In5.Cu")
		(net "PHY_SCC_TO_DPB_31_DP")
	)
	(segment
		(start 131.58851 -64.34709)
		(end 131.566412 -64.34709)
		(width 0.0889)
		(layer "In5.Cu")
		(net "PHY_SCC_TO_DPB_31_DP")
	)
	(segment
		(start 134.98957 -51.319684)
		(end 135.04545 -51.583336)
		(width 0.1016)
		(layer "In5.Cu")
		(net "PHY_SCC_TO_DPB_31_DP")
	)
	(segment
		(start 134.879842 -51.83886)
		(end 134.61619 -51.89474)
		(width 0.1016)
		(layer "In5.Cu")
		(net "PHY_SCC_TO_DPB_31_DP")
	)
	(segment
		(start 133.297168 -54.276498)
		(end 133.054852 -55.415942)
		(width 0.1016)
		(layer "In5.Cu")
		(net "PHY_SCC_TO_DPB_31_DP")
	)
	(segment
		(start 137.584688 -45.224192)
		(end 136.811004 -48.864266)
		(width 0.1016)
		(layer "In5.Cu")
		(net "PHY_SCC_TO_DPB_31_DP")
	)
	(segment
		(start 134.450328 -52.150518)
		(end 134.506208 -52.413916)
		(width 0.1016)
		(layer "In5.Cu")
		(net "PHY_SCC_TO_DPB_31_DP")
	)
	(segment
		(start 131.509262 -64.40424)
		(end 130.77571 -64.40424)
		(width 0.0889)
		(layer "In5.Cu")
		(net "PHY_SCC_TO_DPB_31_DP")
	)
	(segment
		(start 130.648202 -64.351662)
		(end 130.647948 -64.351408)
		(width 0.0889)
		(layer "In5.Cu")
		(net "PHY_SCC_TO_DPB_31_DP")
	)
	(segment
		(start 134.879588 -51.83886)
		(end 134.879842 -51.83886)
		(width 0.1016)
		(layer "In5.Cu")
		(net "PHY_SCC_TO_DPB_31_DP")
	)
	(segment
		(start 133.547612 -17.089374)
		(end 134.339838 -20.81657)
		(width 0.1016)
		(layer "In5.Cu")
		(net "PHY_SCC_TO_DPB_31_DP")
	)
	(segment
		(start 133.054852 -55.415942)
		(end 133.054852 -62.766194)
		(width 0.1016)
		(layer "In5.Cu")
		(net "PHY_SCC_TO_DPB_31_DP")
	)
	(segment
		(start 136.811004 -48.864266)
		(end 135.419084 -51.008026)
		(width 0.1016)
		(layer "In5.Cu")
		(net "PHY_SCC_TO_DPB_31_DP")
	)
	(segment
		(start 132.136388 -63.684658)
		(end 132.136388 -63.900812)
		(width 0.1016)
		(layer "In5.Cu")
		(net "PHY_SCC_TO_DPB_31_DP")
	)
	(segment
		(start 135.04545 -51.583336)
		(end 134.879588 -51.83886)
		(width 0.1016)
		(layer "In5.Cu")
		(net "PHY_SCC_TO_DPB_31_DP")
	)
	(segment
		(start 133.054852 -62.766194)
		(end 132.136388 -63.684658)
		(width 0.1016)
		(layer "In5.Cu")
		(net "PHY_SCC_TO_DPB_31_DP")
	)
	(segment
		(start 134.339838 -20.81657)
		(end 134.340092 -20.81657)
		(width 0.1016)
		(layer "In5.Cu")
		(net "PHY_SCC_TO_DPB_31_DP")
	)
	(segment
		(start 135.419084 -51.008026)
		(end 135.155432 -51.06416)
		(width 0.1016)
		(layer "In5.Cu")
		(net "PHY_SCC_TO_DPB_31_DP")
	)
	(segment
		(start 134.506208 -52.413916)
		(end 133.297168 -54.276498)
		(width 0.1016)
		(layer "In5.Cu")
		(net "PHY_SCC_TO_DPB_31_DP")
	)
	(arc
		(start 134.07136 -10.347706)
		(mid 133.701014 -10.501108)
		(end 133.547612 -10.871454)
		(width 0.1016)
		(layer "In5.Cu")
		(net "PHY_SCC_TO_DPB_31_DP")
	)
	(arc
		(start 130.647948 -64.351408)
		(mid 130.608786 -64.292659)
		(end 130.595116 -64.223392)
		(width 0.0889)
		(layer "In5.Cu")
		(net "PHY_SCC_TO_DPB_31_DP")
	)
	(arc
		(start 134.600188 -10.168382)
		(mid 134.547665 -10.295183)
		(end 134.420864 -10.347706)
		(width 0.1016)
		(layer "In5.Cu")
		(net "PHY_SCC_TO_DPB_31_DP")
	)
	(arc
		(start 130.77571 -64.40424)
		(mid 130.706751 -64.390577)
		(end 130.648202 -64.351662)
		(width 0.0889)
		(layer "In5.Cu")
		(net "PHY_SCC_TO_DPB_31_DP")
	)
	(arc
		(start 130.595116 -64.089026)
		(mid 130.621154 -64.026164)
		(end 130.684016 -64.000126)
		(width 0.0889)
		(layer "In5.Cu")
		(net "PHY_SCC_TO_DPB_31_DP")
	)
	(segment
		(start 129.500122 -64.499998)
		(end 129.999994 -64.000126)
		(width 0.104902)
		(layer "F.Cu")
		(net "PHY_SCC_TO_DPB_31_DN")
	)
	(via
		(at 129.999994 -64.000126)
		(size 0.4572)
		(drill 0.2032)
		(layers "F.Cu" "B.Cu")
		(net "PHY_SCC_TO_DPB_31_DN")
	)
	(segment
		(start 134.431278 -53.089302)
		(end 137.097262 -48.9839)
		(width 0.1016)
		(layer "In5.Cu")
		(net "PHY_SCC_TO_DPB_31_DN")
	)
	(segment
		(start 133.359652 -55.4482)
		(end 133.58368 -54.395116)
		(width 0.1016)
		(layer "In5.Cu")
		(net "PHY_SCC_TO_DPB_31_DN")
	)
	(segment
		(start 137.097262 -48.9839)
		(end 137.896346 -45.224192)
		(width 0.1016)
		(layer "In5.Cu")
		(net "PHY_SCC_TO_DPB_31_DN")
	)
	(segment
		(start 133.359652 -62.892686)
		(end 133.359652 -55.4482)
		(width 0.1016)
		(layer "In5.Cu")
		(net "PHY_SCC_TO_DPB_31_DN")
	)
	(segment
		(start 130.513074 -64.486028)
		(end 130.513582 -64.486536)
		(width 0.0889)
		(layer "In5.Cu")
		(net "PHY_SCC_TO_DPB_31_DN")
	)
	(segment
		(start 134.600188 -10.83183)
		(end 134.600188 -11.20013)
		(width 0.1016)
		(layer "In5.Cu")
		(net "PHY_SCC_TO_DPB_31_DN")
	)
	(segment
		(start 131.566412 -64.65189)
		(end 131.58851 -64.65189)
		(width 0.0889)
		(layer "In5.Cu")
		(net "PHY_SCC_TO_DPB_31_DN")
	)
	(segment
		(start 133.852412 -17.057116)
		(end 133.852412 -10.871454)
		(width 0.1016)
		(layer "In5.Cu")
		(net "PHY_SCC_TO_DPB_31_DN")
	)
	(segment
		(start 131.816602 -64.65189)
		(end 132.441188 -64.027304)
		(width 0.1016)
		(layer "In5.Cu")
		(net "PHY_SCC_TO_DPB_31_DN")
	)
	(segment
		(start 135.444484 -24.544528)
		(end 133.852412 -17.057116)
		(width 0.1016)
		(layer "In5.Cu")
		(net "PHY_SCC_TO_DPB_31_DN")
	)
	(segment
		(start 134.07136 -10.652506)
		(end 134.420864 -10.652506)
		(width 0.1016)
		(layer "In5.Cu")
		(net "PHY_SCC_TO_DPB_31_DN")
	)
	(segment
		(start 132.441188 -64.027304)
		(end 132.441188 -63.81115)
		(width 0.1016)
		(layer "In5.Cu")
		(net "PHY_SCC_TO_DPB_31_DN")
	)
	(segment
		(start 131.509262 -64.59474)
		(end 131.566412 -64.65189)
		(width 0.0889)
		(layer "In5.Cu")
		(net "PHY_SCC_TO_DPB_31_DN")
	)
	(segment
		(start 130.404616 -64.089026)
		(end 130.404616 -64.223138)
		(width 0.0889)
		(layer "In5.Cu")
		(net "PHY_SCC_TO_DPB_31_DN")
	)
	(segment
		(start 133.58368 -54.395116)
		(end 134.431278 -53.089302)
		(width 0.1016)
		(layer "In5.Cu")
		(net "PHY_SCC_TO_DPB_31_DN")
	)
	(segment
		(start 137.896346 -45.224192)
		(end 134.473188 -29.113734)
		(width 0.1016)
		(layer "In5.Cu")
		(net "PHY_SCC_TO_DPB_31_DN")
	)
	(segment
		(start 130.77571 -64.59474)
		(end 131.509262 -64.59474)
		(width 0.0889)
		(layer "In5.Cu")
		(net "PHY_SCC_TO_DPB_31_DN")
	)
	(segment
		(start 134.473188 -29.113734)
		(end 135.444484 -24.544528)
		(width 0.1016)
		(layer "In5.Cu")
		(net "PHY_SCC_TO_DPB_31_DN")
	)
	(segment
		(start 131.58851 -64.65189)
		(end 131.816602 -64.65189)
		(width 0.1016)
		(layer "In5.Cu")
		(net "PHY_SCC_TO_DPB_31_DN")
	)
	(segment
		(start 132.441188 -63.81115)
		(end 133.359652 -62.892686)
		(width 0.1016)
		(layer "In5.Cu")
		(net "PHY_SCC_TO_DPB_31_DN")
	)
	(segment
		(start 129.999994 -64.000126)
		(end 130.315716 -64.000126)
		(width 0.0889)
		(layer "In5.Cu")
		(net "PHY_SCC_TO_DPB_31_DN")
	)
	(arc
		(start 133.852412 -10.871454)
		(mid 133.91654 -10.716634)
		(end 134.07136 -10.652506)
		(width 0.1016)
		(layer "In5.Cu")
		(net "PHY_SCC_TO_DPB_31_DN")
	)
	(arc
		(start 130.315716 -64.000126)
		(mid 130.378578 -64.026164)
		(end 130.404616 -64.089026)
		(width 0.0889)
		(layer "In5.Cu")
		(net "PHY_SCC_TO_DPB_31_DN")
	)
	(arc
		(start 130.513582 -64.486536)
		(mid 130.633918 -64.566627)
		(end 130.77571 -64.59474)
		(width 0.0889)
		(layer "In5.Cu")
		(net "PHY_SCC_TO_DPB_31_DN")
	)
	(arc
		(start 134.420864 -10.652506)
		(mid 134.547665 -10.705029)
		(end 134.600188 -10.83183)
		(width 0.1016)
		(layer "In5.Cu")
		(net "PHY_SCC_TO_DPB_31_DN")
	)
	(arc
		(start 130.404616 -64.223138)
		(mid 130.432717 -64.365354)
		(end 130.513074 -64.486028)
		(width 0.0889)
		(layer "In5.Cu")
		(net "PHY_SCC_TO_DPB_31_DN")
	)
	(segment
		(start 129.500122 -63.5)
		(end 129.999994 -63.000128)
		(width 0.104902)
		(layer "F.Cu")
		(net "PHY_SCC_TO_DPB_30_DP")
	)
	(via
		(at 129.999994 -63.000128)
		(size 0.4572)
		(drill 0.2032)
		(layers "F.Cu" "B.Cu")
		(net "PHY_SCC_TO_DPB_30_DP")
	)
	(segment
		(start 133.779006 -51.674522)
		(end 133.77926 -51.674522)
		(width 0.1016)
		(layer "In5.Cu")
		(net "PHY_SCC_TO_DPB_30_DP")
	)
	(segment
		(start 131.326636 -63.34633)
		(end 131.348734 -63.34633)
		(width 0.0889)
		(layer "In5.Cu")
		(net "PHY_SCC_TO_DPB_30_DP")
	)
	(segment
		(start 132.271262 -11.547602)
		(end 132.620766 -11.547602)
		(width 0.1016)
		(layer "In5.Cu")
		(net "PHY_SCC_TO_DPB_30_DP")
	)
	(segment
		(start 135.920988 -48.376332)
		(end 136.628632 -45.047408)
		(width 0.1016)
		(layer "In5.Cu")
		(net "PHY_SCC_TO_DPB_30_DP")
	)
	(segment
		(start 133.23951 -52.505356)
		(end 133.18363 -52.241958)
		(width 0.1016)
		(layer "In5.Cu")
		(net "PHY_SCC_TO_DPB_30_DP")
	)
	(segment
		(start 132.4102 -55.27421)
		(end 132.881624 -53.05679)
		(width 0.1016)
		(layer "In5.Cu")
		(net "PHY_SCC_TO_DPB_30_DP")
	)
	(segment
		(start 133.349492 -51.98618)
		(end 133.613144 -51.930046)
		(width 0.1016)
		(layer "In5.Cu")
		(net "PHY_SCC_TO_DPB_30_DP")
	)
	(segment
		(start 132.80009 -11.368278)
		(end 132.80009 -10.999978)
		(width 0.1016)
		(layer "In5.Cu")
		(net "PHY_SCC_TO_DPB_30_DP")
	)
	(segment
		(start 132.4102 -62.47765)
		(end 132.4102 -55.27421)
		(width 0.1016)
		(layer "In5.Cu")
		(net "PHY_SCC_TO_DPB_30_DP")
	)
	(segment
		(start 133.613144 -51.930046)
		(end 133.779006 -51.674522)
		(width 0.1016)
		(layer "In5.Cu")
		(net "PHY_SCC_TO_DPB_30_DP")
	)
	(segment
		(start 129.595118 -63.089028)
		(end 129.595118 -63.223902)
		(width 0.0889)
		(layer "In5.Cu")
		(net "PHY_SCC_TO_DPB_30_DP")
	)
	(segment
		(start 131.348734 -63.34633)
		(end 131.54152 -63.34633)
		(width 0.1016)
		(layer "In5.Cu")
		(net "PHY_SCC_TO_DPB_30_DP")
	)
	(segment
		(start 134.15264 -51.099466)
		(end 135.920988 -48.376332)
		(width 0.1016)
		(layer "In5.Cu")
		(net "PHY_SCC_TO_DPB_30_DP")
	)
	(segment
		(start 131.747768 -17.369028)
		(end 131.747768 -12.071096)
		(width 0.1016)
		(layer "In5.Cu")
		(net "PHY_SCC_TO_DPB_30_DP")
	)
	(segment
		(start 131.269486 -63.40348)
		(end 131.326636 -63.34633)
		(width 0.0889)
		(layer "In5.Cu")
		(net "PHY_SCC_TO_DPB_30_DP")
	)
	(segment
		(start 136.628632 -45.047408)
		(end 132.913374 -27.567382)
		(width 0.1016)
		(layer "In5.Cu")
		(net "PHY_SCC_TO_DPB_30_DP")
	)
	(segment
		(start 133.77926 -51.674522)
		(end 133.723126 -51.411124)
		(width 0.1016)
		(layer "In5.Cu")
		(net "PHY_SCC_TO_DPB_30_DP")
	)
	(segment
		(start 129.999994 -63.000128)
		(end 129.684018 -63.000128)
		(width 0.0889)
		(layer "In5.Cu")
		(net "PHY_SCC_TO_DPB_30_DP")
	)
	(segment
		(start 129.774696 -63.40348)
		(end 131.269486 -63.40348)
		(width 0.0889)
		(layer "In5.Cu")
		(net "PHY_SCC_TO_DPB_30_DP")
	)
	(segment
		(start 133.889242 -51.1556)
		(end 134.15264 -51.099466)
		(width 0.1016)
		(layer "In5.Cu")
		(net "PHY_SCC_TO_DPB_30_DP")
	)
	(segment
		(start 132.913374 -27.567382)
		(end 133.414516 -25.210008)
		(width 0.1016)
		(layer "In5.Cu")
		(net "PHY_SCC_TO_DPB_30_DP")
	)
	(segment
		(start 132.881624 -53.05679)
		(end 133.23951 -52.505356)
		(width 0.1016)
		(layer "In5.Cu")
		(net "PHY_SCC_TO_DPB_30_DP")
	)
	(segment
		(start 133.18363 -52.241958)
		(end 133.349492 -51.98618)
		(width 0.1016)
		(layer "In5.Cu")
		(net "PHY_SCC_TO_DPB_30_DP")
	)
	(segment
		(start 133.723126 -51.411124)
		(end 133.889242 -51.1556)
		(width 0.1016)
		(layer "In5.Cu")
		(net "PHY_SCC_TO_DPB_30_DP")
	)
	(segment
		(start 133.414516 -25.210008)
		(end 131.747768 -17.369028)
		(width 0.1016)
		(layer "In5.Cu")
		(net "PHY_SCC_TO_DPB_30_DP")
	)
	(segment
		(start 131.54152 -63.34633)
		(end 132.4102 -62.47765)
		(width 0.1016)
		(layer "In5.Cu")
		(net "PHY_SCC_TO_DPB_30_DP")
	)
	(arc
		(start 129.647696 -63.350902)
		(mid 129.705964 -63.389835)
		(end 129.774696 -63.40348)
		(width 0.0889)
		(layer "In5.Cu")
		(net "PHY_SCC_TO_DPB_30_DP")
	)
	(arc
		(start 129.684018 -63.000128)
		(mid 129.621156 -63.026166)
		(end 129.595118 -63.089028)
		(width 0.0889)
		(layer "In5.Cu")
		(net "PHY_SCC_TO_DPB_30_DP")
	)
	(arc
		(start 132.620766 -11.547602)
		(mid 132.747567 -11.495079)
		(end 132.80009 -11.368278)
		(width 0.1016)
		(layer "In5.Cu")
		(net "PHY_SCC_TO_DPB_30_DP")
	)
	(arc
		(start 129.595118 -63.223902)
		(mid 129.608788 -63.292624)
		(end 129.647696 -63.350902)
		(width 0.0889)
		(layer "In5.Cu")
		(net "PHY_SCC_TO_DPB_30_DP")
	)
	(arc
		(start 131.747768 -12.071096)
		(mid 131.901096 -11.70093)
		(end 132.271262 -11.547602)
		(width 0.1016)
		(layer "In5.Cu")
		(net "PHY_SCC_TO_DPB_30_DP")
	)
	(segment
		(start 128.500124 -63.5)
		(end 128.999996 -63.000128)
		(width 0.104902)
		(layer "F.Cu")
		(net "PHY_SCC_TO_DPB_30_DN")
	)
	(via
		(at 128.999996 -63.000128)
		(size 0.4572)
		(drill 0.2032)
		(layers "F.Cu" "B.Cu")
		(net "PHY_SCC_TO_DPB_30_DN")
	)
	(segment
		(start 131.269486 -63.59398)
		(end 129.774696 -63.59398)
		(width 0.0889)
		(layer "In5.Cu")
		(net "PHY_SCC_TO_DPB_30_DN")
	)
	(segment
		(start 132.052568 -17.33677)
		(end 133.726174 -25.210008)
		(width 0.1016)
		(layer "In5.Cu")
		(net "PHY_SCC_TO_DPB_30_DN")
	)
	(segment
		(start 131.348734 -63.65113)
		(end 131.326636 -63.65113)
		(width 0.0889)
		(layer "In5.Cu")
		(net "PHY_SCC_TO_DPB_30_DN")
	)
	(segment
		(start 131.668012 -63.65113)
		(end 131.348734 -63.65113)
		(width 0.1016)
		(layer "In5.Cu")
		(net "PHY_SCC_TO_DPB_30_DN")
	)
	(segment
		(start 132.715 -62.604142)
		(end 131.668012 -63.65113)
		(width 0.1016)
		(layer "In5.Cu")
		(net "PHY_SCC_TO_DPB_30_DN")
	)
	(segment
		(start 132.620766 -11.852402)
		(end 132.271262 -11.852402)
		(width 0.1016)
		(layer "In5.Cu")
		(net "PHY_SCC_TO_DPB_30_DN")
	)
	(segment
		(start 129.315718 -63.000128)
		(end 128.999996 -63.000128)
		(width 0.0889)
		(layer "In5.Cu")
		(net "PHY_SCC_TO_DPB_30_DN")
	)
	(segment
		(start 132.715 -55.306468)
		(end 132.715 -62.604142)
		(width 0.1016)
		(layer "In5.Cu")
		(net "PHY_SCC_TO_DPB_30_DN")
	)
	(segment
		(start 132.052568 -12.071096)
		(end 132.052568 -17.33677)
		(width 0.1016)
		(layer "In5.Cu")
		(net "PHY_SCC_TO_DPB_30_DN")
	)
	(segment
		(start 133.726174 -25.210008)
		(end 133.225032 -27.567382)
		(width 0.1016)
		(layer "In5.Cu")
		(net "PHY_SCC_TO_DPB_30_DN")
	)
	(segment
		(start 136.2075 -48.49495)
		(end 133.63575 -52.455318)
		(width 0.1016)
		(layer "In5.Cu")
		(net "PHY_SCC_TO_DPB_30_DN")
	)
	(segment
		(start 136.94029 -45.047408)
		(end 136.2075 -48.49495)
		(width 0.1016)
		(layer "In5.Cu")
		(net "PHY_SCC_TO_DPB_30_DN")
	)
	(segment
		(start 132.80009 -12.400026)
		(end 132.80009 -12.031726)
		(width 0.1016)
		(layer "In5.Cu")
		(net "PHY_SCC_TO_DPB_30_DN")
	)
	(segment
		(start 129.404618 -63.223902)
		(end 129.404618 -63.089028)
		(width 0.0889)
		(layer "In5.Cu")
		(net "PHY_SCC_TO_DPB_30_DN")
	)
	(segment
		(start 133.635496 -52.455572)
		(end 133.168136 -53.175408)
		(width 0.1016)
		(layer "In5.Cu")
		(net "PHY_SCC_TO_DPB_30_DN")
	)
	(segment
		(start 133.168136 -53.175408)
		(end 132.715 -55.306468)
		(width 0.1016)
		(layer "In5.Cu")
		(net "PHY_SCC_TO_DPB_30_DN")
	)
	(segment
		(start 133.225032 -27.567382)
		(end 136.94029 -45.047408)
		(width 0.1016)
		(layer "In5.Cu")
		(net "PHY_SCC_TO_DPB_30_DN")
	)
	(segment
		(start 133.63575 -52.455318)
		(end 133.635496 -52.455572)
		(width 0.1016)
		(layer "In5.Cu")
		(net "PHY_SCC_TO_DPB_30_DN")
	)
	(segment
		(start 131.326636 -63.65113)
		(end 131.269486 -63.59398)
		(width 0.0889)
		(layer "In5.Cu")
		(net "PHY_SCC_TO_DPB_30_DN")
	)
	(arc
		(start 132.80009 -12.031726)
		(mid 132.747567 -11.904925)
		(end 132.620766 -11.852402)
		(width 0.1016)
		(layer "In5.Cu")
		(net "PHY_SCC_TO_DPB_30_DN")
	)
	(arc
		(start 129.774696 -63.59398)
		(mid 129.633005 -63.565907)
		(end 129.512822 -63.485776)
		(width 0.0889)
		(layer "In5.Cu")
		(net "PHY_SCC_TO_DPB_30_DN")
	)
	(arc
		(start 132.271262 -11.852402)
		(mid 132.116622 -11.916456)
		(end 132.052568 -12.071096)
		(width 0.1016)
		(layer "In5.Cu")
		(net "PHY_SCC_TO_DPB_30_DN")
	)
	(arc
		(start 129.404618 -63.089028)
		(mid 129.37858 -63.026166)
		(end 129.315718 -63.000128)
		(width 0.0889)
		(layer "In5.Cu")
		(net "PHY_SCC_TO_DPB_30_DN")
	)
	(arc
		(start 129.512822 -63.485776)
		(mid 129.432678 -63.365598)
		(end 129.404618 -63.223902)
		(width 0.0889)
		(layer "In5.Cu")
		(net "PHY_SCC_TO_DPB_30_DN")
	)
	(segment
		(start 130.50012 -68.500244)
		(end 130.999992 -69.000116)
		(width 0.104902)
		(layer "F.Cu")
		(net "PHY_SCC_TO_DPB_3_DP")
	)
	(via
		(at 130.999992 -69.000116)
		(size 0.4572)
		(drill 0.2032)
		(layers "F.Cu" "B.Cu")
		(net "PHY_SCC_TO_DPB_3_DP")
	)
	(segment
		(start 141.937232 -44.166536)
		(end 139.092178 -30.779974)
		(width 0.1016)
		(layer "In5.Cu")
		(net "PHY_SCC_TO_DPB_3_DP")
	)
	(segment
		(start 138.336274 -57.142888)
		(end 139.589256 -55.212234)
		(width 0.1016)
		(layer "In5.Cu")
		(net "PHY_SCC_TO_DPB_3_DP")
	)
	(segment
		(start 139.092178 -30.779974)
		(end 141.44371 -19.711924)
		(width 0.1016)
		(layer "In5.Cu")
		(net "PHY_SCC_TO_DPB_3_DP")
	)
	(segment
		(start 138.072876 -57.199022)
		(end 138.336274 -57.142888)
		(width 0.1016)
		(layer "In5.Cu")
		(net "PHY_SCC_TO_DPB_3_DP")
	)
	(segment
		(start 137.533634 -58.029856)
		(end 137.797032 -57.973722)
		(width 0.1016)
		(layer "In5.Cu")
		(net "PHY_SCC_TO_DPB_3_DP")
	)
	(segment
		(start 131.624578 -69.36613)
		(end 134.696708 -66.294)
		(width 0.1016)
		(layer "In5.Cu")
		(net "PHY_SCC_TO_DPB_3_DP")
	)
	(segment
		(start 135.204708 -66.294)
		(end 136.926574 -64.572134)
		(width 0.1016)
		(layer "In5.Cu")
		(net "PHY_SCC_TO_DPB_3_DP")
	)
	(segment
		(start 137.797032 -57.973722)
		(end 137.963148 -57.718198)
		(width 0.1016)
		(layer "In5.Cu")
		(net "PHY_SCC_TO_DPB_3_DP")
	)
	(segment
		(start 137.963148 -57.718198)
		(end 137.907014 -57.454546)
		(width 0.1016)
		(layer "In5.Cu")
		(net "PHY_SCC_TO_DPB_3_DP")
	)
	(segment
		(start 139.589256 -55.212234)
		(end 141.937232 -44.166536)
		(width 0.1016)
		(layer "In5.Cu")
		(net "PHY_SCC_TO_DPB_3_DP")
	)
	(segment
		(start 131.413758 -69.36613)
		(end 131.435856 -69.36613)
		(width 0.0889)
		(layer "In5.Cu")
		(net "PHY_SCC_TO_DPB_3_DP")
	)
	(segment
		(start 134.696708 -66.294)
		(end 135.204708 -66.294)
		(width 0.1016)
		(layer "In5.Cu")
		(net "PHY_SCC_TO_DPB_3_DP")
	)
	(segment
		(start 130.750056 -69.406516)
		(end 131.373372 -69.406516)
		(width 0.0889)
		(layer "In5.Cu")
		(net "PHY_SCC_TO_DPB_3_DP")
	)
	(segment
		(start 137.907014 -57.454546)
		(end 138.072876 -57.199022)
		(width 0.1016)
		(layer "In5.Cu")
		(net "PHY_SCC_TO_DPB_3_DP")
	)
	(segment
		(start 137.423906 -58.549032)
		(end 137.367772 -58.285634)
		(width 0.1016)
		(layer "In5.Cu")
		(net "PHY_SCC_TO_DPB_3_DP")
	)
	(segment
		(start 140.747496 -16.435578)
		(end 140.747496 -10.871454)
		(width 0.1016)
		(layer "In5.Cu")
		(net "PHY_SCC_TO_DPB_3_DP")
	)
	(segment
		(start 141.800072 -10.168382)
		(end 141.800072 -9.800082)
		(width 0.1016)
		(layer "In5.Cu")
		(net "PHY_SCC_TO_DPB_3_DP")
	)
	(segment
		(start 136.926574 -59.803792)
		(end 137.081006 -59.077352)
		(width 0.1016)
		(layer "In5.Cu")
		(net "PHY_SCC_TO_DPB_3_DP")
	)
	(segment
		(start 130.999992 -69.000116)
		(end 130.658616 -69.000116)
		(width 0.0889)
		(layer "In5.Cu")
		(net "PHY_SCC_TO_DPB_3_DP")
	)
	(segment
		(start 131.373372 -69.406516)
		(end 131.413758 -69.36613)
		(width 0.0889)
		(layer "In5.Cu")
		(net "PHY_SCC_TO_DPB_3_DP")
	)
	(segment
		(start 137.367772 -58.285634)
		(end 137.533634 -58.029856)
		(width 0.1016)
		(layer "In5.Cu")
		(net "PHY_SCC_TO_DPB_3_DP")
	)
	(segment
		(start 130.569716 -69.089016)
		(end 130.569716 -69.226176)
		(width 0.0889)
		(layer "In5.Cu")
		(net "PHY_SCC_TO_DPB_3_DP")
	)
	(segment
		(start 136.926574 -64.572134)
		(end 136.926574 -59.803792)
		(width 0.1016)
		(layer "In5.Cu")
		(net "PHY_SCC_TO_DPB_3_DP")
	)
	(segment
		(start 141.44371 -19.711924)
		(end 140.747496 -16.435578)
		(width 0.1016)
		(layer "In5.Cu")
		(net "PHY_SCC_TO_DPB_3_DP")
	)
	(segment
		(start 141.271244 -10.347706)
		(end 141.620748 -10.347706)
		(width 0.1016)
		(layer "In5.Cu")
		(net "PHY_SCC_TO_DPB_3_DP")
	)
	(segment
		(start 137.081006 -59.077352)
		(end 137.423906 -58.549032)
		(width 0.1016)
		(layer "In5.Cu")
		(net "PHY_SCC_TO_DPB_3_DP")
	)
	(segment
		(start 131.435856 -69.36613)
		(end 131.624578 -69.36613)
		(width 0.1016)
		(layer "In5.Cu")
		(net "PHY_SCC_TO_DPB_3_DP")
	)
	(arc
		(start 130.569716 -69.226176)
		(mid 130.583444 -69.295189)
		(end 130.622548 -69.353684)
		(width 0.0889)
		(layer "In5.Cu")
		(net "PHY_SCC_TO_DPB_3_DP")
	)
	(arc
		(start 130.658616 -69.000116)
		(mid 130.595754 -69.026154)
		(end 130.569716 -69.089016)
		(width 0.0889)
		(layer "In5.Cu")
		(net "PHY_SCC_TO_DPB_3_DP")
	)
	(arc
		(start 141.620748 -10.347706)
		(mid 141.747549 -10.295183)
		(end 141.800072 -10.168382)
		(width 0.1016)
		(layer "In5.Cu")
		(net "PHY_SCC_TO_DPB_3_DP")
	)
	(arc
		(start 130.622548 -69.353684)
		(mid 130.681049 -69.392773)
		(end 130.750056 -69.406516)
		(width 0.0889)
		(layer "In5.Cu")
		(net "PHY_SCC_TO_DPB_3_DP")
	)
	(arc
		(start 140.747496 -10.871454)
		(mid 140.900898 -10.501108)
		(end 141.271244 -10.347706)
		(width 0.1016)
		(layer "In5.Cu")
		(net "PHY_SCC_TO_DPB_3_DP")
	)
	(segment
		(start 129.500122 -68.500244)
		(end 129.999994 -69.000116)
		(width 0.104902)
		(layer "F.Cu")
		(net "PHY_SCC_TO_DPB_3_DN")
	)
	(via
		(at 129.999994 -69.000116)
		(size 0.4572)
		(drill 0.2032)
		(layers "F.Cu" "B.Cu")
		(net "PHY_SCC_TO_DPB_3_DN")
	)
	(segment
		(start 142.24889 -44.166536)
		(end 139.403836 -30.779974)
		(width 0.1016)
		(layer "In5.Cu")
		(net "PHY_SCC_TO_DPB_3_DN")
	)
	(segment
		(start 130.379216 -69.089016)
		(end 130.379216 -69.226176)
		(width 0.0889)
		(layer "In5.Cu")
		(net "PHY_SCC_TO_DPB_3_DN")
	)
	(segment
		(start 141.271244 -10.652506)
		(end 141.620748 -10.652506)
		(width 0.1016)
		(layer "In5.Cu")
		(net "PHY_SCC_TO_DPB_3_DN")
	)
	(segment
		(start 141.755368 -19.711924)
		(end 141.052296 -16.40332)
		(width 0.1016)
		(layer "In5.Cu")
		(net "PHY_SCC_TO_DPB_3_DN")
	)
	(segment
		(start 130.750056 -69.597016)
		(end 131.339844 -69.597016)
		(width 0.0889)
		(layer "In5.Cu")
		(net "PHY_SCC_TO_DPB_3_DN")
	)
	(segment
		(start 137.231374 -64.698626)
		(end 137.231374 -59.83605)
		(width 0.1016)
		(layer "In5.Cu")
		(net "PHY_SCC_TO_DPB_3_DN")
	)
	(segment
		(start 137.679938 -58.715148)
		(end 139.875768 -55.330852)
		(width 0.1016)
		(layer "In5.Cu")
		(net "PHY_SCC_TO_DPB_3_DN")
	)
	(segment
		(start 137.523728 -58.955178)
		(end 137.523982 -58.955178)
		(width 0.1016)
		(layer "In5.Cu")
		(net "PHY_SCC_TO_DPB_3_DN")
	)
	(segment
		(start 141.800072 -10.83183)
		(end 141.800072 -11.20013)
		(width 0.1016)
		(layer "In5.Cu")
		(net "PHY_SCC_TO_DPB_3_DN")
	)
	(segment
		(start 137.523982 -58.955178)
		(end 137.679684 -58.714894)
		(width 0.1016)
		(layer "In5.Cu")
		(net "PHY_SCC_TO_DPB_3_DN")
	)
	(segment
		(start 131.339844 -69.597016)
		(end 131.413758 -69.67093)
		(width 0.0889)
		(layer "In5.Cu")
		(net "PHY_SCC_TO_DPB_3_DN")
	)
	(segment
		(start 135.3312 -66.5988)
		(end 137.231374 -64.698626)
		(width 0.1016)
		(layer "In5.Cu")
		(net "PHY_SCC_TO_DPB_3_DN")
	)
	(segment
		(start 139.875768 -55.330852)
		(end 142.24889 -44.166536)
		(width 0.1016)
		(layer "In5.Cu")
		(net "PHY_SCC_TO_DPB_3_DN")
	)
	(segment
		(start 131.435856 -69.67093)
		(end 131.75107 -69.67093)
		(width 0.1016)
		(layer "In5.Cu")
		(net "PHY_SCC_TO_DPB_3_DN")
	)
	(segment
		(start 137.679684 -58.714894)
		(end 137.679938 -58.715148)
		(width 0.1016)
		(layer "In5.Cu")
		(net "PHY_SCC_TO_DPB_3_DN")
	)
	(segment
		(start 141.052296 -16.40332)
		(end 141.052296 -10.871454)
		(width 0.1016)
		(layer "In5.Cu")
		(net "PHY_SCC_TO_DPB_3_DN")
	)
	(segment
		(start 131.413758 -69.67093)
		(end 131.435856 -69.67093)
		(width 0.0889)
		(layer "In5.Cu")
		(net "PHY_SCC_TO_DPB_3_DN")
	)
	(segment
		(start 139.403836 -30.779974)
		(end 141.755368 -19.711924)
		(width 0.1016)
		(layer "In5.Cu")
		(net "PHY_SCC_TO_DPB_3_DN")
	)
	(segment
		(start 131.75107 -69.67093)
		(end 134.8232 -66.5988)
		(width 0.1016)
		(layer "In5.Cu")
		(net "PHY_SCC_TO_DPB_3_DN")
	)
	(segment
		(start 134.8232 -66.5988)
		(end 135.3312 -66.5988)
		(width 0.1016)
		(layer "In5.Cu")
		(net "PHY_SCC_TO_DPB_3_DN")
	)
	(segment
		(start 137.231374 -59.83605)
		(end 137.367518 -59.19597)
		(width 0.1016)
		(layer "In5.Cu")
		(net "PHY_SCC_TO_DPB_3_DN")
	)
	(segment
		(start 137.367518 -59.19597)
		(end 137.523728 -58.955178)
		(width 0.1016)
		(layer "In5.Cu")
		(net "PHY_SCC_TO_DPB_3_DN")
	)
	(segment
		(start 129.999994 -69.000116)
		(end 130.290316 -69.000116)
		(width 0.0889)
		(layer "In5.Cu")
		(net "PHY_SCC_TO_DPB_3_DN")
	)
	(arc
		(start 141.620748 -10.652506)
		(mid 141.747549 -10.705029)
		(end 141.800072 -10.83183)
		(width 0.1016)
		(layer "In5.Cu")
		(net "PHY_SCC_TO_DPB_3_DN")
	)
	(arc
		(start 130.379216 -69.226176)
		(mid 130.407362 -69.368144)
		(end 130.487674 -69.488558)
		(width 0.0889)
		(layer "In5.Cu")
		(net "PHY_SCC_TO_DPB_3_DN")
	)
	(arc
		(start 141.052296 -10.871454)
		(mid 141.116424 -10.716634)
		(end 141.271244 -10.652506)
		(width 0.1016)
		(layer "In5.Cu")
		(net "PHY_SCC_TO_DPB_3_DN")
	)
	(arc
		(start 130.290316 -69.000116)
		(mid 130.353178 -69.026154)
		(end 130.379216 -69.089016)
		(width 0.0889)
		(layer "In5.Cu")
		(net "PHY_SCC_TO_DPB_3_DN")
	)
	(arc
		(start 130.487674 -69.488558)
		(mid 130.608071 -69.568912)
		(end 130.750056 -69.597016)
		(width 0.0889)
		(layer "In5.Cu")
		(net "PHY_SCC_TO_DPB_3_DN")
	)
	(segment
		(start 130.50012 -62.500002)
		(end 130.999992 -62.00013)
		(width 0.104902)
		(layer "F.Cu")
		(net "PHY_SCC_TO_DPB_29_DP")
	)
	(via
		(at 130.999992 -62.00013)
		(size 0.4572)
		(drill 0.2032)
		(layers "F.Cu" "B.Cu")
		(net "PHY_SCC_TO_DPB_29_DP")
	)
	(segment
		(start 129.94767 -18.015966)
		(end 129.94767 -16.450056)
		(width 0.1016)
		(layer "In5.Cu")
		(net "PHY_SCC_TO_DPB_29_DP")
	)
	(segment
		(start 131.7498 -62.172342)
		(end 131.7498 -54.483508)
		(width 0.1016)
		(layer "In5.Cu")
		(net "PHY_SCC_TO_DPB_29_DP")
	)
	(segment
		(start 130.595116 -62.08903)
		(end 130.595116 -62.283848)
		(width 0.0889)
		(layer "In5.Cu")
		(net "PHY_SCC_TO_DPB_29_DP")
	)
	(segment
		(start 131.574032 -62.34811)
		(end 131.7498 -62.172342)
		(width 0.1016)
		(layer "In5.Cu")
		(net "PHY_SCC_TO_DPB_29_DP")
	)
	(segment
		(start 131.450334 -62.34811)
		(end 131.472432 -62.34811)
		(width 0.0889)
		(layer "In5.Cu")
		(net "PHY_SCC_TO_DPB_29_DP")
	)
	(segment
		(start 129.75717 -15.954756)
		(end 129.94767 -15.764256)
		(width 0.1016)
		(layer "In5.Cu")
		(net "PHY_SCC_TO_DPB_29_DP")
	)
	(segment
		(start 129.75717 -15.268956)
		(end 129.75717 -14.964156)
		(width 0.1016)
		(layer "In5.Cu")
		(net "PHY_SCC_TO_DPB_29_DP")
	)
	(segment
		(start 130.471164 -10.347706)
		(end 130.820668 -10.347706)
		(width 0.1016)
		(layer "In5.Cu")
		(net "PHY_SCC_TO_DPB_29_DP")
	)
	(segment
		(start 130.999992 -62.00013)
		(end 130.684016 -62.00013)
		(width 0.0889)
		(layer "In5.Cu")
		(net "PHY_SCC_TO_DPB_29_DP")
	)
	(segment
		(start 131.393184 -62.40526)
		(end 131.450334 -62.34811)
		(width 0.0889)
		(layer "In5.Cu")
		(net "PHY_SCC_TO_DPB_29_DP")
	)
	(segment
		(start 132.193792 -52.394866)
		(end 134.92226 -48.193452)
		(width 0.1016)
		(layer "In5.Cu")
		(net "PHY_SCC_TO_DPB_29_DP")
	)
	(segment
		(start 129.94767 -16.450056)
		(end 129.75717 -16.259556)
		(width 0.1016)
		(layer "In5.Cu")
		(net "PHY_SCC_TO_DPB_29_DP")
	)
	(segment
		(start 130.999992 -10.168382)
		(end 130.999992 -9.800082)
		(width 0.1016)
		(layer "In5.Cu")
		(net "PHY_SCC_TO_DPB_29_DP")
	)
	(segment
		(start 129.94767 -15.764256)
		(end 129.94767 -15.459456)
		(width 0.1016)
		(layer "In5.Cu")
		(net "PHY_SCC_TO_DPB_29_DP")
	)
	(segment
		(start 135.641588 -44.808394)
		(end 129.94767 -18.015966)
		(width 0.1016)
		(layer "In5.Cu")
		(net "PHY_SCC_TO_DPB_29_DP")
	)
	(segment
		(start 134.92226 -48.193452)
		(end 135.641588 -44.808394)
		(width 0.1016)
		(layer "In5.Cu")
		(net "PHY_SCC_TO_DPB_29_DP")
	)
	(segment
		(start 129.94767 -15.459456)
		(end 129.75717 -15.268956)
		(width 0.1016)
		(layer "In5.Cu")
		(net "PHY_SCC_TO_DPB_29_DP")
	)
	(segment
		(start 130.716528 -62.40526)
		(end 131.393184 -62.40526)
		(width 0.0889)
		(layer "In5.Cu")
		(net "PHY_SCC_TO_DPB_29_DP")
	)
	(segment
		(start 129.75717 -14.964156)
		(end 129.94767 -14.773656)
		(width 0.1016)
		(layer "In5.Cu")
		(net "PHY_SCC_TO_DPB_29_DP")
	)
	(segment
		(start 131.7498 -54.483508)
		(end 132.193792 -52.394866)
		(width 0.1016)
		(layer "In5.Cu")
		(net "PHY_SCC_TO_DPB_29_DP")
	)
	(segment
		(start 131.472432 -62.34811)
		(end 131.574032 -62.34811)
		(width 0.1016)
		(layer "In5.Cu")
		(net "PHY_SCC_TO_DPB_29_DP")
	)
	(segment
		(start 129.94767 -14.773656)
		(end 129.94767 -10.8712)
		(width 0.1016)
		(layer "In5.Cu")
		(net "PHY_SCC_TO_DPB_29_DP")
	)
	(segment
		(start 129.75717 -16.259556)
		(end 129.75717 -15.954756)
		(width 0.1016)
		(layer "In5.Cu")
		(net "PHY_SCC_TO_DPB_29_DP")
	)
	(arc
		(start 130.595116 -62.283848)
		(mid 130.604358 -62.33031)
		(end 130.630676 -62.3697)
		(width 0.0889)
		(layer "In5.Cu")
		(net "PHY_SCC_TO_DPB_29_DP")
	)
	(arc
		(start 130.630676 -62.3697)
		(mid 130.670065 -62.396019)
		(end 130.716528 -62.40526)
		(width 0.0889)
		(layer "In5.Cu")
		(net "PHY_SCC_TO_DPB_29_DP")
	)
	(arc
		(start 130.820668 -10.347706)
		(mid 130.947469 -10.295183)
		(end 130.999992 -10.168382)
		(width 0.1016)
		(layer "In5.Cu")
		(net "PHY_SCC_TO_DPB_29_DP")
	)
	(arc
		(start 129.94767 -10.8712)
		(mid 130.100998 -10.501034)
		(end 130.471164 -10.347706)
		(width 0.1016)
		(layer "In5.Cu")
		(net "PHY_SCC_TO_DPB_29_DP")
	)
	(arc
		(start 130.684016 -62.00013)
		(mid 130.621154 -62.026168)
		(end 130.595116 -62.08903)
		(width 0.0889)
		(layer "In5.Cu")
		(net "PHY_SCC_TO_DPB_29_DP")
	)
	(segment
		(start 129.500122 -62.500002)
		(end 129.999994 -62.00013)
		(width 0.104902)
		(layer "F.Cu")
		(net "PHY_SCC_TO_DPB_29_DN")
	)
	(via
		(at 129.999994 -62.00013)
		(size 0.4572)
		(drill 0.2032)
		(layers "F.Cu" "B.Cu")
		(net "PHY_SCC_TO_DPB_29_DN")
	)
	(segment
		(start 135.208772 -48.31207)
		(end 135.953246 -44.808394)
		(width 0.1016)
		(layer "In5.Cu")
		(net "PHY_SCC_TO_DPB_29_DN")
	)
	(segment
		(start 130.716528 -62.59576)
		(end 131.393184 -62.59576)
		(width 0.0889)
		(layer "In5.Cu")
		(net "PHY_SCC_TO_DPB_29_DN")
	)
	(segment
		(start 131.393184 -62.59576)
		(end 131.450334 -62.65291)
		(width 0.0889)
		(layer "In5.Cu")
		(net "PHY_SCC_TO_DPB_29_DN")
	)
	(segment
		(start 130.25247 -17.983708)
		(end 130.25247 -10.8712)
		(width 0.1016)
		(layer "In5.Cu")
		(net "PHY_SCC_TO_DPB_29_DN")
	)
	(segment
		(start 131.450334 -62.65291)
		(end 131.472432 -62.65291)
		(width 0.0889)
		(layer "In5.Cu")
		(net "PHY_SCC_TO_DPB_29_DN")
	)
	(segment
		(start 132.0546 -54.515766)
		(end 132.480304 -52.513484)
		(width 0.1016)
		(layer "In5.Cu")
		(net "PHY_SCC_TO_DPB_29_DN")
	)
	(segment
		(start 132.0546 -62.298834)
		(end 132.0546 -54.515766)
		(width 0.1016)
		(layer "In5.Cu")
		(net "PHY_SCC_TO_DPB_29_DN")
	)
	(segment
		(start 132.480304 -52.513484)
		(end 135.208772 -48.31207)
		(width 0.1016)
		(layer "In5.Cu")
		(net "PHY_SCC_TO_DPB_29_DN")
	)
	(segment
		(start 130.404616 -62.08903)
		(end 130.404616 -62.283848)
		(width 0.0889)
		(layer "In5.Cu")
		(net "PHY_SCC_TO_DPB_29_DN")
	)
	(segment
		(start 130.999992 -10.83183)
		(end 130.999992 -11.20013)
		(width 0.1016)
		(layer "In5.Cu")
		(net "PHY_SCC_TO_DPB_29_DN")
	)
	(segment
		(start 131.472432 -62.65291)
		(end 131.700524 -62.65291)
		(width 0.1016)
		(layer "In5.Cu")
		(net "PHY_SCC_TO_DPB_29_DN")
	)
	(segment
		(start 130.471164 -10.652506)
		(end 130.820668 -10.652506)
		(width 0.1016)
		(layer "In5.Cu")
		(net "PHY_SCC_TO_DPB_29_DN")
	)
	(segment
		(start 129.999994 -62.00013)
		(end 130.315716 -62.00013)
		(width 0.0889)
		(layer "In5.Cu")
		(net "PHY_SCC_TO_DPB_29_DN")
	)
	(segment
		(start 131.700524 -62.65291)
		(end 132.0546 -62.298834)
		(width 0.1016)
		(layer "In5.Cu")
		(net "PHY_SCC_TO_DPB_29_DN")
	)
	(segment
		(start 135.953246 -44.808394)
		(end 130.25247 -17.983708)
		(width 0.1016)
		(layer "In5.Cu")
		(net "PHY_SCC_TO_DPB_29_DN")
	)
	(arc
		(start 130.315716 -62.00013)
		(mid 130.378578 -62.026168)
		(end 130.404616 -62.08903)
		(width 0.0889)
		(layer "In5.Cu")
		(net "PHY_SCC_TO_DPB_29_DN")
	)
	(arc
		(start 130.495802 -62.504574)
		(mid 130.597087 -62.572157)
		(end 130.716528 -62.59576)
		(width 0.0889)
		(layer "In5.Cu")
		(net "PHY_SCC_TO_DPB_29_DN")
	)
	(arc
		(start 130.25247 -10.8712)
		(mid 130.316524 -10.71656)
		(end 130.471164 -10.652506)
		(width 0.1016)
		(layer "In5.Cu")
		(net "PHY_SCC_TO_DPB_29_DN")
	)
	(arc
		(start 130.820668 -10.652506)
		(mid 130.947469 -10.705029)
		(end 130.999992 -10.83183)
		(width 0.1016)
		(layer "In5.Cu")
		(net "PHY_SCC_TO_DPB_29_DN")
	)
	(arc
		(start 130.404616 -62.283848)
		(mid 130.428276 -62.403265)
		(end 130.495802 -62.504574)
		(width 0.0889)
		(layer "In5.Cu")
		(net "PHY_SCC_TO_DPB_29_DN")
	)
	(segment
		(start 129.500122 -61.500004)
		(end 129.999994 -61.000132)
		(width 0.104902)
		(layer "F.Cu")
		(net "PHY_SCC_TO_DPB_28_DP")
	)
	(via
		(at 129.999994 -61.000132)
		(size 0.4572)
		(drill 0.2032)
		(layers "F.Cu" "B.Cu")
		(net "PHY_SCC_TO_DPB_28_DP")
	)
	(segment
		(start 129.595118 -61.23178)
		(end 129.595118 -61.089032)
		(width 0.0889)
		(layer "In5.Cu")
		(net "PHY_SCC_TO_DPB_28_DP")
	)
	(segment
		(start 129.200148 -10.999978)
		(end 129.200148 -11.368278)
		(width 0.1016)
		(layer "In5.Cu")
		(net "PHY_SCC_TO_DPB_28_DP")
	)
	(segment
		(start 131.085336 -52.40147)
		(end 130.893566 -52.696872)
		(width 0.1016)
		(layer "In5.Cu")
		(net "PHY_SCC_TO_DPB_28_DP")
	)
	(segment
		(start 131.195572 -51.882294)
		(end 131.029456 -52.137818)
		(width 0.1016)
		(layer "In5.Cu")
		(net "PHY_SCC_TO_DPB_28_DP")
	)
	(segment
		(start 128.147826 -15.306294)
		(end 134.496302 -45.179234)
		(width 0.1016)
		(layer "In5.Cu")
		(net "PHY_SCC_TO_DPB_28_DP")
	)
	(segment
		(start 131.45897 -51.82616)
		(end 131.195572 -51.882294)
		(width 0.1016)
		(layer "In5.Cu")
		(net "PHY_SCC_TO_DPB_28_DP")
	)
	(segment
		(start 131.029456 -52.137818)
		(end 131.085336 -52.40147)
		(width 0.1016)
		(layer "In5.Cu")
		(net "PHY_SCC_TO_DPB_28_DP")
	)
	(segment
		(start 129.684018 -61.000132)
		(end 129.999994 -61.000132)
		(width 0.0889)
		(layer "In5.Cu")
		(net "PHY_SCC_TO_DPB_28_DP")
	)
	(segment
		(start 130.27787 -61.4045)
		(end 129.768092 -61.4045)
		(width 0.0889)
		(layer "In5.Cu")
		(net "PHY_SCC_TO_DPB_28_DP")
	)
	(segment
		(start 130.367532 -60.248292)
		(end 130.367532 -60.27039)
		(width 0.0889)
		(layer "In5.Cu")
		(net "PHY_SCC_TO_DPB_28_DP")
	)
	(segment
		(start 130.893566 -52.696872)
		(end 130.367532 -55.173118)
		(width 0.1016)
		(layer "In5.Cu")
		(net "PHY_SCC_TO_DPB_28_DP")
	)
	(segment
		(start 130.367532 -55.173118)
		(end 130.367532 -60.248292)
		(width 0.1016)
		(layer "In5.Cu")
		(net "PHY_SCC_TO_DPB_28_DP")
	)
	(segment
		(start 128.147826 -12.071096)
		(end 128.147826 -15.306294)
		(width 0.1016)
		(layer "In5.Cu")
		(net "PHY_SCC_TO_DPB_28_DP")
	)
	(segment
		(start 134.496302 -45.179234)
		(end 133.874002 -48.107854)
		(width 0.1016)
		(layer "In5.Cu")
		(net "PHY_SCC_TO_DPB_28_DP")
	)
	(segment
		(start 133.874002 -48.107854)
		(end 131.45897 -51.82616)
		(width 0.1016)
		(layer "In5.Cu")
		(net "PHY_SCC_TO_DPB_28_DP")
	)
	(segment
		(start 130.40614 -60.308998)
		(end 130.40614 -61.27623)
		(width 0.0889)
		(layer "In5.Cu")
		(net "PHY_SCC_TO_DPB_28_DP")
	)
	(segment
		(start 130.367532 -60.27039)
		(end 130.40614 -60.308998)
		(width 0.0889)
		(layer "In5.Cu")
		(net "PHY_SCC_TO_DPB_28_DP")
	)
	(segment
		(start 129.020824 -11.547602)
		(end 128.67132 -11.547602)
		(width 0.1016)
		(layer "In5.Cu")
		(net "PHY_SCC_TO_DPB_28_DP")
	)
	(arc
		(start 130.40614 -61.27623)
		(mid 130.368571 -61.366931)
		(end 130.27787 -61.4045)
		(width 0.0889)
		(layer "In5.Cu")
		(net "PHY_SCC_TO_DPB_28_DP")
	)
	(arc
		(start 129.200148 -11.368278)
		(mid 129.147625 -11.495079)
		(end 129.020824 -11.547602)
		(width 0.1016)
		(layer "In5.Cu")
		(net "PHY_SCC_TO_DPB_28_DP")
	)
	(arc
		(start 129.595118 -61.089032)
		(mid 129.621156 -61.02617)
		(end 129.684018 -61.000132)
		(width 0.0889)
		(layer "In5.Cu")
		(net "PHY_SCC_TO_DPB_28_DP")
	)
	(arc
		(start 129.768092 -61.4045)
		(mid 129.701815 -61.391299)
		(end 129.645664 -61.3537)
		(width 0.0889)
		(layer "In5.Cu")
		(net "PHY_SCC_TO_DPB_28_DP")
	)
	(arc
		(start 128.67132 -11.547602)
		(mid 128.301154 -11.70093)
		(end 128.147826 -12.071096)
		(width 0.1016)
		(layer "In5.Cu")
		(net "PHY_SCC_TO_DPB_28_DP")
	)
	(arc
		(start 129.645664 -61.3537)
		(mid 129.608234 -61.297777)
		(end 129.595118 -61.23178)
		(width 0.0889)
		(layer "In5.Cu")
		(net "PHY_SCC_TO_DPB_28_DP")
	)
	(segment
		(start 128.500124 -61.500004)
		(end 128.999996 -61.000132)
		(width 0.104902)
		(layer "F.Cu")
		(net "PHY_SCC_TO_DPB_28_DN")
	)
	(via
		(at 128.999996 -61.000132)
		(size 0.4572)
		(drill 0.2032)
		(layers "F.Cu" "B.Cu")
		(net "PHY_SCC_TO_DPB_28_DN")
	)
	(segment
		(start 130.59664 -61.27623)
		(end 130.59664 -60.346082)
		(width 0.0889)
		(layer "In5.Cu")
		(net "PHY_SCC_TO_DPB_28_DN")
	)
	(segment
		(start 129.404618 -61.089032)
		(end 129.404618 -61.23178)
		(width 0.0889)
		(layer "In5.Cu")
		(net "PHY_SCC_TO_DPB_28_DN")
	)
	(segment
		(start 134.160514 -48.226472)
		(end 134.80796 -45.179234)
		(width 0.1016)
		(layer "In5.Cu")
		(net "PHY_SCC_TO_DPB_28_DN")
	)
	(segment
		(start 130.672332 -55.205376)
		(end 131.180078 -52.81549)
		(width 0.1016)
		(layer "In5.Cu")
		(net "PHY_SCC_TO_DPB_28_DN")
	)
	(segment
		(start 131.180078 -52.81549)
		(end 134.160514 -48.226472)
		(width 0.1016)
		(layer "In5.Cu")
		(net "PHY_SCC_TO_DPB_28_DN")
	)
	(segment
		(start 129.768092 -61.595)
		(end 130.27787 -61.595)
		(width 0.0889)
		(layer "In5.Cu")
		(net "PHY_SCC_TO_DPB_28_DN")
	)
	(segment
		(start 134.80796 -45.179234)
		(end 128.452626 -15.274036)
		(width 0.1016)
		(layer "In5.Cu")
		(net "PHY_SCC_TO_DPB_28_DN")
	)
	(segment
		(start 130.672332 -60.27039)
		(end 130.672332 -60.248292)
		(width 0.0889)
		(layer "In5.Cu")
		(net "PHY_SCC_TO_DPB_28_DN")
	)
	(segment
		(start 128.999996 -61.000132)
		(end 129.315718 -61.000132)
		(width 0.0889)
		(layer "In5.Cu")
		(net "PHY_SCC_TO_DPB_28_DN")
	)
	(segment
		(start 130.59664 -60.346082)
		(end 130.672332 -60.27039)
		(width 0.0889)
		(layer "In5.Cu")
		(net "PHY_SCC_TO_DPB_28_DN")
	)
	(segment
		(start 128.452626 -15.274036)
		(end 128.452626 -12.071096)
		(width 0.1016)
		(layer "In5.Cu")
		(net "PHY_SCC_TO_DPB_28_DN")
	)
	(segment
		(start 129.200148 -12.031726)
		(end 129.200148 -12.400026)
		(width 0.1016)
		(layer "In5.Cu")
		(net "PHY_SCC_TO_DPB_28_DN")
	)
	(segment
		(start 130.672332 -60.248292)
		(end 130.672332 -55.205376)
		(width 0.1016)
		(layer "In5.Cu")
		(net "PHY_SCC_TO_DPB_28_DN")
	)
	(segment
		(start 128.67132 -11.852402)
		(end 129.020824 -11.852402)
		(width 0.1016)
		(layer "In5.Cu")
		(net "PHY_SCC_TO_DPB_28_DN")
	)
	(arc
		(start 129.404618 -61.23178)
		(mid 129.432164 -61.370735)
		(end 129.51079 -61.488574)
		(width 0.0889)
		(layer "In5.Cu")
		(net "PHY_SCC_TO_DPB_28_DN")
	)
	(arc
		(start 128.452626 -12.071096)
		(mid 128.51668 -11.916456)
		(end 128.67132 -11.852402)
		(width 0.1016)
		(layer "In5.Cu")
		(net "PHY_SCC_TO_DPB_28_DN")
	)
	(arc
		(start 130.27787 -61.595)
		(mid 130.503274 -61.501634)
		(end 130.59664 -61.27623)
		(width 0.0889)
		(layer "In5.Cu")
		(net "PHY_SCC_TO_DPB_28_DN")
	)
	(arc
		(start 129.020824 -11.852402)
		(mid 129.147625 -11.904925)
		(end 129.200148 -12.031726)
		(width 0.1016)
		(layer "In5.Cu")
		(net "PHY_SCC_TO_DPB_28_DN")
	)
	(arc
		(start 129.315718 -61.000132)
		(mid 129.37858 -61.02617)
		(end 129.404618 -61.089032)
		(width 0.0889)
		(layer "In5.Cu")
		(net "PHY_SCC_TO_DPB_28_DN")
	)
	(arc
		(start 129.51079 -61.488574)
		(mid 129.628842 -61.567424)
		(end 129.768092 -61.595)
		(width 0.0889)
		(layer "In5.Cu")
		(net "PHY_SCC_TO_DPB_28_DN")
	)
	(segment
		(start 115.50015 -52.500022)
		(end 116.000022 -52.00015)
		(width 0.104902)
		(layer "F.Cu")
		(net "PHY_SCC_TO_DPB_27_DP")
	)
	(via
		(at 116.000022 -52.00015)
		(size 0.4572)
		(drill 0.2032)
		(layers "F.Cu" "B.Cu")
		(net "PHY_SCC_TO_DPB_27_DP")
	)
	(segment
		(start 116.34724 -50.075338)
		(end 116.767864 -48.096932)
		(width 0.1016)
		(layer "In5.Cu")
		(net "PHY_SCC_TO_DPB_27_DP")
	)
	(segment
		(start 116.767864 -48.096932)
		(end 118.870984 -44.857162)
		(width 0.1016)
		(layer "In5.Cu")
		(net "PHY_SCC_TO_DPB_27_DP")
	)
	(segment
		(start 117.30736 -40.814752)
		(end 111.947706 -15.573248)
		(width 0.1016)
		(layer "In5.Cu")
		(net "PHY_SCC_TO_DPB_27_DP")
	)
	(segment
		(start 116.36121 -52.3621)
		(end 116.361464 -52.361846)
		(width 0.0889)
		(layer "In5.Cu")
		(net "PHY_SCC_TO_DPB_27_DP")
	)
	(segment
		(start 113.000028 -10.168382)
		(end 113.000028 -9.800082)
		(width 0.1016)
		(layer "In5.Cu")
		(net "PHY_SCC_TO_DPB_27_DP")
	)
	(segment
		(start 118.870984 -43.692572)
		(end 117.30736 -40.814752)
		(width 0.1016)
		(layer "In5.Cu")
		(net "PHY_SCC_TO_DPB_27_DP")
	)
	(segment
		(start 116.40439 -50.60315)
		(end 116.34724 -50.546)
		(width 0.0889)
		(layer "In5.Cu")
		(net "PHY_SCC_TO_DPB_27_DP")
	)
	(segment
		(start 118.870984 -44.857162)
		(end 118.870984 -43.692572)
		(width 0.1016)
		(layer "In5.Cu")
		(net "PHY_SCC_TO_DPB_27_DP")
	)
	(segment
		(start 116.40439 -52.257706)
		(end 116.40439 -50.60315)
		(width 0.0889)
		(layer "In5.Cu")
		(net "PHY_SCC_TO_DPB_27_DP")
	)
	(segment
		(start 116.34724 -50.546)
		(end 116.34724 -50.523902)
		(width 0.0889)
		(layer "In5.Cu")
		(net "PHY_SCC_TO_DPB_27_DP")
	)
	(segment
		(start 116.000022 -52.00015)
		(end 116.000022 -52.315872)
		(width 0.0889)
		(layer "In5.Cu")
		(net "PHY_SCC_TO_DPB_27_DP")
	)
	(segment
		(start 116.088922 -52.404772)
		(end 116.257578 -52.404772)
		(width 0.0889)
		(layer "In5.Cu")
		(net "PHY_SCC_TO_DPB_27_DP")
	)
	(segment
		(start 116.34724 -50.523902)
		(end 116.34724 -50.075338)
		(width 0.1016)
		(layer "In5.Cu")
		(net "PHY_SCC_TO_DPB_27_DP")
	)
	(segment
		(start 111.947706 -15.573248)
		(end 111.947706 -10.8712)
		(width 0.1016)
		(layer "In5.Cu")
		(net "PHY_SCC_TO_DPB_27_DP")
	)
	(segment
		(start 112.4712 -10.347706)
		(end 112.820704 -10.347706)
		(width 0.1016)
		(layer "In5.Cu")
		(net "PHY_SCC_TO_DPB_27_DP")
	)
	(arc
		(start 116.257578 -52.404772)
		(mid 116.313609 -52.39368)
		(end 116.36121 -52.3621)
		(width 0.0889)
		(layer "In5.Cu")
		(net "PHY_SCC_TO_DPB_27_DP")
	)
	(arc
		(start 116.000022 -52.315872)
		(mid 116.02606 -52.378734)
		(end 116.088922 -52.404772)
		(width 0.0889)
		(layer "In5.Cu")
		(net "PHY_SCC_TO_DPB_27_DP")
	)
	(arc
		(start 112.820704 -10.347706)
		(mid 112.947505 -10.295183)
		(end 113.000028 -10.168382)
		(width 0.1016)
		(layer "In5.Cu")
		(net "PHY_SCC_TO_DPB_27_DP")
	)
	(arc
		(start 116.361464 -52.361846)
		(mid 116.393306 -52.314051)
		(end 116.40439 -52.257706)
		(width 0.0889)
		(layer "In5.Cu")
		(net "PHY_SCC_TO_DPB_27_DP")
	)
	(arc
		(start 111.947706 -10.8712)
		(mid 112.101034 -10.501034)
		(end 112.4712 -10.347706)
		(width 0.1016)
		(layer "In5.Cu")
		(net "PHY_SCC_TO_DPB_27_DP")
	)
	(segment
		(start 115.50015 -53.50002)
		(end 116.000022 -53.000148)
		(width 0.104902)
		(layer "F.Cu")
		(net "PHY_SCC_TO_DPB_27_DN")
	)
	(via
		(at 116.000022 -53.000148)
		(size 0.4572)
		(drill 0.2032)
		(layers "F.Cu" "B.Cu")
		(net "PHY_SCC_TO_DPB_27_DN")
	)
	(segment
		(start 116.65204 -50.107596)
		(end 117.054376 -48.21555)
		(width 0.1016)
		(layer "In5.Cu")
		(net "PHY_SCC_TO_DPB_27_DN")
	)
	(segment
		(start 112.4712 -10.652506)
		(end 112.820704 -10.652506)
		(width 0.1016)
		(layer "In5.Cu")
		(net "PHY_SCC_TO_DPB_27_DN")
	)
	(segment
		(start 116.000022 -53.000148)
		(end 116.000022 -52.684172)
		(width 0.0889)
		(layer "In5.Cu")
		(net "PHY_SCC_TO_DPB_27_DN")
	)
	(segment
		(start 117.646704 -47.303436)
		(end 117.910102 -47.247302)
		(width 0.1016)
		(layer "In5.Cu")
		(net "PHY_SCC_TO_DPB_27_DN")
	)
	(segment
		(start 117.910102 -47.247302)
		(end 118.076218 -46.991778)
		(width 0.1016)
		(layer "In5.Cu")
		(net "PHY_SCC_TO_DPB_27_DN")
	)
	(segment
		(start 117.054376 -48.21555)
		(end 117.646704 -47.303436)
		(width 0.1016)
		(layer "In5.Cu")
		(net "PHY_SCC_TO_DPB_27_DN")
	)
	(segment
		(start 112.252506 -15.541244)
		(end 112.252506 -10.8712)
		(width 0.1016)
		(layer "In5.Cu")
		(net "PHY_SCC_TO_DPB_27_DN")
	)
	(segment
		(start 117.596412 -40.708072)
		(end 112.252506 -15.541244)
		(width 0.1016)
		(layer "In5.Cu")
		(net "PHY_SCC_TO_DPB_27_DN")
	)
	(segment
		(start 119.175784 -43.615102)
		(end 117.596412 -40.708072)
		(width 0.1016)
		(layer "In5.Cu")
		(net "PHY_SCC_TO_DPB_27_DN")
	)
	(segment
		(start 116.49583 -52.497228)
		(end 116.496338 -52.496466)
		(width 0.0889)
		(layer "In5.Cu")
		(net "PHY_SCC_TO_DPB_27_DN")
	)
	(segment
		(start 118.076218 -46.991778)
		(end 118.020084 -46.728126)
		(width 0.1016)
		(layer "In5.Cu")
		(net "PHY_SCC_TO_DPB_27_DN")
	)
	(segment
		(start 116.59489 -50.60315)
		(end 116.65204 -50.546)
		(width 0.0889)
		(layer "In5.Cu")
		(net "PHY_SCC_TO_DPB_27_DN")
	)
	(segment
		(start 118.573296 -45.875702)
		(end 118.573296 -45.875448)
		(width 0.1016)
		(layer "In5.Cu")
		(net "PHY_SCC_TO_DPB_27_DN")
	)
	(segment
		(start 113.000028 -10.83183)
		(end 113.000028 -11.20013)
		(width 0.1016)
		(layer "In5.Cu")
		(net "PHY_SCC_TO_DPB_27_DN")
	)
	(segment
		(start 119.175784 -44.947586)
		(end 119.175784 -43.615102)
		(width 0.1016)
		(layer "In5.Cu")
		(net "PHY_SCC_TO_DPB_27_DN")
	)
	(segment
		(start 116.59489 -52.257706)
		(end 116.59489 -50.60315)
		(width 0.0889)
		(layer "In5.Cu")
		(net "PHY_SCC_TO_DPB_27_DN")
	)
	(segment
		(start 118.020084 -46.728126)
		(end 118.573296 -45.875702)
		(width 0.1016)
		(layer "In5.Cu")
		(net "PHY_SCC_TO_DPB_27_DN")
	)
	(segment
		(start 118.573296 -45.875448)
		(end 119.175784 -44.947586)
		(width 0.1016)
		(layer "In5.Cu")
		(net "PHY_SCC_TO_DPB_27_DN")
	)
	(segment
		(start 116.088922 -52.595272)
		(end 116.257578 -52.595272)
		(width 0.0889)
		(layer "In5.Cu")
		(net "PHY_SCC_TO_DPB_27_DN")
	)
	(segment
		(start 116.65204 -50.523902)
		(end 116.65204 -50.107596)
		(width 0.1016)
		(layer "In5.Cu")
		(net "PHY_SCC_TO_DPB_27_DN")
	)
	(segment
		(start 116.65204 -50.546)
		(end 116.65204 -50.523902)
		(width 0.0889)
		(layer "In5.Cu")
		(net "PHY_SCC_TO_DPB_27_DN")
	)
	(arc
		(start 112.252506 -10.8712)
		(mid 112.31656 -10.71656)
		(end 112.4712 -10.652506)
		(width 0.1016)
		(layer "In5.Cu")
		(net "PHY_SCC_TO_DPB_27_DN")
	)
	(arc
		(start 116.000022 -52.684172)
		(mid 116.02606 -52.62131)
		(end 116.088922 -52.595272)
		(width 0.0889)
		(layer "In5.Cu")
		(net "PHY_SCC_TO_DPB_27_DN")
	)
	(arc
		(start 116.257578 -52.595272)
		(mid 116.386412 -52.569845)
		(end 116.49583 -52.497228)
		(width 0.0889)
		(layer "In5.Cu")
		(net "PHY_SCC_TO_DPB_27_DN")
	)
	(arc
		(start 116.496338 -52.496466)
		(mid 116.569396 -52.386893)
		(end 116.59489 -52.257706)
		(width 0.0889)
		(layer "In5.Cu")
		(net "PHY_SCC_TO_DPB_27_DN")
	)
	(arc
		(start 112.820704 -10.652506)
		(mid 112.947505 -10.705029)
		(end 113.000028 -10.83183)
		(width 0.1016)
		(layer "In5.Cu")
		(net "PHY_SCC_TO_DPB_27_DN")
	)
	(segment
		(start 114.499898 -51.500024)
		(end 114.000026 -51.000152)
		(width 0.104902)
		(layer "F.Cu")
		(net "PHY_SCC_TO_DPB_26_DP")
	)
	(via
		(at 114.000026 -51.000152)
		(size 0.4572)
		(drill 0.2032)
		(layers "F.Cu" "B.Cu")
		(net "PHY_SCC_TO_DPB_26_DP")
	)
	(segment
		(start 114.356642 -50.563526)
		(end 114.356642 -50.541428)
		(width 0.0889)
		(layer "In5.Cu")
		(net "PHY_SCC_TO_DPB_26_DP")
	)
	(segment
		(start 117.06225 -45.703236)
		(end 117.239796 -45.449744)
		(width 0.1016)
		(layer "In5.Cu")
		(net "PHY_SCC_TO_DPB_26_DP")
	)
	(segment
		(start 110.671356 -11.547602)
		(end 111.02086 -11.547602)
		(width 0.1016)
		(layer "In5.Cu")
		(net "PHY_SCC_TO_DPB_26_DP")
	)
	(segment
		(start 114.088926 -51.404774)
		(end 114.283744 -51.404774)
		(width 0.0889)
		(layer "In5.Cu")
		(net "PHY_SCC_TO_DPB_26_DP")
	)
	(segment
		(start 111.200184 -11.368278)
		(end 111.200184 -10.999978)
		(width 0.1016)
		(layer "In5.Cu")
		(net "PHY_SCC_TO_DPB_26_DP")
	)
	(segment
		(start 117.239796 -43.317922)
		(end 115.795552 -41.09339)
		(width 0.1016)
		(layer "In5.Cu")
		(net "PHY_SCC_TO_DPB_26_DP")
	)
	(segment
		(start 110.147862 -14.531594)
		(end 110.147862 -12.071096)
		(width 0.1016)
		(layer "In5.Cu")
		(net "PHY_SCC_TO_DPB_26_DP")
	)
	(segment
		(start 117.32641 -43.527726)
		(end 117.30609 -43.41241)
		(width 0.1016)
		(layer "In5.Cu")
		(net "PHY_SCC_TO_DPB_26_DP")
	)
	(segment
		(start 115.795552 -41.09339)
		(end 110.147862 -14.531594)
		(width 0.1016)
		(layer "In5.Cu")
		(net "PHY_SCC_TO_DPB_26_DP")
	)
	(segment
		(start 117.346984 -43.64355)
		(end 117.33276 -43.564302)
		(width 0.1016)
		(layer "In5.Cu")
		(net "PHY_SCC_TO_DPB_26_DP")
	)
	(segment
		(start 117.293136 -45.146214)
		(end 117.346984 -44.841668)
		(width 0.1016)
		(layer "In5.Cu")
		(net "PHY_SCC_TO_DPB_26_DP")
	)
	(segment
		(start 117.30609 -43.41241)
		(end 117.239796 -43.317922)
		(width 0.1016)
		(layer "In5.Cu")
		(net "PHY_SCC_TO_DPB_26_DP")
	)
	(segment
		(start 114.356642 -49.868582)
		(end 117.06225 -45.703236)
		(width 0.1016)
		(layer "In5.Cu")
		(net "PHY_SCC_TO_DPB_26_DP")
	)
	(segment
		(start 117.241828 -45.437552)
		(end 117.293136 -45.146214)
		(width 0.1016)
		(layer "In5.Cu")
		(net "PHY_SCC_TO_DPB_26_DP")
	)
	(segment
		(start 114.413792 -50.620676)
		(end 114.356642 -50.563526)
		(width 0.0889)
		(layer "In5.Cu")
		(net "PHY_SCC_TO_DPB_26_DP")
	)
	(segment
		(start 117.33276 -43.564302)
		(end 117.32641 -43.527726)
		(width 0.1016)
		(layer "In5.Cu")
		(net "PHY_SCC_TO_DPB_26_DP")
	)
	(segment
		(start 114.413792 -51.274726)
		(end 114.413792 -50.620676)
		(width 0.0889)
		(layer "In5.Cu")
		(net "PHY_SCC_TO_DPB_26_DP")
	)
	(segment
		(start 117.239796 -45.449744)
		(end 117.241828 -45.437552)
		(width 0.1016)
		(layer "In5.Cu")
		(net "PHY_SCC_TO_DPB_26_DP")
	)
	(segment
		(start 114.000026 -51.000152)
		(end 114.000026 -51.315874)
		(width 0.0889)
		(layer "In5.Cu")
		(net "PHY_SCC_TO_DPB_26_DP")
	)
	(segment
		(start 114.356642 -50.541428)
		(end 114.356642 -49.868582)
		(width 0.1016)
		(layer "In5.Cu")
		(net "PHY_SCC_TO_DPB_26_DP")
	)
	(segment
		(start 117.346984 -44.841668)
		(end 117.346984 -43.64355)
		(width 0.1016)
		(layer "In5.Cu")
		(net "PHY_SCC_TO_DPB_26_DP")
	)
	(arc
		(start 114.283744 -51.404774)
		(mid 114.333511 -51.394875)
		(end 114.375692 -51.366674)
		(width 0.0889)
		(layer "In5.Cu")
		(net "PHY_SCC_TO_DPB_26_DP")
	)
	(arc
		(start 114.000026 -51.315874)
		(mid 114.026064 -51.378736)
		(end 114.088926 -51.404774)
		(width 0.0889)
		(layer "In5.Cu")
		(net "PHY_SCC_TO_DPB_26_DP")
	)
	(arc
		(start 114.375692 -51.366674)
		(mid 114.40388 -51.324488)
		(end 114.413792 -51.274726)
		(width 0.0889)
		(layer "In5.Cu")
		(net "PHY_SCC_TO_DPB_26_DP")
	)
	(arc
		(start 111.02086 -11.547602)
		(mid 111.147661 -11.495079)
		(end 111.200184 -11.368278)
		(width 0.1016)
		(layer "In5.Cu")
		(net "PHY_SCC_TO_DPB_26_DP")
	)
	(arc
		(start 110.147862 -12.071096)
		(mid 110.30119 -11.70093)
		(end 110.671356 -11.547602)
		(width 0.1016)
		(layer "In5.Cu")
		(net "PHY_SCC_TO_DPB_26_DP")
	)
	(segment
		(start 114.499898 -52.500022)
		(end 114.000026 -52.00015)
		(width 0.104902)
		(layer "F.Cu")
		(net "PHY_SCC_TO_DPB_26_DN")
	)
	(via
		(at 114.000026 -52.00015)
		(size 0.4572)
		(drill 0.2032)
		(layers "F.Cu" "B.Cu")
		(net "PHY_SCC_TO_DPB_26_DN")
	)
	(segment
		(start 114.604292 -51.274726)
		(end 114.604292 -50.620676)
		(width 0.0889)
		(layer "In5.Cu")
		(net "PHY_SCC_TO_DPB_26_DN")
	)
	(segment
		(start 117.651784 -43.61688)
		(end 117.594634 -43.292776)
		(width 0.1016)
		(layer "In5.Cu")
		(net "PHY_SCC_TO_DPB_26_DN")
	)
	(segment
		(start 110.671356 -11.852402)
		(end 111.02086 -11.852402)
		(width 0.1016)
		(layer "In5.Cu")
		(net "PHY_SCC_TO_DPB_26_DN")
	)
	(segment
		(start 117.315234 -45.873924)
		(end 117.52834 -45.569124)
		(width 0.1016)
		(layer "In5.Cu")
		(net "PHY_SCC_TO_DPB_26_DN")
	)
	(segment
		(start 114.827558 -49.703736)
		(end 115.090956 -49.647602)
		(width 0.1016)
		(layer "In5.Cu")
		(net "PHY_SCC_TO_DPB_26_DN")
	)
	(segment
		(start 115.200938 -49.128426)
		(end 115.200938 -49.128172)
		(width 0.1016)
		(layer "In5.Cu")
		(net "PHY_SCC_TO_DPB_26_DN")
	)
	(segment
		(start 116.082064 -40.974772)
		(end 110.452662 -14.499336)
		(width 0.1016)
		(layer "In5.Cu")
		(net "PHY_SCC_TO_DPB_26_DN")
	)
	(segment
		(start 117.492526 -43.147234)
		(end 116.082064 -40.974772)
		(width 0.1016)
		(layer "In5.Cu")
		(net "PHY_SCC_TO_DPB_26_DN")
	)
	(segment
		(start 114.000026 -52.00015)
		(end 114.000026 -51.684174)
		(width 0.0889)
		(layer "In5.Cu")
		(net "PHY_SCC_TO_DPB_26_DN")
	)
	(segment
		(start 110.452662 -14.499336)
		(end 110.452662 -12.071096)
		(width 0.1016)
		(layer "In5.Cu")
		(net "PHY_SCC_TO_DPB_26_DN")
	)
	(segment
		(start 114.088926 -51.595274)
		(end 114.283744 -51.595274)
		(width 0.0889)
		(layer "In5.Cu")
		(net "PHY_SCC_TO_DPB_26_DN")
	)
	(segment
		(start 115.257072 -49.392078)
		(end 115.200938 -49.128426)
		(width 0.1016)
		(layer "In5.Cu")
		(net "PHY_SCC_TO_DPB_26_DN")
	)
	(segment
		(start 114.661442 -49.95926)
		(end 114.827558 -49.703736)
		(width 0.1016)
		(layer "In5.Cu")
		(net "PHY_SCC_TO_DPB_26_DN")
	)
	(segment
		(start 111.200184 -12.031726)
		(end 111.200184 -12.400026)
		(width 0.1016)
		(layer "In5.Cu")
		(net "PHY_SCC_TO_DPB_26_DN")
	)
	(segment
		(start 117.52834 -45.569124)
		(end 117.651784 -44.868592)
		(width 0.1016)
		(layer "In5.Cu")
		(net "PHY_SCC_TO_DPB_26_DN")
	)
	(segment
		(start 114.661442 -50.563526)
		(end 114.661442 -50.541428)
		(width 0.0889)
		(layer "In5.Cu")
		(net "PHY_SCC_TO_DPB_26_DN")
	)
	(segment
		(start 115.090956 -49.647602)
		(end 115.257072 -49.392078)
		(width 0.1016)
		(layer "In5.Cu")
		(net "PHY_SCC_TO_DPB_26_DN")
	)
	(segment
		(start 114.661442 -50.541428)
		(end 114.661442 -49.95926)
		(width 0.1016)
		(layer "In5.Cu")
		(net "PHY_SCC_TO_DPB_26_DN")
	)
	(segment
		(start 117.651784 -44.868592)
		(end 117.651784 -43.61688)
		(width 0.1016)
		(layer "In5.Cu")
		(net "PHY_SCC_TO_DPB_26_DN")
	)
	(segment
		(start 117.594634 -43.292776)
		(end 117.492526 -43.147234)
		(width 0.1016)
		(layer "In5.Cu")
		(net "PHY_SCC_TO_DPB_26_DN")
	)
	(segment
		(start 115.200938 -49.128172)
		(end 117.315234 -45.873924)
		(width 0.1016)
		(layer "In5.Cu")
		(net "PHY_SCC_TO_DPB_26_DN")
	)
	(segment
		(start 114.604292 -50.620676)
		(end 114.661442 -50.563526)
		(width 0.0889)
		(layer "In5.Cu")
		(net "PHY_SCC_TO_DPB_26_DN")
	)
	(arc
		(start 114.000026 -51.684174)
		(mid 114.026064 -51.621312)
		(end 114.088926 -51.595274)
		(width 0.0889)
		(layer "In5.Cu")
		(net "PHY_SCC_TO_DPB_26_DN")
	)
	(arc
		(start 110.452662 -12.071096)
		(mid 110.516716 -11.916456)
		(end 110.671356 -11.852402)
		(width 0.1016)
		(layer "In5.Cu")
		(net "PHY_SCC_TO_DPB_26_DN")
	)
	(arc
		(start 111.02086 -11.852402)
		(mid 111.147661 -11.904925)
		(end 111.200184 -12.031726)
		(width 0.1016)
		(layer "In5.Cu")
		(net "PHY_SCC_TO_DPB_26_DN")
	)
	(arc
		(start 114.283744 -51.595274)
		(mid 114.406466 -51.570957)
		(end 114.510566 -51.501548)
		(width 0.0889)
		(layer "In5.Cu")
		(net "PHY_SCC_TO_DPB_26_DN")
	)
	(arc
		(start 114.510566 -51.501548)
		(mid 114.580018 -51.397466)
		(end 114.604292 -51.274726)
		(width 0.0889)
		(layer "In5.Cu")
		(net "PHY_SCC_TO_DPB_26_DN")
	)
	(segment
		(start 113.4999 -52.500022)
		(end 113.000028 -52.00015)
		(width 0.104902)
		(layer "F.Cu")
		(net "PHY_SCC_TO_DPB_25_DP")
	)
	(via
		(at 113.000028 -52.00015)
		(size 0.4572)
		(drill 0.2032)
		(layers "F.Cu" "B.Cu")
		(net "PHY_SCC_TO_DPB_25_DP")
	)
	(segment
		(start 113.347246 -50.523902)
		(end 113.347246 -49.651666)
		(width 0.1016)
		(layer "In5.Cu")
		(net "PHY_SCC_TO_DPB_25_DP")
	)
	(segment
		(start 115.742974 -45.379894)
		(end 115.822984 -44.92625)
		(width 0.1016)
		(layer "In5.Cu")
		(net "PHY_SCC_TO_DPB_25_DP")
	)
	(segment
		(start 113.404396 -52.2478)
		(end 113.404396 -50.60315)
		(width 0.0889)
		(layer "In5.Cu")
		(net "PHY_SCC_TO_DPB_25_DP")
	)
	(segment
		(start 115.717066 -45.509688)
		(end 115.742974 -45.379894)
		(width 0.1016)
		(layer "In5.Cu")
		(net "PHY_SCC_TO_DPB_25_DP")
	)
	(segment
		(start 115.784884 -43.343576)
		(end 114.305842 -41.232836)
		(width 0.1016)
		(layer "In5.Cu")
		(net "PHY_SCC_TO_DPB_25_DP")
	)
	(segment
		(start 109.400086 -10.168382)
		(end 109.400086 -9.800082)
		(width 0.1016)
		(layer "In5.Cu")
		(net "PHY_SCC_TO_DPB_25_DP")
	)
	(segment
		(start 113.404396 -50.60315)
		(end 113.347246 -50.546)
		(width 0.0889)
		(layer "In5.Cu")
		(net "PHY_SCC_TO_DPB_25_DP")
	)
	(segment
		(start 113.000028 -52.00015)
		(end 113.000028 -52.315872)
		(width 0.0889)
		(layer "In5.Cu")
		(net "PHY_SCC_TO_DPB_25_DP")
	)
	(segment
		(start 115.822984 -43.558968)
		(end 115.784884 -43.343576)
		(width 0.1016)
		(layer "In5.Cu")
		(net "PHY_SCC_TO_DPB_25_DP")
	)
	(segment
		(start 108.34751 -13.199872)
		(end 108.34751 -10.871454)
		(width 0.1016)
		(layer "In5.Cu")
		(net "PHY_SCC_TO_DPB_25_DP")
	)
	(segment
		(start 114.305842 -41.232836)
		(end 108.34751 -13.199872)
		(width 0.1016)
		(layer "In5.Cu")
		(net "PHY_SCC_TO_DPB_25_DP")
	)
	(segment
		(start 113.347246 -49.651666)
		(end 113.502694 -48.919638)
		(width 0.1016)
		(layer "In5.Cu")
		(net "PHY_SCC_TO_DPB_25_DP")
	)
	(segment
		(start 115.822984 -44.92625)
		(end 115.822984 -43.558968)
		(width 0.1016)
		(layer "In5.Cu")
		(net "PHY_SCC_TO_DPB_25_DP")
	)
	(segment
		(start 113.347246 -50.546)
		(end 113.347246 -50.523902)
		(width 0.0889)
		(layer "In5.Cu")
		(net "PHY_SCC_TO_DPB_25_DP")
	)
	(segment
		(start 108.871258 -10.347706)
		(end 109.220762 -10.347706)
		(width 0.1016)
		(layer "In5.Cu")
		(net "PHY_SCC_TO_DPB_25_DP")
	)
	(segment
		(start 113.088928 -52.404772)
		(end 113.247424 -52.404772)
		(width 0.0889)
		(layer "In5.Cu")
		(net "PHY_SCC_TO_DPB_25_DP")
	)
	(segment
		(start 113.502694 -48.919638)
		(end 115.717066 -45.509688)
		(width 0.1016)
		(layer "In5.Cu")
		(net "PHY_SCC_TO_DPB_25_DP")
	)
	(arc
		(start 109.220762 -10.347706)
		(mid 109.347563 -10.295183)
		(end 109.400086 -10.168382)
		(width 0.1016)
		(layer "In5.Cu")
		(net "PHY_SCC_TO_DPB_25_DP")
	)
	(arc
		(start 113.247424 -52.404772)
		(mid 113.307495 -52.392823)
		(end 113.358422 -52.358798)
		(width 0.0889)
		(layer "In5.Cu")
		(net "PHY_SCC_TO_DPB_25_DP")
	)
	(arc
		(start 113.000028 -52.315872)
		(mid 113.026066 -52.378734)
		(end 113.088928 -52.404772)
		(width 0.0889)
		(layer "In5.Cu")
		(net "PHY_SCC_TO_DPB_25_DP")
	)
	(arc
		(start 108.34751 -10.871454)
		(mid 108.500912 -10.501108)
		(end 108.871258 -10.347706)
		(width 0.1016)
		(layer "In5.Cu")
		(net "PHY_SCC_TO_DPB_25_DP")
	)
	(arc
		(start 113.358422 -52.358798)
		(mid 113.39245 -52.307872)
		(end 113.404396 -52.2478)
		(width 0.0889)
		(layer "In5.Cu")
		(net "PHY_SCC_TO_DPB_25_DP")
	)
	(segment
		(start 113.4999 -53.50002)
		(end 113.000028 -53.000148)
		(width 0.104902)
		(layer "F.Cu")
		(net "PHY_SCC_TO_DPB_25_DN")
	)
	(via
		(at 113.000028 -53.000148)
		(size 0.4572)
		(drill 0.2032)
		(layers "F.Cu" "B.Cu")
		(net "PHY_SCC_TO_DPB_25_DN")
	)
	(segment
		(start 113.594896 -50.60315)
		(end 113.652046 -50.546)
		(width 0.0889)
		(layer "In5.Cu")
		(net "PHY_SCC_TO_DPB_25_DN")
	)
	(segment
		(start 116.127784 -44.953174)
		(end 116.127784 -43.532298)
		(width 0.1016)
		(layer "In5.Cu")
		(net "PHY_SCC_TO_DPB_25_DN")
	)
	(segment
		(start 114.591338 -41.10863)
		(end 108.65231 -13.167614)
		(width 0.1016)
		(layer "In5.Cu")
		(net "PHY_SCC_TO_DPB_25_DN")
	)
	(segment
		(start 116.004594 -45.626782)
		(end 116.042694 -45.436282)
		(width 0.1016)
		(layer "In5.Cu")
		(net "PHY_SCC_TO_DPB_25_DN")
	)
	(segment
		(start 108.871258 -10.652506)
		(end 109.220762 -10.652506)
		(width 0.1016)
		(layer "In5.Cu")
		(net "PHY_SCC_TO_DPB_25_DN")
	)
	(segment
		(start 109.400086 -10.83183)
		(end 109.400086 -11.20013)
		(width 0.1016)
		(layer "In5.Cu")
		(net "PHY_SCC_TO_DPB_25_DN")
	)
	(segment
		(start 113.652046 -50.546)
		(end 113.652046 -50.523902)
		(width 0.0889)
		(layer "In5.Cu")
		(net "PHY_SCC_TO_DPB_25_DN")
	)
	(segment
		(start 113.652046 -50.523902)
		(end 113.652046 -49.683924)
		(width 0.1016)
		(layer "In5.Cu")
		(net "PHY_SCC_TO_DPB_25_DN")
	)
	(segment
		(start 115.025424 -47.484284)
		(end 115.19154 -47.228506)
		(width 0.1016)
		(layer "In5.Cu")
		(net "PHY_SCC_TO_DPB_25_DN")
	)
	(segment
		(start 113.000028 -53.000148)
		(end 113.000028 -52.684172)
		(width 0.0889)
		(layer "In5.Cu")
		(net "PHY_SCC_TO_DPB_25_DN")
	)
	(segment
		(start 116.073428 -43.223942)
		(end 114.591338 -41.10863)
		(width 0.1016)
		(layer "In5.Cu")
		(net "PHY_SCC_TO_DPB_25_DN")
	)
	(segment
		(start 115.19154 -47.228506)
		(end 115.135406 -46.965108)
		(width 0.1016)
		(layer "In5.Cu")
		(net "PHY_SCC_TO_DPB_25_DN")
	)
	(segment
		(start 113.789206 -49.038256)
		(end 114.762026 -47.540164)
		(width 0.1016)
		(layer "In5.Cu")
		(net "PHY_SCC_TO_DPB_25_DN")
	)
	(segment
		(start 116.127784 -43.532298)
		(end 116.073428 -43.223942)
		(width 0.1016)
		(layer "In5.Cu")
		(net "PHY_SCC_TO_DPB_25_DN")
	)
	(segment
		(start 113.594896 -52.2478)
		(end 113.594896 -50.60315)
		(width 0.0889)
		(layer "In5.Cu")
		(net "PHY_SCC_TO_DPB_25_DN")
	)
	(segment
		(start 113.088928 -52.595272)
		(end 113.247424 -52.595272)
		(width 0.0889)
		(layer "In5.Cu")
		(net "PHY_SCC_TO_DPB_25_DN")
	)
	(segment
		(start 108.65231 -13.167614)
		(end 108.65231 -10.871454)
		(width 0.1016)
		(layer "In5.Cu")
		(net "PHY_SCC_TO_DPB_25_DN")
	)
	(segment
		(start 114.762026 -47.540164)
		(end 115.025424 -47.484284)
		(width 0.1016)
		(layer "In5.Cu")
		(net "PHY_SCC_TO_DPB_25_DN")
	)
	(segment
		(start 116.042694 -45.436282)
		(end 116.127784 -44.953174)
		(width 0.1016)
		(layer "In5.Cu")
		(net "PHY_SCC_TO_DPB_25_DN")
	)
	(segment
		(start 113.652046 -49.683924)
		(end 113.789206 -49.038256)
		(width 0.1016)
		(layer "In5.Cu")
		(net "PHY_SCC_TO_DPB_25_DN")
	)
	(segment
		(start 115.135406 -46.965108)
		(end 116.004594 -45.626782)
		(width 0.1016)
		(layer "In5.Cu")
		(net "PHY_SCC_TO_DPB_25_DN")
	)
	(arc
		(start 113.493296 -52.493672)
		(mid 113.568535 -52.380836)
		(end 113.594896 -52.2478)
		(width 0.0889)
		(layer "In5.Cu")
		(net "PHY_SCC_TO_DPB_25_DN")
	)
	(arc
		(start 109.220762 -10.652506)
		(mid 109.347563 -10.705029)
		(end 109.400086 -10.83183)
		(width 0.1016)
		(layer "In5.Cu")
		(net "PHY_SCC_TO_DPB_25_DN")
	)
	(arc
		(start 113.000028 -52.684172)
		(mid 113.026066 -52.62131)
		(end 113.088928 -52.595272)
		(width 0.0889)
		(layer "In5.Cu")
		(net "PHY_SCC_TO_DPB_25_DN")
	)
	(arc
		(start 108.65231 -10.871454)
		(mid 108.716438 -10.716634)
		(end 108.871258 -10.652506)
		(width 0.1016)
		(layer "In5.Cu")
		(net "PHY_SCC_TO_DPB_25_DN")
	)
	(arc
		(start 113.247424 -52.595272)
		(mid 113.380464 -52.56892)
		(end 113.493296 -52.493672)
		(width 0.0889)
		(layer "In5.Cu")
		(net "PHY_SCC_TO_DPB_25_DN")
	)
	(segment
		(start 112.499902 -51.500024)
		(end 112.00003 -51.000152)
		(width 0.104902)
		(layer "F.Cu")
		(net "PHY_SCC_TO_DPB_24_DP")
	)
	(via
		(at 112.00003 -51.000152)
		(size 0.4572)
		(drill 0.2032)
		(layers "F.Cu" "B.Cu")
		(net "PHY_SCC_TO_DPB_24_DP")
	)
	(segment
		(start 114.298984 -43.551602)
		(end 114.257328 -43.315128)
		(width 0.1016)
		(layer "In5.Cu")
		(net "PHY_SCC_TO_DPB_24_DP")
	)
	(segment
		(start 112.351566 -49.549304)
		(end 112.724946 -47.792132)
		(width 0.1016)
		(layer "In5.Cu")
		(net "PHY_SCC_TO_DPB_24_DP")
	)
	(segment
		(start 114.072924 -45.716444)
		(end 114.198654 -45.536866)
		(width 0.1016)
		(layer "In5.Cu")
		(net "PHY_SCC_TO_DPB_24_DP")
	)
	(segment
		(start 114.257328 -43.315128)
		(end 113.36147 -42.020998)
		(width 0.1016)
		(layer "In5.Cu")
		(net "PHY_SCC_TO_DPB_24_DP")
	)
	(segment
		(start 112.351566 -50.541428)
		(end 112.351566 -49.549304)
		(width 0.1016)
		(layer "In5.Cu")
		(net "PHY_SCC_TO_DPB_24_DP")
	)
	(segment
		(start 112.00003 -51.000152)
		(end 112.00003 -51.315874)
		(width 0.0889)
		(layer "In5.Cu")
		(net "PHY_SCC_TO_DPB_24_DP")
	)
	(segment
		(start 107.07116 -11.547602)
		(end 107.420664 -11.547602)
		(width 0.1016)
		(layer "In5.Cu")
		(net "PHY_SCC_TO_DPB_24_DP")
	)
	(segment
		(start 113.36147 -42.020998)
		(end 108.574078 -19.491452)
		(width 0.1016)
		(layer "In5.Cu")
		(net "PHY_SCC_TO_DPB_24_DP")
	)
	(segment
		(start 107.15625 -17.308068)
		(end 106.547666 -14.445742)
		(width 0.1016)
		(layer "In5.Cu")
		(net "PHY_SCC_TO_DPB_24_DP")
	)
	(segment
		(start 107.599988 -11.368278)
		(end 107.599988 -10.999978)
		(width 0.1016)
		(layer "In5.Cu")
		(net "PHY_SCC_TO_DPB_24_DP")
	)
	(segment
		(start 112.351566 -50.563526)
		(end 112.351566 -50.541428)
		(width 0.0889)
		(layer "In5.Cu")
		(net "PHY_SCC_TO_DPB_24_DP")
	)
	(segment
		(start 112.08893 -51.404774)
		(end 112.277398 -51.404774)
		(width 0.0889)
		(layer "In5.Cu")
		(net "PHY_SCC_TO_DPB_24_DP")
	)
	(segment
		(start 114.198654 -45.536866)
		(end 114.298984 -44.967652)
		(width 0.1016)
		(layer "In5.Cu")
		(net "PHY_SCC_TO_DPB_24_DP")
	)
	(segment
		(start 112.408716 -50.620676)
		(end 112.351566 -50.563526)
		(width 0.0889)
		(layer "In5.Cu")
		(net "PHY_SCC_TO_DPB_24_DP")
	)
	(segment
		(start 106.547666 -14.445742)
		(end 106.547666 -12.071096)
		(width 0.1016)
		(layer "In5.Cu")
		(net "PHY_SCC_TO_DPB_24_DP")
	)
	(segment
		(start 108.574078 -19.491452)
		(end 107.895898 -18.447004)
		(width 0.1016)
		(layer "In5.Cu")
		(net "PHY_SCC_TO_DPB_24_DP")
	)
	(segment
		(start 112.724946 -47.792132)
		(end 114.072924 -45.716444)
		(width 0.1016)
		(layer "In5.Cu")
		(net "PHY_SCC_TO_DPB_24_DP")
	)
	(segment
		(start 112.408716 -51.27371)
		(end 112.408716 -50.620676)
		(width 0.0889)
		(layer "In5.Cu")
		(net "PHY_SCC_TO_DPB_24_DP")
	)
	(segment
		(start 107.895898 -18.447004)
		(end 107.15625 -17.308068)
		(width 0.1016)
		(layer "In5.Cu")
		(net "PHY_SCC_TO_DPB_24_DP")
	)
	(segment
		(start 114.298984 -44.967652)
		(end 114.298984 -43.551602)
		(width 0.1016)
		(layer "In5.Cu")
		(net "PHY_SCC_TO_DPB_24_DP")
	)
	(arc
		(start 106.547666 -12.071096)
		(mid 106.700994 -11.70093)
		(end 107.07116 -11.547602)
		(width 0.1016)
		(layer "In5.Cu")
		(net "PHY_SCC_TO_DPB_24_DP")
	)
	(arc
		(start 107.420664 -11.547602)
		(mid 107.547465 -11.495079)
		(end 107.599988 -11.368278)
		(width 0.1016)
		(layer "In5.Cu")
		(net "PHY_SCC_TO_DPB_24_DP")
	)
	(arc
		(start 112.277398 -51.404774)
		(mid 112.327734 -51.394744)
		(end 112.370362 -51.366166)
		(width 0.0889)
		(layer "In5.Cu")
		(net "PHY_SCC_TO_DPB_24_DP")
	)
	(arc
		(start 112.00003 -51.315874)
		(mid 112.026068 -51.378736)
		(end 112.08893 -51.404774)
		(width 0.0889)
		(layer "In5.Cu")
		(net "PHY_SCC_TO_DPB_24_DP")
	)
	(arc
		(start 112.370362 -51.366166)
		(mid 112.398681 -51.323733)
		(end 112.408716 -51.27371)
		(width 0.0889)
		(layer "In5.Cu")
		(net "PHY_SCC_TO_DPB_24_DP")
	)
	(segment
		(start 112.499902 -52.500022)
		(end 112.00003 -52.00015)
		(width 0.104902)
		(layer "F.Cu")
		(net "PHY_SCC_TO_DPB_24_DN")
	)
	(via
		(at 112.00003 -52.00015)
		(size 0.4572)
		(drill 0.2032)
		(layers "F.Cu" "B.Cu")
		(net "PHY_SCC_TO_DPB_24_DN")
	)
	(segment
		(start 114.325908 -45.887132)
		(end 114.487198 -45.656246)
		(width 0.1016)
		(layer "In5.Cu")
		(net "PHY_SCC_TO_DPB_24_DN")
	)
	(segment
		(start 107.07116 -11.852402)
		(end 107.420664 -11.852402)
		(width 0.1016)
		(layer "In5.Cu")
		(net "PHY_SCC_TO_DPB_24_DN")
	)
	(segment
		(start 112.504982 -51.501294)
		(end 112.50549 -51.500786)
		(width 0.0889)
		(layer "In5.Cu")
		(net "PHY_SCC_TO_DPB_24_DN")
	)
	(segment
		(start 107.442762 -17.18945)
		(end 106.852466 -14.413484)
		(width 0.1016)
		(layer "In5.Cu")
		(net "PHY_SCC_TO_DPB_24_DN")
	)
	(segment
		(start 112.00003 -52.00015)
		(end 112.00003 -51.684174)
		(width 0.0889)
		(layer "In5.Cu")
		(net "PHY_SCC_TO_DPB_24_DN")
	)
	(segment
		(start 113.440972 -47.599092)
		(end 113.607088 -47.343568)
		(width 0.1016)
		(layer "In5.Cu")
		(net "PHY_SCC_TO_DPB_24_DN")
	)
	(segment
		(start 113.551208 -47.08017)
		(end 114.325908 -45.887132)
		(width 0.1016)
		(layer "In5.Cu")
		(net "PHY_SCC_TO_DPB_24_DN")
	)
	(segment
		(start 113.607088 -47.343568)
		(end 113.551208 -47.08017)
		(width 0.1016)
		(layer "In5.Cu")
		(net "PHY_SCC_TO_DPB_24_DN")
	)
	(segment
		(start 108.86059 -19.372834)
		(end 107.442762 -17.18945)
		(width 0.1016)
		(layer "In5.Cu")
		(net "PHY_SCC_TO_DPB_24_DN")
	)
	(segment
		(start 114.603784 -43.524932)
		(end 114.546126 -43.19651)
		(width 0.1016)
		(layer "In5.Cu")
		(net "PHY_SCC_TO_DPB_24_DN")
	)
	(segment
		(start 114.603784 -44.994322)
		(end 114.603784 -43.524932)
		(width 0.1016)
		(layer "In5.Cu")
		(net "PHY_SCC_TO_DPB_24_DN")
	)
	(segment
		(start 112.656366 -50.541428)
		(end 112.656366 -49.581562)
		(width 0.1016)
		(layer "In5.Cu")
		(net "PHY_SCC_TO_DPB_24_DN")
	)
	(segment
		(start 113.011458 -47.91075)
		(end 113.177574 -47.655226)
		(width 0.1016)
		(layer "In5.Cu")
		(net "PHY_SCC_TO_DPB_24_DN")
	)
	(segment
		(start 113.177574 -47.655226)
		(end 113.440972 -47.599092)
		(width 0.1016)
		(layer "In5.Cu")
		(net "PHY_SCC_TO_DPB_24_DN")
	)
	(segment
		(start 112.599216 -51.27371)
		(end 112.599216 -50.620676)
		(width 0.0889)
		(layer "In5.Cu")
		(net "PHY_SCC_TO_DPB_24_DN")
	)
	(segment
		(start 112.599216 -50.620676)
		(end 112.656366 -50.563526)
		(width 0.0889)
		(layer "In5.Cu")
		(net "PHY_SCC_TO_DPB_24_DN")
	)
	(segment
		(start 114.487198 -45.656246)
		(end 114.603784 -44.994322)
		(width 0.1016)
		(layer "In5.Cu")
		(net "PHY_SCC_TO_DPB_24_DN")
	)
	(segment
		(start 113.646966 -41.897808)
		(end 108.86059 -19.372834)
		(width 0.1016)
		(layer "In5.Cu")
		(net "PHY_SCC_TO_DPB_24_DN")
	)
	(segment
		(start 106.852466 -14.413484)
		(end 106.852466 -12.071096)
		(width 0.1016)
		(layer "In5.Cu")
		(net "PHY_SCC_TO_DPB_24_DN")
	)
	(segment
		(start 114.546126 -43.19651)
		(end 113.646966 -41.897808)
		(width 0.1016)
		(layer "In5.Cu")
		(net "PHY_SCC_TO_DPB_24_DN")
	)
	(segment
		(start 112.08893 -51.595274)
		(end 112.277144 -51.595274)
		(width 0.0889)
		(layer "In5.Cu")
		(net "PHY_SCC_TO_DPB_24_DN")
	)
	(segment
		(start 107.599988 -12.031726)
		(end 107.599988 -12.400026)
		(width 0.1016)
		(layer "In5.Cu")
		(net "PHY_SCC_TO_DPB_24_DN")
	)
	(segment
		(start 112.656366 -50.563526)
		(end 112.656366 -50.541428)
		(width 0.0889)
		(layer "In5.Cu")
		(net "PHY_SCC_TO_DPB_24_DN")
	)
	(segment
		(start 112.656366 -49.581562)
		(end 113.011458 -47.91075)
		(width 0.1016)
		(layer "In5.Cu")
		(net "PHY_SCC_TO_DPB_24_DN")
	)
	(arc
		(start 112.277144 -51.595274)
		(mid 112.400406 -51.570943)
		(end 112.504982 -51.501294)
		(width 0.0889)
		(layer "In5.Cu")
		(net "PHY_SCC_TO_DPB_24_DN")
	)
	(arc
		(start 112.50549 -51.500786)
		(mid 112.574889 -51.396546)
		(end 112.599216 -51.27371)
		(width 0.0889)
		(layer "In5.Cu")
		(net "PHY_SCC_TO_DPB_24_DN")
	)
	(arc
		(start 107.420664 -11.852402)
		(mid 107.547465 -11.904925)
		(end 107.599988 -12.031726)
		(width 0.1016)
		(layer "In5.Cu")
		(net "PHY_SCC_TO_DPB_24_DN")
	)
	(arc
		(start 106.852466 -12.071096)
		(mid 106.91652 -11.916456)
		(end 107.07116 -11.852402)
		(width 0.1016)
		(layer "In5.Cu")
		(net "PHY_SCC_TO_DPB_24_DN")
	)
	(arc
		(start 112.00003 -51.684174)
		(mid 112.026068 -51.621312)
		(end 112.08893 -51.595274)
		(width 0.0889)
		(layer "In5.Cu")
		(net "PHY_SCC_TO_DPB_24_DN")
	)
	(segment
		(start 111.499904 -52.500022)
		(end 111.000032 -52.00015)
		(width 0.104902)
		(layer "F.Cu")
		(net "PHY_SCC_TO_DPB_23_DP")
	)
	(via
		(at 111.000032 -52.00015)
		(size 0.4572)
		(drill 0.2032)
		(layers "F.Cu" "B.Cu")
		(net "PHY_SCC_TO_DPB_23_DP")
	)
	(segment
		(start 107.660186 -20.042632)
		(end 105.454958 -16.647414)
		(width 0.1016)
		(layer "In5.Cu")
		(net "PHY_SCC_TO_DPB_23_DP")
	)
	(segment
		(start 111.088932 -52.404772)
		(end 111.268256 -52.404772)
		(width 0.0889)
		(layer "In5.Cu")
		(net "PHY_SCC_TO_DPB_23_DP")
	)
	(segment
		(start 112.774984 -43.601386)
		(end 112.710722 -43.238674)
		(width 0.1016)
		(layer "In5.Cu")
		(net "PHY_SCC_TO_DPB_23_DP")
	)
	(segment
		(start 111.891318 -47.024544)
		(end 112.495584 -46.094396)
		(width 0.1016)
		(layer "In5.Cu")
		(net "PHY_SCC_TO_DPB_23_DP")
	)
	(segment
		(start 111.4044 -50.60315)
		(end 111.34725 -50.546)
		(width 0.0889)
		(layer "In5.Cu")
		(net "PHY_SCC_TO_DPB_23_DP")
	)
	(segment
		(start 104.747568 -13.320014)
		(end 104.747568 -10.871454)
		(width 0.1016)
		(layer "In5.Cu")
		(net "PHY_SCC_TO_DPB_23_DP")
	)
	(segment
		(start 111.000032 -52.00015)
		(end 111.000032 -52.315872)
		(width 0.0889)
		(layer "In5.Cu")
		(net "PHY_SCC_TO_DPB_23_DP")
	)
	(segment
		(start 112.53597 -42.988484)
		(end 107.660186 -20.042632)
		(width 0.1016)
		(layer "In5.Cu")
		(net "PHY_SCC_TO_DPB_23_DP")
	)
	(segment
		(start 112.710722 -43.238674)
		(end 112.53597 -42.988484)
		(width 0.1016)
		(layer "In5.Cu")
		(net "PHY_SCC_TO_DPB_23_DP")
	)
	(segment
		(start 111.34725 -50.546)
		(end 111.34725 -50.523902)
		(width 0.0889)
		(layer "In5.Cu")
		(net "PHY_SCC_TO_DPB_23_DP")
	)
	(segment
		(start 111.34725 -49.58334)
		(end 111.891318 -47.024544)
		(width 0.1016)
		(layer "In5.Cu")
		(net "PHY_SCC_TO_DPB_23_DP")
	)
	(segment
		(start 111.34725 -50.523902)
		(end 111.34725 -49.58334)
		(width 0.1016)
		(layer "In5.Cu")
		(net "PHY_SCC_TO_DPB_23_DP")
	)
	(segment
		(start 105.271316 -10.347706)
		(end 105.62082 -10.347706)
		(width 0.1016)
		(layer "In5.Cu")
		(net "PHY_SCC_TO_DPB_23_DP")
	)
	(segment
		(start 112.774984 -44.77258)
		(end 112.774984 -43.601386)
		(width 0.1016)
		(layer "In5.Cu")
		(net "PHY_SCC_TO_DPB_23_DP")
	)
	(segment
		(start 105.800144 -10.168382)
		(end 105.800144 -9.800082)
		(width 0.1016)
		(layer "In5.Cu")
		(net "PHY_SCC_TO_DPB_23_DP")
	)
	(segment
		(start 105.454958 -16.647414)
		(end 104.747568 -13.320014)
		(width 0.1016)
		(layer "In5.Cu")
		(net "PHY_SCC_TO_DPB_23_DP")
	)
	(segment
		(start 111.4044 -52.268628)
		(end 111.4044 -50.60315)
		(width 0.0889)
		(layer "In5.Cu")
		(net "PHY_SCC_TO_DPB_23_DP")
	)
	(segment
		(start 112.495584 -46.094396)
		(end 112.774984 -44.77258)
		(width 0.1016)
		(layer "In5.Cu")
		(net "PHY_SCC_TO_DPB_23_DP")
	)
	(arc
		(start 111.000032 -52.315872)
		(mid 111.02607 -52.378734)
		(end 111.088932 -52.404772)
		(width 0.0889)
		(layer "In5.Cu")
		(net "PHY_SCC_TO_DPB_23_DP")
	)
	(arc
		(start 111.364522 -52.364894)
		(mid 111.394034 -52.320727)
		(end 111.4044 -52.268628)
		(width 0.0889)
		(layer "In5.Cu")
		(net "PHY_SCC_TO_DPB_23_DP")
	)
	(arc
		(start 105.62082 -10.347706)
		(mid 105.747621 -10.295183)
		(end 105.800144 -10.168382)
		(width 0.1016)
		(layer "In5.Cu")
		(net "PHY_SCC_TO_DPB_23_DP")
	)
	(arc
		(start 111.268256 -52.404772)
		(mid 111.320356 -52.394409)
		(end 111.364522 -52.364894)
		(width 0.0889)
		(layer "In5.Cu")
		(net "PHY_SCC_TO_DPB_23_DP")
	)
	(arc
		(start 104.747568 -10.871454)
		(mid 104.90097 -10.501108)
		(end 105.271316 -10.347706)
		(width 0.1016)
		(layer "In5.Cu")
		(net "PHY_SCC_TO_DPB_23_DP")
	)
	(segment
		(start 111.499904 -53.50002)
		(end 111.000032 -53.000148)
		(width 0.104902)
		(layer "F.Cu")
		(net "PHY_SCC_TO_DPB_23_DN")
	)
	(via
		(at 111.000032 -53.000148)
		(size 0.4572)
		(drill 0.2032)
		(layers "F.Cu" "B.Cu")
		(net "PHY_SCC_TO_DPB_23_DN")
	)
	(segment
		(start 113.079784 -43.574462)
		(end 112.999266 -43.11904)
		(width 0.1016)
		(layer "In5.Cu")
		(net "PHY_SCC_TO_DPB_23_DN")
	)
	(segment
		(start 111.65205 -49.615598)
		(end 112.17783 -47.143416)
		(width 0.1016)
		(layer "In5.Cu")
		(net "PHY_SCC_TO_DPB_23_DN")
	)
	(segment
		(start 111.000032 -53.000148)
		(end 111.000032 -52.684172)
		(width 0.0889)
		(layer "In5.Cu")
		(net "PHY_SCC_TO_DPB_23_DN")
	)
	(segment
		(start 111.5949 -50.60315)
		(end 111.65205 -50.546)
		(width 0.0889)
		(layer "In5.Cu")
		(net "PHY_SCC_TO_DPB_23_DN")
	)
	(segment
		(start 112.95126 -43.05046)
		(end 112.821466 -42.864532)
		(width 0.1016)
		(layer "In5.Cu")
		(net "PHY_SCC_TO_DPB_23_DN")
	)
	(segment
		(start 112.999266 -43.11904)
		(end 112.95126 -43.05046)
		(width 0.1016)
		(layer "In5.Cu")
		(net "PHY_SCC_TO_DPB_23_DN")
	)
	(segment
		(start 107.946698 -19.924014)
		(end 105.74147 -16.528796)
		(width 0.1016)
		(layer "In5.Cu")
		(net "PHY_SCC_TO_DPB_23_DN")
	)
	(segment
		(start 113.079784 -44.806616)
		(end 113.079784 -43.574462)
		(width 0.1016)
		(layer "In5.Cu")
		(net "PHY_SCC_TO_DPB_23_DN")
	)
	(segment
		(start 105.800144 -10.83183)
		(end 105.800144 -11.20013)
		(width 0.1016)
		(layer "In5.Cu")
		(net "PHY_SCC_TO_DPB_23_DN")
	)
	(segment
		(start 112.816894 -42.842688)
		(end 112.81664 -42.842688)
		(width 0.1016)
		(layer "In5.Cu")
		(net "PHY_SCC_TO_DPB_23_DN")
	)
	(segment
		(start 112.96777 -45.340016)
		(end 113.079784 -44.806616)
		(width 0.1016)
		(layer "In5.Cu")
		(net "PHY_SCC_TO_DPB_23_DN")
	)
	(segment
		(start 111.088932 -52.595272)
		(end 111.268256 -52.595272)
		(width 0.0889)
		(layer "In5.Cu")
		(net "PHY_SCC_TO_DPB_23_DN")
	)
	(segment
		(start 113.051082 -45.863764)
		(end 113.114328 -45.565822)
		(width 0.1016)
		(layer "In5.Cu")
		(net "PHY_SCC_TO_DPB_23_DN")
	)
	(segment
		(start 105.397046 -14.90853)
		(end 105.052368 -13.287756)
		(width 0.1016)
		(layer "In5.Cu")
		(net "PHY_SCC_TO_DPB_23_DN")
	)
	(segment
		(start 112.81664 -42.842688)
		(end 107.946698 -19.924014)
		(width 0.1016)
		(layer "In5.Cu")
		(net "PHY_SCC_TO_DPB_23_DN")
	)
	(segment
		(start 112.17783 -47.143416)
		(end 112.782096 -46.213014)
		(width 0.1016)
		(layer "In5.Cu")
		(net "PHY_SCC_TO_DPB_23_DN")
	)
	(segment
		(start 111.65205 -50.523902)
		(end 111.65205 -49.615598)
		(width 0.1016)
		(layer "In5.Cu")
		(net "PHY_SCC_TO_DPB_23_DN")
	)
	(segment
		(start 112.825022 -46.010576)
		(end 113.051082 -45.863764)
		(width 0.1016)
		(layer "In5.Cu")
		(net "PHY_SCC_TO_DPB_23_DN")
	)
	(segment
		(start 112.821466 -42.864532)
		(end 112.816894 -42.842688)
		(width 0.1016)
		(layer "In5.Cu")
		(net "PHY_SCC_TO_DPB_23_DN")
	)
	(segment
		(start 105.271316 -10.652506)
		(end 105.62082 -10.652506)
		(width 0.1016)
		(layer "In5.Cu")
		(net "PHY_SCC_TO_DPB_23_DN")
	)
	(segment
		(start 105.052368 -13.287756)
		(end 105.052368 -10.871454)
		(width 0.1016)
		(layer "In5.Cu")
		(net "PHY_SCC_TO_DPB_23_DN")
	)
	(segment
		(start 111.65205 -50.546)
		(end 111.65205 -50.523902)
		(width 0.0889)
		(layer "In5.Cu")
		(net "PHY_SCC_TO_DPB_23_DN")
	)
	(segment
		(start 113.114328 -45.565822)
		(end 112.96777 -45.340016)
		(width 0.1016)
		(layer "In5.Cu")
		(net "PHY_SCC_TO_DPB_23_DN")
	)
	(segment
		(start 112.782096 -46.213014)
		(end 112.825022 -46.010576)
		(width 0.1016)
		(layer "In5.Cu")
		(net "PHY_SCC_TO_DPB_23_DN")
	)
	(segment
		(start 105.74147 -16.528796)
		(end 105.397046 -14.90853)
		(width 0.1016)
		(layer "In5.Cu")
		(net "PHY_SCC_TO_DPB_23_DN")
	)
	(segment
		(start 111.5949 -52.268628)
		(end 111.5949 -50.60315)
		(width 0.0889)
		(layer "In5.Cu")
		(net "PHY_SCC_TO_DPB_23_DN")
	)
	(arc
		(start 105.052368 -10.871454)
		(mid 105.116496 -10.716634)
		(end 105.271316 -10.652506)
		(width 0.1016)
		(layer "In5.Cu")
		(net "PHY_SCC_TO_DPB_23_DN")
	)
	(arc
		(start 111.268256 -52.595272)
		(mid 111.393311 -52.570491)
		(end 111.499396 -52.499768)
		(width 0.0889)
		(layer "In5.Cu")
		(net "PHY_SCC_TO_DPB_23_DN")
	)
	(arc
		(start 111.499396 -52.499768)
		(mid 111.570172 -52.393705)
		(end 111.5949 -52.268628)
		(width 0.0889)
		(layer "In5.Cu")
		(net "PHY_SCC_TO_DPB_23_DN")
	)
	(arc
		(start 111.000032 -52.684172)
		(mid 111.02607 -52.62131)
		(end 111.088932 -52.595272)
		(width 0.0889)
		(layer "In5.Cu")
		(net "PHY_SCC_TO_DPB_23_DN")
	)
	(arc
		(start 105.62082 -10.652506)
		(mid 105.747621 -10.705029)
		(end 105.800144 -10.83183)
		(width 0.1016)
		(layer "In5.Cu")
		(net "PHY_SCC_TO_DPB_23_DN")
	)
	(segment
		(start 110.499906 -51.500024)
		(end 110.000034 -51.000152)
		(width 0.104902)
		(layer "F.Cu")
		(net "PHY_SCC_TO_DPB_22_DP")
	)
	(via
		(at 110.000034 -51.000152)
		(size 0.4572)
		(drill 0.2032)
		(layers "F.Cu" "B.Cu")
		(net "PHY_SCC_TO_DPB_22_DP")
	)
	(segment
		(start 110.40872 -50.620676)
		(end 110.35157 -50.563526)
		(width 0.0889)
		(layer "In5.Cu")
		(net "PHY_SCC_TO_DPB_22_DP")
	)
	(segment
		(start 111.250984 -45.317664)
		(end 111.250984 -43.67403)
		(width 0.1016)
		(layer "In5.Cu")
		(net "PHY_SCC_TO_DPB_22_DP")
	)
	(segment
		(start 110.000034 -51.000152)
		(end 110.000034 -51.315874)
		(width 0.0889)
		(layer "In5.Cu")
		(net "PHY_SCC_TO_DPB_22_DP")
	)
	(segment
		(start 106.670602 -20.477734)
		(end 103.363014 -15.385034)
		(width 0.1016)
		(layer "In5.Cu")
		(net "PHY_SCC_TO_DPB_22_DP")
	)
	(segment
		(start 110.35157 -50.563526)
		(end 110.35157 -50.541428)
		(width 0.0889)
		(layer "In5.Cu")
		(net "PHY_SCC_TO_DPB_22_DP")
	)
	(segment
		(start 103.471218 -11.547602)
		(end 103.820722 -11.547602)
		(width 0.1016)
		(layer "In5.Cu")
		(net "PHY_SCC_TO_DPB_22_DP")
	)
	(segment
		(start 103.363014 -15.385034)
		(end 102.947724 -13.431266)
		(width 0.1016)
		(layer "In5.Cu")
		(net "PHY_SCC_TO_DPB_22_DP")
	)
	(segment
		(start 110.35157 -49.63541)
		(end 111.25073 -45.406818)
		(width 0.1016)
		(layer "In5.Cu")
		(net "PHY_SCC_TO_DPB_22_DP")
	)
	(segment
		(start 110.35157 -50.541428)
		(end 110.35157 -49.63541)
		(width 0.1016)
		(layer "In5.Cu")
		(net "PHY_SCC_TO_DPB_22_DP")
	)
	(segment
		(start 110.604046 -40.006778)
		(end 110.712504 -39.497)
		(width 0.1016)
		(layer "In5.Cu")
		(net "PHY_SCC_TO_DPB_22_DP")
	)
	(segment
		(start 111.250984 -43.67403)
		(end 110.604046 -40.006778)
		(width 0.1016)
		(layer "In5.Cu")
		(net "PHY_SCC_TO_DPB_22_DP")
	)
	(segment
		(start 102.947724 -13.431266)
		(end 102.947724 -12.071096)
		(width 0.1016)
		(layer "In5.Cu")
		(net "PHY_SCC_TO_DPB_22_DP")
	)
	(segment
		(start 110.088934 -51.404774)
		(end 110.303818 -51.404774)
		(width 0.0889)
		(layer "In5.Cu")
		(net "PHY_SCC_TO_DPB_22_DP")
	)
	(segment
		(start 104.000046 -11.368278)
		(end 104.000046 -10.999978)
		(width 0.1016)
		(layer "In5.Cu")
		(net "PHY_SCC_TO_DPB_22_DP")
	)
	(segment
		(start 111.25073 -45.406818)
		(end 111.250984 -45.317664)
		(width 0.1016)
		(layer "In5.Cu")
		(net "PHY_SCC_TO_DPB_22_DP")
	)
	(segment
		(start 110.40872 -51.299872)
		(end 110.40872 -50.620676)
		(width 0.0889)
		(layer "In5.Cu")
		(net "PHY_SCC_TO_DPB_22_DP")
	)
	(segment
		(start 110.712504 -39.497)
		(end 106.670602 -20.477734)
		(width 0.1016)
		(layer "In5.Cu")
		(net "PHY_SCC_TO_DPB_22_DP")
	)
	(arc
		(start 102.947724 -12.071096)
		(mid 103.101052 -11.70093)
		(end 103.471218 -11.547602)
		(width 0.1016)
		(layer "In5.Cu")
		(net "PHY_SCC_TO_DPB_22_DP")
	)
	(arc
		(start 103.820722 -11.547602)
		(mid 103.947523 -11.495079)
		(end 104.000046 -11.368278)
		(width 0.1016)
		(layer "In5.Cu")
		(net "PHY_SCC_TO_DPB_22_DP")
	)
	(arc
		(start 110.303818 -51.404774)
		(mid 110.343962 -51.396789)
		(end 110.377986 -51.37404)
		(width 0.0889)
		(layer "In5.Cu")
		(net "PHY_SCC_TO_DPB_22_DP")
	)
	(arc
		(start 110.377986 -51.37404)
		(mid 110.400723 -51.340011)
		(end 110.40872 -51.299872)
		(width 0.0889)
		(layer "In5.Cu")
		(net "PHY_SCC_TO_DPB_22_DP")
	)
	(arc
		(start 110.000034 -51.315874)
		(mid 110.026072 -51.378736)
		(end 110.088934 -51.404774)
		(width 0.0889)
		(layer "In5.Cu")
		(net "PHY_SCC_TO_DPB_22_DP")
	)
	(segment
		(start 110.499906 -52.500022)
		(end 110.000034 -52.00015)
		(width 0.104902)
		(layer "F.Cu")
		(net "PHY_SCC_TO_DPB_22_DN")
	)
	(via
		(at 110.000034 -52.00015)
		(size 0.4572)
		(drill 0.2032)
		(layers "F.Cu" "B.Cu")
		(net "PHY_SCC_TO_DPB_22_DN")
	)
	(segment
		(start 110.59922 -50.620676)
		(end 110.65637 -50.563526)
		(width 0.0889)
		(layer "In5.Cu")
		(net "PHY_SCC_TO_DPB_22_DN")
	)
	(segment
		(start 104.000046 -12.031726)
		(end 104.000046 -12.400026)
		(width 0.1016)
		(layer "In5.Cu")
		(net "PHY_SCC_TO_DPB_22_DN")
	)
	(segment
		(start 110.914688 -40.012112)
		(end 110.928658 -39.946326)
		(width 0.1016)
		(layer "In5.Cu")
		(net "PHY_SCC_TO_DPB_22_DN")
	)
	(segment
		(start 110.65637 -49.667668)
		(end 111.241078 -46.918626)
		(width 0.1016)
		(layer "In5.Cu")
		(net "PHY_SCC_TO_DPB_22_DN")
	)
	(segment
		(start 110.65637 -50.563526)
		(end 110.65637 -50.541428)
		(width 0.0889)
		(layer "In5.Cu")
		(net "PHY_SCC_TO_DPB_22_DN")
	)
	(segment
		(start 106.957114 -20.359116)
		(end 103.649526 -15.266416)
		(width 0.1016)
		(layer "In5.Cu")
		(net "PHY_SCC_TO_DPB_22_DN")
	)
	(segment
		(start 110.59922 -51.299872)
		(end 110.59922 -50.620676)
		(width 0.0889)
		(layer "In5.Cu")
		(net "PHY_SCC_TO_DPB_22_DN")
	)
	(segment
		(start 111.555784 -43.647106)
		(end 110.914688 -40.012112)
		(width 0.1016)
		(layer "In5.Cu")
		(net "PHY_SCC_TO_DPB_22_DN")
	)
	(segment
		(start 111.466376 -45.858938)
		(end 111.55553 -45.43933)
		(width 0.1016)
		(layer "In5.Cu")
		(net "PHY_SCC_TO_DPB_22_DN")
	)
	(segment
		(start 111.466376 -45.859192)
		(end 111.466376 -45.858938)
		(width 0.1016)
		(layer "In5.Cu")
		(net "PHY_SCC_TO_DPB_22_DN")
	)
	(segment
		(start 111.383572 -46.247812)
		(end 111.466376 -45.859192)
		(width 0.1016)
		(layer "In5.Cu")
		(net "PHY_SCC_TO_DPB_22_DN")
	)
	(segment
		(start 111.024162 -39.497)
		(end 106.957114 -20.359116)
		(width 0.1016)
		(layer "In5.Cu")
		(net "PHY_SCC_TO_DPB_22_DN")
	)
	(segment
		(start 103.649526 -15.266416)
		(end 103.252524 -13.399008)
		(width 0.1016)
		(layer "In5.Cu")
		(net "PHY_SCC_TO_DPB_22_DN")
	)
	(segment
		(start 103.252524 -13.399008)
		(end 103.252524 -12.071096)
		(width 0.1016)
		(layer "In5.Cu")
		(net "PHY_SCC_TO_DPB_22_DN")
	)
	(segment
		(start 110.000034 -52.00015)
		(end 110.000034 -51.684174)
		(width 0.0889)
		(layer "In5.Cu")
		(net "PHY_SCC_TO_DPB_22_DN")
	)
	(segment
		(start 111.466884 -46.771814)
		(end 111.530384 -46.473618)
		(width 0.1016)
		(layer "In5.Cu")
		(net "PHY_SCC_TO_DPB_22_DN")
	)
	(segment
		(start 111.530384 -46.473618)
		(end 111.383572 -46.247812)
		(width 0.1016)
		(layer "In5.Cu")
		(net "PHY_SCC_TO_DPB_22_DN")
	)
	(segment
		(start 110.928658 -39.946326)
		(end 111.024162 -39.497)
		(width 0.1016)
		(layer "In5.Cu")
		(net "PHY_SCC_TO_DPB_22_DN")
	)
	(segment
		(start 111.55553 -45.43933)
		(end 111.555784 -45.318172)
		(width 0.1016)
		(layer "In5.Cu")
		(net "PHY_SCC_TO_DPB_22_DN")
	)
	(segment
		(start 111.241078 -46.918626)
		(end 111.466884 -46.771814)
		(width 0.1016)
		(layer "In5.Cu")
		(net "PHY_SCC_TO_DPB_22_DN")
	)
	(segment
		(start 110.088934 -51.595274)
		(end 110.303818 -51.595274)
		(width 0.0889)
		(layer "In5.Cu")
		(net "PHY_SCC_TO_DPB_22_DN")
	)
	(segment
		(start 103.471218 -11.852402)
		(end 103.820722 -11.852402)
		(width 0.1016)
		(layer "In5.Cu")
		(net "PHY_SCC_TO_DPB_22_DN")
	)
	(segment
		(start 111.555784 -45.318172)
		(end 111.555784 -43.647106)
		(width 0.1016)
		(layer "In5.Cu")
		(net "PHY_SCC_TO_DPB_22_DN")
	)
	(segment
		(start 110.65637 -50.541428)
		(end 110.65637 -49.667668)
		(width 0.1016)
		(layer "In5.Cu")
		(net "PHY_SCC_TO_DPB_22_DN")
	)
	(arc
		(start 103.252524 -12.071096)
		(mid 103.316578 -11.916456)
		(end 103.471218 -11.852402)
		(width 0.1016)
		(layer "In5.Cu")
		(net "PHY_SCC_TO_DPB_22_DN")
	)
	(arc
		(start 110.51286 -51.508914)
		(mid 110.576862 -51.41299)
		(end 110.59922 -51.299872)
		(width 0.0889)
		(layer "In5.Cu")
		(net "PHY_SCC_TO_DPB_22_DN")
	)
	(arc
		(start 110.000034 -51.684174)
		(mid 110.026072 -51.621312)
		(end 110.088934 -51.595274)
		(width 0.0889)
		(layer "In5.Cu")
		(net "PHY_SCC_TO_DPB_22_DN")
	)
	(arc
		(start 103.820722 -11.852402)
		(mid 103.947523 -11.904925)
		(end 104.000046 -12.031726)
		(width 0.1016)
		(layer "In5.Cu")
		(net "PHY_SCC_TO_DPB_22_DN")
	)
	(arc
		(start 110.303818 -51.595274)
		(mid 110.416917 -51.572871)
		(end 110.51286 -51.508914)
		(width 0.0889)
		(layer "In5.Cu")
		(net "PHY_SCC_TO_DPB_22_DN")
	)
	(segment
		(start 109.499908 -52.500022)
		(end 109.000036 -52.00015)
		(width 0.104902)
		(layer "F.Cu")
		(net "PHY_SCC_TO_DPB_21_DP")
	)
	(via
		(at 109.000036 -52.00015)
		(size 0.4572)
		(drill 0.2032)
		(layers "F.Cu" "B.Cu")
		(net "PHY_SCC_TO_DPB_21_DP")
	)
	(segment
		(start 109.088936 -52.404772)
		(end 109.307122 -52.404772)
		(width 0.0889)
		(layer "In5.Cu")
		(net "PHY_SCC_TO_DPB_21_DP")
	)
	(segment
		(start 109.989366 -46.527466)
		(end 109.858048 -45.782484)
		(width 0.1016)
		(layer "In5.Cu")
		(net "PHY_SCC_TO_DPB_21_DP")
	)
	(segment
		(start 109.347254 -50.546)
		(end 109.347254 -50.523902)
		(width 0.0889)
		(layer "In5.Cu")
		(net "PHY_SCC_TO_DPB_21_DP")
	)
	(segment
		(start 109.726984 -45.037502)
		(end 109.726984 -43.560238)
		(width 0.1016)
		(layer "In5.Cu")
		(net "PHY_SCC_TO_DPB_21_DP")
	)
	(segment
		(start 109.000036 -52.00015)
		(end 109.000036 -52.315872)
		(width 0.0889)
		(layer "In5.Cu")
		(net "PHY_SCC_TO_DPB_21_DP")
	)
	(segment
		(start 101.147626 -13.31849)
		(end 101.147626 -10.871454)
		(width 0.1016)
		(layer "In5.Cu")
		(net "PHY_SCC_TO_DPB_21_DP")
	)
	(segment
		(start 101.341428 -14.230604)
		(end 101.147626 -13.31849)
		(width 0.1016)
		(layer "In5.Cu")
		(net "PHY_SCC_TO_DPB_21_DP")
	)
	(segment
		(start 109.347254 -49.548288)
		(end 109.989366 -46.527466)
		(width 0.1016)
		(layer "In5.Cu")
		(net "PHY_SCC_TO_DPB_21_DP")
	)
	(segment
		(start 109.404404 -52.307236)
		(end 109.404404 -50.60315)
		(width 0.0889)
		(layer "In5.Cu")
		(net "PHY_SCC_TO_DPB_21_DP")
	)
	(segment
		(start 109.858048 -45.78223)
		(end 109.726984 -45.037502)
		(width 0.1016)
		(layer "In5.Cu")
		(net "PHY_SCC_TO_DPB_21_DP")
	)
	(segment
		(start 109.404404 -50.60315)
		(end 109.347254 -50.546)
		(width 0.0889)
		(layer "In5.Cu")
		(net "PHY_SCC_TO_DPB_21_DP")
	)
	(segment
		(start 101.372162 -14.277848)
		(end 101.341428 -14.230604)
		(width 0.1016)
		(layer "In5.Cu")
		(net "PHY_SCC_TO_DPB_21_DP")
	)
	(segment
		(start 109.726984 -43.560238)
		(end 109.139482 -40.248332)
		(width 0.1016)
		(layer "In5.Cu")
		(net "PHY_SCC_TO_DPB_21_DP")
	)
	(segment
		(start 105.485692 -20.611846)
		(end 101.372162 -14.277848)
		(width 0.1016)
		(layer "In5.Cu")
		(net "PHY_SCC_TO_DPB_21_DP")
	)
	(segment
		(start 109.139482 -40.248332)
		(end 109.398816 -39.0271)
		(width 0.1016)
		(layer "In5.Cu")
		(net "PHY_SCC_TO_DPB_21_DP")
	)
	(segment
		(start 109.347254 -50.523902)
		(end 109.347254 -49.548288)
		(width 0.1016)
		(layer "In5.Cu")
		(net "PHY_SCC_TO_DPB_21_DP")
	)
	(segment
		(start 101.671374 -10.347706)
		(end 102.020878 -10.347706)
		(width 0.1016)
		(layer "In5.Cu")
		(net "PHY_SCC_TO_DPB_21_DP")
	)
	(segment
		(start 102.200202 -10.168382)
		(end 102.200202 -9.800082)
		(width 0.1016)
		(layer "In5.Cu")
		(net "PHY_SCC_TO_DPB_21_DP")
	)
	(segment
		(start 109.398816 -39.0271)
		(end 107.442254 -29.819092)
		(width 0.1016)
		(layer "In5.Cu")
		(net "PHY_SCC_TO_DPB_21_DP")
	)
	(segment
		(start 109.858048 -45.782484)
		(end 109.858048 -45.78223)
		(width 0.1016)
		(layer "In5.Cu")
		(net "PHY_SCC_TO_DPB_21_DP")
	)
	(segment
		(start 107.442254 -29.819092)
		(end 105.485692 -20.611846)
		(width 0.1016)
		(layer "In5.Cu")
		(net "PHY_SCC_TO_DPB_21_DP")
	)
	(arc
		(start 109.375702 -52.376324)
		(mid 109.396936 -52.34464)
		(end 109.404404 -52.307236)
		(width 0.0889)
		(layer "In5.Cu")
		(net "PHY_SCC_TO_DPB_21_DP")
	)
	(arc
		(start 102.020878 -10.347706)
		(mid 102.147679 -10.295183)
		(end 102.200202 -10.168382)
		(width 0.1016)
		(layer "In5.Cu")
		(net "PHY_SCC_TO_DPB_21_DP")
	)
	(arc
		(start 109.307122 -52.404772)
		(mid 109.344239 -52.397371)
		(end 109.375702 -52.376324)
		(width 0.0889)
		(layer "In5.Cu")
		(net "PHY_SCC_TO_DPB_21_DP")
	)
	(arc
		(start 101.147626 -10.871454)
		(mid 101.301028 -10.501108)
		(end 101.671374 -10.347706)
		(width 0.1016)
		(layer "In5.Cu")
		(net "PHY_SCC_TO_DPB_21_DP")
	)
	(arc
		(start 109.000036 -52.315872)
		(mid 109.026074 -52.378734)
		(end 109.088936 -52.404772)
		(width 0.0889)
		(layer "In5.Cu")
		(net "PHY_SCC_TO_DPB_21_DP")
	)
	(segment
		(start 109.499908 -53.50002)
		(end 109.000036 -53.000148)
		(width 0.104902)
		(layer "F.Cu")
		(net "PHY_SCC_TO_DPB_21_DN")
	)
	(via
		(at 109.000036 -53.000148)
		(size 0.4572)
		(drill 0.2032)
		(layers "F.Cu" "B.Cu")
		(net "PHY_SCC_TO_DPB_21_DN")
	)
	(segment
		(start 109.996478 -47.960534)
		(end 110.222538 -47.813722)
		(width 0.1016)
		(layer "In5.Cu")
		(net "PHY_SCC_TO_DPB_21_DN")
	)
	(segment
		(start 110.285784 -47.515526)
		(end 110.138972 -47.28972)
		(width 0.1016)
		(layer "In5.Cu")
		(net "PHY_SCC_TO_DPB_21_DN")
	)
	(segment
		(start 101.62794 -14.111986)
		(end 101.452426 -13.286232)
		(width 0.1016)
		(layer "In5.Cu")
		(net "PHY_SCC_TO_DPB_21_DN")
	)
	(segment
		(start 110.031784 -45.010832)
		(end 110.031784 -43.533314)
		(width 0.1016)
		(layer "In5.Cu")
		(net "PHY_SCC_TO_DPB_21_DN")
	)
	(segment
		(start 109.088936 -52.595272)
		(end 109.307122 -52.595272)
		(width 0.0889)
		(layer "In5.Cu")
		(net "PHY_SCC_TO_DPB_21_DN")
	)
	(segment
		(start 109.652054 -49.580546)
		(end 109.996478 -47.960534)
		(width 0.1016)
		(layer "In5.Cu")
		(net "PHY_SCC_TO_DPB_21_DN")
	)
	(segment
		(start 109.710474 -39.0271)
		(end 105.772204 -20.493228)
		(width 0.1016)
		(layer "In5.Cu")
		(net "PHY_SCC_TO_DPB_21_DN")
	)
	(segment
		(start 109.652054 -50.523902)
		(end 109.652054 -49.580546)
		(width 0.1016)
		(layer "In5.Cu")
		(net "PHY_SCC_TO_DPB_21_DN")
	)
	(segment
		(start 110.031784 -43.533314)
		(end 109.450124 -40.253666)
		(width 0.1016)
		(layer "In5.Cu")
		(net "PHY_SCC_TO_DPB_21_DN")
	)
	(segment
		(start 105.772204 -20.493228)
		(end 101.62794 -14.111986)
		(width 0.1016)
		(layer "In5.Cu")
		(net "PHY_SCC_TO_DPB_21_DN")
	)
	(segment
		(start 102.200202 -10.83183)
		(end 102.200202 -11.20013)
		(width 0.1016)
		(layer "In5.Cu")
		(net "PHY_SCC_TO_DPB_21_DN")
	)
	(segment
		(start 109.594904 -50.60315)
		(end 109.652054 -50.546)
		(width 0.0889)
		(layer "In5.Cu")
		(net "PHY_SCC_TO_DPB_21_DN")
	)
	(segment
		(start 109.652054 -50.546)
		(end 109.652054 -50.523902)
		(width 0.0889)
		(layer "In5.Cu")
		(net "PHY_SCC_TO_DPB_21_DN")
	)
	(segment
		(start 110.300008 -46.5328)
		(end 110.031784 -45.010832)
		(width 0.1016)
		(layer "In5.Cu")
		(net "PHY_SCC_TO_DPB_21_DN")
	)
	(segment
		(start 110.138972 -47.28972)
		(end 110.300008 -46.5328)
		(width 0.1016)
		(layer "In5.Cu")
		(net "PHY_SCC_TO_DPB_21_DN")
	)
	(segment
		(start 109.594904 -52.307236)
		(end 109.594904 -50.60315)
		(width 0.0889)
		(layer "In5.Cu")
		(net "PHY_SCC_TO_DPB_21_DN")
	)
	(segment
		(start 109.450124 -40.253666)
		(end 109.710474 -39.0271)
		(width 0.1016)
		(layer "In5.Cu")
		(net "PHY_SCC_TO_DPB_21_DN")
	)
	(segment
		(start 109.000036 -53.000148)
		(end 109.000036 -52.684172)
		(width 0.0889)
		(layer "In5.Cu")
		(net "PHY_SCC_TO_DPB_21_DN")
	)
	(segment
		(start 101.452426 -13.286232)
		(end 101.452426 -10.871454)
		(width 0.1016)
		(layer "In5.Cu")
		(net "PHY_SCC_TO_DPB_21_DN")
	)
	(segment
		(start 110.222538 -47.813722)
		(end 110.285784 -47.515526)
		(width 0.1016)
		(layer "In5.Cu")
		(net "PHY_SCC_TO_DPB_21_DN")
	)
	(segment
		(start 101.671374 -10.652506)
		(end 102.020878 -10.652506)
		(width 0.1016)
		(layer "In5.Cu")
		(net "PHY_SCC_TO_DPB_21_DN")
	)
	(arc
		(start 109.000036 -52.684172)
		(mid 109.026074 -52.62131)
		(end 109.088936 -52.595272)
		(width 0.0889)
		(layer "In5.Cu")
		(net "PHY_SCC_TO_DPB_21_DN")
	)
	(arc
		(start 109.510322 -52.511198)
		(mid 109.572903 -52.417634)
		(end 109.594904 -52.307236)
		(width 0.0889)
		(layer "In5.Cu")
		(net "PHY_SCC_TO_DPB_21_DN")
	)
	(arc
		(start 109.307122 -52.595272)
		(mid 109.417071 -52.57342)
		(end 109.510322 -52.511198)
		(width 0.0889)
		(layer "In5.Cu")
		(net "PHY_SCC_TO_DPB_21_DN")
	)
	(arc
		(start 101.452426 -10.871454)
		(mid 101.516554 -10.716634)
		(end 101.671374 -10.652506)
		(width 0.1016)
		(layer "In5.Cu")
		(net "PHY_SCC_TO_DPB_21_DN")
	)
	(arc
		(start 102.020878 -10.652506)
		(mid 102.147679 -10.705029)
		(end 102.200202 -10.83183)
		(width 0.1016)
		(layer "In5.Cu")
		(net "PHY_SCC_TO_DPB_21_DN")
	)
	(segment
		(start 108.49991 -51.500024)
		(end 108.000038 -51.000152)
		(width 0.104902)
		(layer "F.Cu")
		(net "PHY_SCC_TO_DPB_20_DP")
	)
	(via
		(at 108.000038 -51.000152)
		(size 0.4572)
		(drill 0.2032)
		(layers "F.Cu" "B.Cu")
		(net "PHY_SCC_TO_DPB_20_DP")
	)
	(segment
		(start 108.202984 -43.416474)
		(end 107.698794 -40.55618)
		(width 0.1016)
		(layer "In5.Cu")
		(net "PHY_SCC_TO_DPB_20_DP")
	)
	(segment
		(start 108.351574 -49.493424)
		(end 108.707682 -47.81677)
		(width 0.1016)
		(layer "In5.Cu")
		(net "PHY_SCC_TO_DPB_20_DP")
	)
	(segment
		(start 108.202984 -44.956984)
		(end 108.202984 -43.416474)
		(width 0.1016)
		(layer "In5.Cu")
		(net "PHY_SCC_TO_DPB_20_DP")
	)
	(segment
		(start 108.408724 -51.26228)
		(end 108.408724 -50.620676)
		(width 0.0889)
		(layer "In5.Cu")
		(net "PHY_SCC_TO_DPB_20_DP")
	)
	(segment
		(start 108.000038 -51.000152)
		(end 108.000038 -51.315874)
		(width 0.0889)
		(layer "In5.Cu")
		(net "PHY_SCC_TO_DPB_20_DP")
	)
	(segment
		(start 100.400104 -11.368278)
		(end 100.400104 -10.999978)
		(width 0.1016)
		(layer "In5.Cu")
		(net "PHY_SCC_TO_DPB_20_DP")
	)
	(segment
		(start 108.351574 -50.541428)
		(end 108.351574 -49.493424)
		(width 0.1016)
		(layer "In5.Cu")
		(net "PHY_SCC_TO_DPB_20_DP")
	)
	(segment
		(start 108.081318 -38.75659)
		(end 104.652572 -22.62505)
		(width 0.1016)
		(layer "In5.Cu")
		(net "PHY_SCC_TO_DPB_20_DP")
	)
	(segment
		(start 108.088938 -51.404774)
		(end 108.265976 -51.404774)
		(width 0.0889)
		(layer "In5.Cu")
		(net "PHY_SCC_TO_DPB_20_DP")
	)
	(segment
		(start 108.351574 -50.563526)
		(end 108.351574 -50.541428)
		(width 0.0889)
		(layer "In5.Cu")
		(net "PHY_SCC_TO_DPB_20_DP")
	)
	(segment
		(start 99.796346 -15.147036)
		(end 99.347782 -13.036804)
		(width 0.1016)
		(layer "In5.Cu")
		(net "PHY_SCC_TO_DPB_20_DP")
	)
	(segment
		(start 107.698794 -40.55618)
		(end 108.081318 -38.75659)
		(width 0.1016)
		(layer "In5.Cu")
		(net "PHY_SCC_TO_DPB_20_DP")
	)
	(segment
		(start 108.707682 -47.81677)
		(end 108.202984 -44.956984)
		(width 0.1016)
		(layer "In5.Cu")
		(net "PHY_SCC_TO_DPB_20_DP")
	)
	(segment
		(start 104.652572 -22.62505)
		(end 99.796346 -15.147036)
		(width 0.1016)
		(layer "In5.Cu")
		(net "PHY_SCC_TO_DPB_20_DP")
	)
	(segment
		(start 108.408724 -50.620676)
		(end 108.351574 -50.563526)
		(width 0.0889)
		(layer "In5.Cu")
		(net "PHY_SCC_TO_DPB_20_DP")
	)
	(segment
		(start 99.871276 -11.547602)
		(end 100.22078 -11.547602)
		(width 0.1016)
		(layer "In5.Cu")
		(net "PHY_SCC_TO_DPB_20_DP")
	)
	(segment
		(start 99.347782 -13.036804)
		(end 99.347782 -12.071096)
		(width 0.1016)
		(layer "In5.Cu")
		(net "PHY_SCC_TO_DPB_20_DP")
	)
	(arc
		(start 108.000038 -51.315874)
		(mid 108.026076 -51.378736)
		(end 108.088938 -51.404774)
		(width 0.0889)
		(layer "In5.Cu")
		(net "PHY_SCC_TO_DPB_20_DP")
	)
	(arc
		(start 108.265976 -51.404774)
		(mid 108.3207 -51.393889)
		(end 108.367068 -51.362864)
		(width 0.0889)
		(layer "In5.Cu")
		(net "PHY_SCC_TO_DPB_20_DP")
	)
	(arc
		(start 99.347782 -12.071096)
		(mid 99.50111 -11.70093)
		(end 99.871276 -11.547602)
		(width 0.1016)
		(layer "In5.Cu")
		(net "PHY_SCC_TO_DPB_20_DP")
	)
	(arc
		(start 100.22078 -11.547602)
		(mid 100.347581 -11.495079)
		(end 100.400104 -11.368278)
		(width 0.1016)
		(layer "In5.Cu")
		(net "PHY_SCC_TO_DPB_20_DP")
	)
	(arc
		(start 108.367068 -51.362864)
		(mid 108.397903 -51.316716)
		(end 108.408724 -51.26228)
		(width 0.0889)
		(layer "In5.Cu")
		(net "PHY_SCC_TO_DPB_20_DP")
	)
	(segment
		(start 108.49991 -52.500022)
		(end 108.000038 -52.00015)
		(width 0.104902)
		(layer "F.Cu")
		(net "PHY_SCC_TO_DPB_20_DN")
	)
	(via
		(at 108.000038 -52.00015)
		(size 0.4572)
		(drill 0.2032)
		(layers "F.Cu" "B.Cu")
		(net "PHY_SCC_TO_DPB_20_DN")
	)
	(segment
		(start 108.656374 -50.563526)
		(end 108.656374 -50.541428)
		(width 0.0889)
		(layer "In5.Cu")
		(net "PHY_SCC_TO_DPB_20_DN")
	)
	(segment
		(start 108.599224 -50.620676)
		(end 108.656374 -50.563526)
		(width 0.0889)
		(layer "In5.Cu")
		(net "PHY_SCC_TO_DPB_20_DN")
	)
	(segment
		(start 108.392976 -38.75659)
		(end 104.939084 -22.506432)
		(width 0.1016)
		(layer "In5.Cu")
		(net "PHY_SCC_TO_DPB_20_DN")
	)
	(segment
		(start 104.939084 -22.506432)
		(end 100.082858 -15.028418)
		(width 0.1016)
		(layer "In5.Cu")
		(net "PHY_SCC_TO_DPB_20_DN")
	)
	(segment
		(start 99.652582 -13.004546)
		(end 99.652582 -12.071096)
		(width 0.1016)
		(layer "In5.Cu")
		(net "PHY_SCC_TO_DPB_20_DN")
	)
	(segment
		(start 100.082858 -15.028418)
		(end 99.652582 -13.004546)
		(width 0.1016)
		(layer "In5.Cu")
		(net "PHY_SCC_TO_DPB_20_DN")
	)
	(segment
		(start 108.599224 -51.26228)
		(end 108.599224 -50.620676)
		(width 0.0889)
		(layer "In5.Cu")
		(net "PHY_SCC_TO_DPB_20_DN")
	)
	(segment
		(start 108.009436 -40.561514)
		(end 108.188252 -39.720012)
		(width 0.1016)
		(layer "In5.Cu")
		(net "PHY_SCC_TO_DPB_20_DN")
	)
	(segment
		(start 108.000038 -52.00015)
		(end 108.000038 -51.684174)
		(width 0.0889)
		(layer "In5.Cu")
		(net "PHY_SCC_TO_DPB_20_DN")
	)
	(segment
		(start 109.083602 -48.43145)
		(end 108.93679 -48.20539)
		(width 0.1016)
		(layer "In5.Cu")
		(net "PHY_SCC_TO_DPB_20_DN")
	)
	(segment
		(start 99.871276 -11.852402)
		(end 100.22078 -11.852402)
		(width 0.1016)
		(layer "In5.Cu")
		(net "PHY_SCC_TO_DPB_20_DN")
	)
	(segment
		(start 108.93679 -48.20539)
		(end 108.937044 -48.20539)
		(width 0.1016)
		(layer "In5.Cu")
		(net "PHY_SCC_TO_DPB_20_DN")
	)
	(segment
		(start 108.188252 -39.720012)
		(end 108.392976 -38.75659)
		(width 0.1016)
		(layer "In5.Cu")
		(net "PHY_SCC_TO_DPB_20_DN")
	)
	(segment
		(start 108.088938 -51.595274)
		(end 108.265976 -51.595274)
		(width 0.0889)
		(layer "In5.Cu")
		(net "PHY_SCC_TO_DPB_20_DN")
	)
	(segment
		(start 109.018324 -47.822104)
		(end 108.507784 -44.93006)
		(width 0.1016)
		(layer "In5.Cu")
		(net "PHY_SCC_TO_DPB_20_DN")
	)
	(segment
		(start 108.656374 -49.525682)
		(end 108.794296 -48.876204)
		(width 0.1016)
		(layer "In5.Cu")
		(net "PHY_SCC_TO_DPB_20_DN")
	)
	(segment
		(start 108.507784 -44.93006)
		(end 108.507784 -43.389804)
		(width 0.1016)
		(layer "In5.Cu")
		(net "PHY_SCC_TO_DPB_20_DN")
	)
	(segment
		(start 109.020102 -48.729646)
		(end 109.083602 -48.43145)
		(width 0.1016)
		(layer "In5.Cu")
		(net "PHY_SCC_TO_DPB_20_DN")
	)
	(segment
		(start 100.400104 -12.031726)
		(end 100.400104 -12.400026)
		(width 0.1016)
		(layer "In5.Cu")
		(net "PHY_SCC_TO_DPB_20_DN")
	)
	(segment
		(start 108.656374 -50.541428)
		(end 108.656374 -49.525682)
		(width 0.1016)
		(layer "In5.Cu")
		(net "PHY_SCC_TO_DPB_20_DN")
	)
	(segment
		(start 108.507784 -43.389804)
		(end 108.009436 -40.561514)
		(width 0.1016)
		(layer "In5.Cu")
		(net "PHY_SCC_TO_DPB_20_DN")
	)
	(segment
		(start 108.937044 -48.20539)
		(end 109.018324 -47.822104)
		(width 0.1016)
		(layer "In5.Cu")
		(net "PHY_SCC_TO_DPB_20_DN")
	)
	(segment
		(start 108.794296 -48.876204)
		(end 109.020102 -48.729646)
		(width 0.1016)
		(layer "In5.Cu")
		(net "PHY_SCC_TO_DPB_20_DN")
	)
	(arc
		(start 108.501942 -51.497484)
		(mid 108.57394 -51.389543)
		(end 108.599224 -51.26228)
		(width 0.0889)
		(layer "In5.Cu")
		(net "PHY_SCC_TO_DPB_20_DN")
	)
	(arc
		(start 99.652582 -12.071096)
		(mid 99.716636 -11.916456)
		(end 99.871276 -11.852402)
		(width 0.1016)
		(layer "In5.Cu")
		(net "PHY_SCC_TO_DPB_20_DN")
	)
	(arc
		(start 108.265976 -51.595274)
		(mid 108.393685 -51.569853)
		(end 108.501942 -51.497484)
		(width 0.0889)
		(layer "In5.Cu")
		(net "PHY_SCC_TO_DPB_20_DN")
	)
	(arc
		(start 108.000038 -51.684174)
		(mid 108.026076 -51.621312)
		(end 108.088938 -51.595274)
		(width 0.0889)
		(layer "In5.Cu")
		(net "PHY_SCC_TO_DPB_20_DN")
	)
	(arc
		(start 100.22078 -11.852402)
		(mid 100.347581 -11.904925)
		(end 100.400104 -12.031726)
		(width 0.1016)
		(layer "In5.Cu")
		(net "PHY_SCC_TO_DPB_20_DN")
	)
	(segment
		(start 129.500122 -67.500246)
		(end 129.999994 -68.000118)
		(width 0.104902)
		(layer "F.Cu")
		(net "PHY_SCC_TO_DPB_2_DP")
	)
	(via
		(at 129.999994 -68.000118)
		(size 0.4572)
		(drill 0.2032)
		(layers "F.Cu" "B.Cu")
		(net "PHY_SCC_TO_DPB_2_DP")
	)
	(segment
		(start 131.2672 -68.34759)
		(end 131.289298 -68.34759)
		(width 0.0889)
		(layer "In5.Cu")
		(net "PHY_SCC_TO_DPB_2_DP")
	)
	(segment
		(start 140.767308 -45.008038)
		(end 137.746486 -30.796992)
		(width 0.1016)
		(layer "In5.Cu")
		(net "PHY_SCC_TO_DPB_2_DP")
	)
	(segment
		(start 136.5123 -57.89803)
		(end 138.764264 -54.431184)
		(width 0.1016)
		(layer "In5.Cu")
		(net "PHY_SCC_TO_DPB_2_DP")
	)
	(segment
		(start 132.289042 -67.162172)
		(end 132.504688 -66.94678)
		(width 0.1016)
		(layer "In5.Cu")
		(net "PHY_SCC_TO_DPB_2_DP")
	)
	(segment
		(start 129.999994 -68.000118)
		(end 129.682748 -68.000118)
		(width 0.0889)
		(layer "In5.Cu")
		(net "PHY_SCC_TO_DPB_2_DP")
	)
	(segment
		(start 131.588764 -68.131944)
		(end 131.588764 -67.862704)
		(width 0.1016)
		(layer "In5.Cu")
		(net "PHY_SCC_TO_DPB_2_DP")
	)
	(segment
		(start 139.999974 -11.368278)
		(end 139.999974 -10.999978)
		(width 0.1016)
		(layer "In5.Cu")
		(net "PHY_SCC_TO_DPB_2_DP")
	)
	(segment
		(start 134.315708 -65.405)
		(end 135.0264 -65.405)
		(width 0.1016)
		(layer "In5.Cu")
		(net "PHY_SCC_TO_DPB_2_DP")
	)
	(segment
		(start 132.773928 -66.94678)
		(end 134.315708 -65.405)
		(width 0.1016)
		(layer "In5.Cu")
		(net "PHY_SCC_TO_DPB_2_DP")
	)
	(segment
		(start 132.07365 -67.647058)
		(end 132.289042 -67.431666)
		(width 0.1016)
		(layer "In5.Cu")
		(net "PHY_SCC_TO_DPB_2_DP")
	)
	(segment
		(start 129.593848 -68.089018)
		(end 129.593848 -68.199254)
		(width 0.0889)
		(layer "In5.Cu")
		(net "PHY_SCC_TO_DPB_2_DP")
	)
	(segment
		(start 138.947652 -16.780764)
		(end 138.947652 -12.071096)
		(width 0.1016)
		(layer "In5.Cu")
		(net "PHY_SCC_TO_DPB_2_DP")
	)
	(segment
		(start 139.471146 -11.547602)
		(end 139.82065 -11.547602)
		(width 0.1016)
		(layer "In5.Cu")
		(net "PHY_SCC_TO_DPB_2_DP")
	)
	(segment
		(start 135.0264 -65.405)
		(end 136.205468 -64.225932)
		(width 0.1016)
		(layer "In5.Cu")
		(net "PHY_SCC_TO_DPB_2_DP")
	)
	(segment
		(start 132.504688 -66.94678)
		(end 132.773928 -66.94678)
		(width 0.1016)
		(layer "In5.Cu")
		(net "PHY_SCC_TO_DPB_2_DP")
	)
	(segment
		(start 137.746486 -30.796992)
		(end 139.836144 -20.962366)
		(width 0.1016)
		(layer "In5.Cu")
		(net "PHY_SCC_TO_DPB_2_DP")
	)
	(segment
		(start 131.289298 -68.34759)
		(end 131.373118 -68.34759)
		(width 0.1016)
		(layer "In5.Cu")
		(net "PHY_SCC_TO_DPB_2_DP")
	)
	(segment
		(start 136.205468 -64.225932)
		(end 136.205468 -59.341258)
		(width 0.1016)
		(layer "In5.Cu")
		(net "PHY_SCC_TO_DPB_2_DP")
	)
	(segment
		(start 129.799334 -68.40474)
		(end 131.21005 -68.40474)
		(width 0.0889)
		(layer "In5.Cu")
		(net "PHY_SCC_TO_DPB_2_DP")
	)
	(segment
		(start 131.588764 -67.862704)
		(end 131.804156 -67.647058)
		(width 0.1016)
		(layer "In5.Cu")
		(net "PHY_SCC_TO_DPB_2_DP")
	)
	(segment
		(start 132.289042 -67.431666)
		(end 132.289042 -67.162172)
		(width 0.1016)
		(layer "In5.Cu")
		(net "PHY_SCC_TO_DPB_2_DP")
	)
	(segment
		(start 131.21005 -68.40474)
		(end 131.2672 -68.34759)
		(width 0.0889)
		(layer "In5.Cu")
		(net "PHY_SCC_TO_DPB_2_DP")
	)
	(segment
		(start 131.373118 -68.34759)
		(end 131.588764 -68.131944)
		(width 0.1016)
		(layer "In5.Cu")
		(net "PHY_SCC_TO_DPB_2_DP")
	)
	(segment
		(start 131.804156 -67.647058)
		(end 132.07365 -67.647058)
		(width 0.1016)
		(layer "In5.Cu")
		(net "PHY_SCC_TO_DPB_2_DP")
	)
	(segment
		(start 138.764264 -54.431184)
		(end 140.767308 -45.008038)
		(width 0.1016)
		(layer "In5.Cu")
		(net "PHY_SCC_TO_DPB_2_DP")
	)
	(segment
		(start 136.205468 -59.341258)
		(end 136.5123 -57.89803)
		(width 0.1016)
		(layer "In5.Cu")
		(net "PHY_SCC_TO_DPB_2_DP")
	)
	(segment
		(start 139.836144 -20.962366)
		(end 138.947652 -16.780764)
		(width 0.1016)
		(layer "In5.Cu")
		(net "PHY_SCC_TO_DPB_2_DP")
	)
	(arc
		(start 129.593848 -68.199254)
		(mid 129.60949 -68.27789)
		(end 129.654046 -68.344542)
		(width 0.0889)
		(layer "In5.Cu")
		(net "PHY_SCC_TO_DPB_2_DP")
	)
	(arc
		(start 139.82065 -11.547602)
		(mid 139.947451 -11.495079)
		(end 139.999974 -11.368278)
		(width 0.1016)
		(layer "In5.Cu")
		(net "PHY_SCC_TO_DPB_2_DP")
	)
	(arc
		(start 138.947652 -12.071096)
		(mid 139.10098 -11.70093)
		(end 139.471146 -11.547602)
		(width 0.1016)
		(layer "In5.Cu")
		(net "PHY_SCC_TO_DPB_2_DP")
	)
	(arc
		(start 129.654046 -68.344542)
		(mid 129.720705 -68.389082)
		(end 129.799334 -68.40474)
		(width 0.0889)
		(layer "In5.Cu")
		(net "PHY_SCC_TO_DPB_2_DP")
	)
	(arc
		(start 129.682748 -68.000118)
		(mid 129.619886 -68.026156)
		(end 129.593848 -68.089018)
		(width 0.0889)
		(layer "In5.Cu")
		(net "PHY_SCC_TO_DPB_2_DP")
	)
	(segment
		(start 128.500124 -67.500246)
		(end 128.999996 -68.000118)
		(width 0.104902)
		(layer "F.Cu")
		(net "PHY_SCC_TO_DPB_2_DN")
	)
	(via
		(at 128.999996 -68.000118)
		(size 0.4572)
		(drill 0.2032)
		(layers "F.Cu" "B.Cu")
		(net "PHY_SCC_TO_DPB_2_DN")
	)
	(segment
		(start 139.563348 -52.13858)
		(end 140.063982 -49.782984)
		(width 0.1016)
		(layer "In5.Cu")
		(net "PHY_SCC_TO_DPB_2_DN")
	)
	(segment
		(start 136.510268 -64.352424)
		(end 136.510268 -59.373516)
		(width 0.1016)
		(layer "In5.Cu")
		(net "PHY_SCC_TO_DPB_2_DN")
	)
	(segment
		(start 139.471146 -11.852402)
		(end 139.82065 -11.852402)
		(width 0.1016)
		(layer "In5.Cu")
		(net "PHY_SCC_TO_DPB_2_DN")
	)
	(segment
		(start 128.999996 -68.000118)
		(end 129.314448 -68.000118)
		(width 0.0889)
		(layer "In5.Cu")
		(net "PHY_SCC_TO_DPB_2_DN")
	)
	(segment
		(start 135.152892 -65.7098)
		(end 136.510268 -64.352424)
		(width 0.1016)
		(layer "In5.Cu")
		(net "PHY_SCC_TO_DPB_2_DN")
	)
	(segment
		(start 140.063982 -49.782984)
		(end 141.078966 -45.008038)
		(width 0.1016)
		(layer "In5.Cu")
		(net "PHY_SCC_TO_DPB_2_DN")
	)
	(segment
		(start 141.078966 -45.008038)
		(end 138.058144 -30.796992)
		(width 0.1016)
		(layer "In5.Cu")
		(net "PHY_SCC_TO_DPB_2_DN")
	)
	(segment
		(start 138.058144 -30.796992)
		(end 140.147802 -20.962366)
		(width 0.1016)
		(layer "In5.Cu")
		(net "PHY_SCC_TO_DPB_2_DN")
	)
	(segment
		(start 129.403348 -68.089018)
		(end 129.403348 -68.199254)
		(width 0.0889)
		(layer "In5.Cu")
		(net "PHY_SCC_TO_DPB_2_DN")
	)
	(segment
		(start 139.252452 -16.748506)
		(end 139.252452 -12.071096)
		(width 0.1016)
		(layer "In5.Cu")
		(net "PHY_SCC_TO_DPB_2_DN")
	)
	(segment
		(start 136.510268 -59.373516)
		(end 136.798812 -58.016648)
		(width 0.1016)
		(layer "In5.Cu")
		(net "PHY_SCC_TO_DPB_2_DN")
	)
	(segment
		(start 139.050776 -54.549802)
		(end 139.563348 -52.13858)
		(width 0.1016)
		(layer "In5.Cu")
		(net "PHY_SCC_TO_DPB_2_DN")
	)
	(segment
		(start 131.49961 -68.65239)
		(end 134.4422 -65.7098)
		(width 0.1016)
		(layer "In5.Cu")
		(net "PHY_SCC_TO_DPB_2_DN")
	)
	(segment
		(start 136.798812 -58.016648)
		(end 139.050776 -54.549802)
		(width 0.1016)
		(layer "In5.Cu")
		(net "PHY_SCC_TO_DPB_2_DN")
	)
	(segment
		(start 131.21005 -68.59524)
		(end 131.2672 -68.65239)
		(width 0.0889)
		(layer "In5.Cu")
		(net "PHY_SCC_TO_DPB_2_DN")
	)
	(segment
		(start 139.999974 -12.031726)
		(end 139.999974 -12.400026)
		(width 0.1016)
		(layer "In5.Cu")
		(net "PHY_SCC_TO_DPB_2_DN")
	)
	(segment
		(start 131.2672 -68.65239)
		(end 131.289298 -68.65239)
		(width 0.0889)
		(layer "In5.Cu")
		(net "PHY_SCC_TO_DPB_2_DN")
	)
	(segment
		(start 131.289298 -68.65239)
		(end 131.49961 -68.65239)
		(width 0.1016)
		(layer "In5.Cu")
		(net "PHY_SCC_TO_DPB_2_DN")
	)
	(segment
		(start 129.799334 -68.59524)
		(end 131.21005 -68.59524)
		(width 0.0889)
		(layer "In5.Cu")
		(net "PHY_SCC_TO_DPB_2_DN")
	)
	(segment
		(start 140.147802 -20.962366)
		(end 139.252452 -16.748506)
		(width 0.1016)
		(layer "In5.Cu")
		(net "PHY_SCC_TO_DPB_2_DN")
	)
	(segment
		(start 134.4422 -65.7098)
		(end 135.152892 -65.7098)
		(width 0.1016)
		(layer "In5.Cu")
		(net "PHY_SCC_TO_DPB_2_DN")
	)
	(arc
		(start 129.519172 -68.479416)
		(mid 129.647726 -68.56522)
		(end 129.799334 -68.59524)
		(width 0.0889)
		(layer "In5.Cu")
		(net "PHY_SCC_TO_DPB_2_DN")
	)
	(arc
		(start 139.252452 -12.071096)
		(mid 139.316506 -11.916456)
		(end 139.471146 -11.852402)
		(width 0.1016)
		(layer "In5.Cu")
		(net "PHY_SCC_TO_DPB_2_DN")
	)
	(arc
		(start 129.314448 -68.000118)
		(mid 129.37731 -68.026156)
		(end 129.403348 -68.089018)
		(width 0.0889)
		(layer "In5.Cu")
		(net "PHY_SCC_TO_DPB_2_DN")
	)
	(arc
		(start 139.82065 -11.852402)
		(mid 139.947451 -11.904925)
		(end 139.999974 -12.031726)
		(width 0.1016)
		(layer "In5.Cu")
		(net "PHY_SCC_TO_DPB_2_DN")
	)
	(arc
		(start 129.403348 -68.199254)
		(mid 129.433408 -68.350845)
		(end 129.519172 -68.479416)
		(width 0.0889)
		(layer "In5.Cu")
		(net "PHY_SCC_TO_DPB_2_DN")
	)
	(segment
		(start 107.499912 -52.500022)
		(end 107.00004 -52.00015)
		(width 0.104902)
		(layer "F.Cu")
		(net "PHY_SCC_TO_DPB_19_DP")
	)
	(via
		(at 107.00004 -52.00015)
		(size 0.4572)
		(drill 0.2032)
		(layers "F.Cu" "B.Cu")
		(net "PHY_SCC_TO_DPB_19_DP")
	)
	(segment
		(start 107.347258 -50.523902)
		(end 107.347258 -49.267364)
		(width 0.1016)
		(layer "In5.Cu")
		(net "PHY_SCC_TO_DPB_19_DP")
	)
	(segment
		(start 106.982006 -45.738796)
		(end 106.748326 -45.404786)
		(width 0.1016)
		(layer "In5.Cu")
		(net "PHY_SCC_TO_DPB_19_DP")
	)
	(segment
		(start 106.299762 -41.376092)
		(end 106.81081 -38.970712)
		(width 0.1016)
		(layer "In5.Cu")
		(net "PHY_SCC_TO_DPB_19_DP")
	)
	(segment
		(start 106.991658 -45.75302)
		(end 106.991658 -45.752766)
		(width 0.1016)
		(layer "In5.Cu")
		(net "PHY_SCC_TO_DPB_19_DP")
	)
	(segment
		(start 107.404408 -50.60315)
		(end 107.347258 -50.546)
		(width 0.0889)
		(layer "In5.Cu")
		(net "PHY_SCC_TO_DPB_19_DP")
	)
	(segment
		(start 107.543346 -48.345852)
		(end 106.991658 -45.75302)
		(width 0.1016)
		(layer "In5.Cu")
		(net "PHY_SCC_TO_DPB_19_DP")
	)
	(segment
		(start 107.347258 -50.546)
		(end 107.347258 -50.523902)
		(width 0.0889)
		(layer "In5.Cu")
		(net "PHY_SCC_TO_DPB_19_DP")
	)
	(segment
		(start 98.600006 -10.168382)
		(end 98.600006 -9.800082)
		(width 0.1016)
		(layer "In5.Cu")
		(net "PHY_SCC_TO_DPB_19_DP")
	)
	(segment
		(start 106.991658 -45.752766)
		(end 106.989626 -45.749718)
		(width 0.1016)
		(layer "In5.Cu")
		(net "PHY_SCC_TO_DPB_19_DP")
	)
	(segment
		(start 103.591106 -23.824184)
		(end 98.07829 -15.335758)
		(width 0.1016)
		(layer "In5.Cu")
		(net "PHY_SCC_TO_DPB_19_DP")
	)
	(segment
		(start 106.748326 -45.404786)
		(end 106.678984 -45.011086)
		(width 0.1016)
		(layer "In5.Cu")
		(net "PHY_SCC_TO_DPB_19_DP")
	)
	(segment
		(start 98.07829 -15.335758)
		(end 97.547684 -12.838176)
		(width 0.1016)
		(layer "In5.Cu")
		(net "PHY_SCC_TO_DPB_19_DP")
	)
	(segment
		(start 106.678984 -45.011086)
		(end 106.678984 -43.526964)
		(width 0.1016)
		(layer "In5.Cu")
		(net "PHY_SCC_TO_DPB_19_DP")
	)
	(segment
		(start 106.989626 -45.749718)
		(end 106.989372 -45.749718)
		(width 0.1016)
		(layer "In5.Cu")
		(net "PHY_SCC_TO_DPB_19_DP")
	)
	(segment
		(start 107.404408 -52.214018)
		(end 107.404408 -50.60315)
		(width 0.0889)
		(layer "In5.Cu")
		(net "PHY_SCC_TO_DPB_19_DP")
	)
	(segment
		(start 98.071178 -10.347706)
		(end 98.420682 -10.347706)
		(width 0.1016)
		(layer "In5.Cu")
		(net "PHY_SCC_TO_DPB_19_DP")
	)
	(segment
		(start 107.00004 -52.00015)
		(end 107.00004 -52.315872)
		(width 0.0889)
		(layer "In5.Cu")
		(net "PHY_SCC_TO_DPB_19_DP")
	)
	(segment
		(start 107.08894 -52.404772)
		(end 107.213654 -52.404772)
		(width 0.0889)
		(layer "In5.Cu")
		(net "PHY_SCC_TO_DPB_19_DP")
	)
	(segment
		(start 106.81081 -38.970712)
		(end 103.591106 -23.824184)
		(width 0.1016)
		(layer "In5.Cu")
		(net "PHY_SCC_TO_DPB_19_DP")
	)
	(segment
		(start 106.678984 -43.526964)
		(end 106.299762 -41.376092)
		(width 0.1016)
		(layer "In5.Cu")
		(net "PHY_SCC_TO_DPB_19_DP")
	)
	(segment
		(start 106.989372 -45.749718)
		(end 106.985816 -45.744384)
		(width 0.1016)
		(layer "In5.Cu")
		(net "PHY_SCC_TO_DPB_19_DP")
	)
	(segment
		(start 97.547684 -12.838176)
		(end 97.547684 -10.8712)
		(width 0.1016)
		(layer "In5.Cu")
		(net "PHY_SCC_TO_DPB_19_DP")
	)
	(segment
		(start 106.985054 -45.743622)
		(end 106.984038 -45.741844)
		(width 0.1016)
		(layer "In5.Cu")
		(net "PHY_SCC_TO_DPB_19_DP")
	)
	(segment
		(start 106.985816 -45.744384)
		(end 106.985054 -45.743622)
		(width 0.1016)
		(layer "In5.Cu")
		(net "PHY_SCC_TO_DPB_19_DP")
	)
	(segment
		(start 107.347258 -49.267364)
		(end 107.543346 -48.345852)
		(width 0.1016)
		(layer "In5.Cu")
		(net "PHY_SCC_TO_DPB_19_DP")
	)
	(segment
		(start 106.984038 -45.741844)
		(end 106.982006 -45.738796)
		(width 0.1016)
		(layer "In5.Cu")
		(net "PHY_SCC_TO_DPB_19_DP")
	)
	(arc
		(start 107.348528 -52.348892)
		(mid 107.389875 -52.287011)
		(end 107.404408 -52.214018)
		(width 0.0889)
		(layer "In5.Cu")
		(net "PHY_SCC_TO_DPB_19_DP")
	)
	(arc
		(start 107.00004 -52.315872)
		(mid 107.026078 -52.378734)
		(end 107.08894 -52.404772)
		(width 0.0889)
		(layer "In5.Cu")
		(net "PHY_SCC_TO_DPB_19_DP")
	)
	(arc
		(start 107.213654 -52.404772)
		(mid 107.286652 -52.390252)
		(end 107.348528 -52.348892)
		(width 0.0889)
		(layer "In5.Cu")
		(net "PHY_SCC_TO_DPB_19_DP")
	)
	(arc
		(start 97.547684 -10.8712)
		(mid 97.701012 -10.501034)
		(end 98.071178 -10.347706)
		(width 0.1016)
		(layer "In5.Cu")
		(net "PHY_SCC_TO_DPB_19_DP")
	)
	(arc
		(start 98.420682 -10.347706)
		(mid 98.547483 -10.295183)
		(end 98.600006 -10.168382)
		(width 0.1016)
		(layer "In5.Cu")
		(net "PHY_SCC_TO_DPB_19_DP")
	)
	(segment
		(start 107.499912 -53.50002)
		(end 107.00004 -53.000148)
		(width 0.104902)
		(layer "F.Cu")
		(net "PHY_SCC_TO_DPB_19_DN")
	)
	(via
		(at 107.00004 -53.000148)
		(size 0.4572)
		(drill 0.2032)
		(layers "F.Cu" "B.Cu")
		(net "PHY_SCC_TO_DPB_19_DN")
	)
	(segment
		(start 107.08894 -52.595272)
		(end 107.213654 -52.595272)
		(width 0.0889)
		(layer "In5.Cu")
		(net "PHY_SCC_TO_DPB_19_DN")
	)
	(segment
		(start 107.277662 -45.62983)
		(end 107.27563 -45.626782)
		(width 0.1016)
		(layer "In5.Cu")
		(net "PHY_SCC_TO_DPB_19_DN")
	)
	(segment
		(start 106.983784 -44.984162)
		(end 106.983784 -43.500294)
		(width 0.1016)
		(layer "In5.Cu")
		(net "PHY_SCC_TO_DPB_19_DN")
	)
	(segment
		(start 107.64901 -47.376588)
		(end 107.278932 -45.636688)
		(width 0.1016)
		(layer "In5.Cu")
		(net "PHY_SCC_TO_DPB_19_DN")
	)
	(segment
		(start 107.594908 -50.60315)
		(end 107.652058 -50.546)
		(width 0.0889)
		(layer "In5.Cu")
		(net "PHY_SCC_TO_DPB_19_DN")
	)
	(segment
		(start 107.874816 -47.5234)
		(end 107.64901 -47.376588)
		(width 0.1016)
		(layer "In5.Cu")
		(net "PHY_SCC_TO_DPB_19_DN")
	)
	(segment
		(start 106.610404 -41.381934)
		(end 107.122468 -38.970712)
		(width 0.1016)
		(layer "In5.Cu")
		(net "PHY_SCC_TO_DPB_19_DN")
	)
	(segment
		(start 97.852484 -12.805918)
		(end 97.852484 -10.8712)
		(width 0.1016)
		(layer "In5.Cu")
		(net "PHY_SCC_TO_DPB_19_DN")
	)
	(segment
		(start 107.122468 -38.970712)
		(end 103.877618 -23.705566)
		(width 0.1016)
		(layer "In5.Cu")
		(net "PHY_SCC_TO_DPB_19_DN")
	)
	(segment
		(start 107.652058 -50.523902)
		(end 107.652058 -49.299622)
		(width 0.1016)
		(layer "In5.Cu")
		(net "PHY_SCC_TO_DPB_19_DN")
	)
	(segment
		(start 98.364802 -15.21714)
		(end 97.852484 -12.805918)
		(width 0.1016)
		(layer "In5.Cu")
		(net "PHY_SCC_TO_DPB_19_DN")
	)
	(segment
		(start 103.877618 -23.705566)
		(end 98.364802 -15.21714)
		(width 0.1016)
		(layer "In5.Cu")
		(net "PHY_SCC_TO_DPB_19_DN")
	)
	(segment
		(start 107.652058 -50.546)
		(end 107.652058 -50.523902)
		(width 0.0889)
		(layer "In5.Cu")
		(net "PHY_SCC_TO_DPB_19_DN")
	)
	(segment
		(start 107.27563 -45.626782)
		(end 107.03687 -45.285152)
		(width 0.1016)
		(layer "In5.Cu")
		(net "PHY_SCC_TO_DPB_19_DN")
	)
	(segment
		(start 107.791504 -48.047402)
		(end 107.938316 -47.821596)
		(width 0.1016)
		(layer "In5.Cu")
		(net "PHY_SCC_TO_DPB_19_DN")
	)
	(segment
		(start 106.983784 -43.500294)
		(end 106.610404 -41.381934)
		(width 0.1016)
		(layer "In5.Cu")
		(net "PHY_SCC_TO_DPB_19_DN")
	)
	(segment
		(start 98.600006 -10.83183)
		(end 98.600006 -11.20013)
		(width 0.1016)
		(layer "In5.Cu")
		(net "PHY_SCC_TO_DPB_19_DN")
	)
	(segment
		(start 107.03687 -45.285152)
		(end 106.983784 -44.984162)
		(width 0.1016)
		(layer "In5.Cu")
		(net "PHY_SCC_TO_DPB_19_DN")
	)
	(segment
		(start 107.938316 -47.821596)
		(end 107.874816 -47.5234)
		(width 0.1016)
		(layer "In5.Cu")
		(net "PHY_SCC_TO_DPB_19_DN")
	)
	(segment
		(start 107.855004 -48.345852)
		(end 107.791504 -48.047402)
		(width 0.1016)
		(layer "In5.Cu")
		(net "PHY_SCC_TO_DPB_19_DN")
	)
	(segment
		(start 107.652058 -49.299622)
		(end 107.855004 -48.345852)
		(width 0.1016)
		(layer "In5.Cu")
		(net "PHY_SCC_TO_DPB_19_DN")
	)
	(segment
		(start 107.00004 -53.000148)
		(end 107.00004 -52.684172)
		(width 0.0889)
		(layer "In5.Cu")
		(net "PHY_SCC_TO_DPB_19_DN")
	)
	(segment
		(start 107.278932 -45.636688)
		(end 107.277662 -45.62983)
		(width 0.1016)
		(layer "In5.Cu")
		(net "PHY_SCC_TO_DPB_19_DN")
	)
	(segment
		(start 107.594908 -52.214018)
		(end 107.594908 -50.60315)
		(width 0.0889)
		(layer "In5.Cu")
		(net "PHY_SCC_TO_DPB_19_DN")
	)
	(segment
		(start 98.071178 -10.652506)
		(end 98.420682 -10.652506)
		(width 0.1016)
		(layer "In5.Cu")
		(net "PHY_SCC_TO_DPB_19_DN")
	)
	(arc
		(start 107.213654 -52.595272)
		(mid 107.359607 -52.566334)
		(end 107.483402 -52.483766)
		(width 0.0889)
		(layer "In5.Cu")
		(net "PHY_SCC_TO_DPB_19_DN")
	)
	(arc
		(start 107.483402 -52.483766)
		(mid 107.566014 -52.35999)
		(end 107.594908 -52.214018)
		(width 0.0889)
		(layer "In5.Cu")
		(net "PHY_SCC_TO_DPB_19_DN")
	)
	(arc
		(start 98.420682 -10.652506)
		(mid 98.547483 -10.705029)
		(end 98.600006 -10.83183)
		(width 0.1016)
		(layer "In5.Cu")
		(net "PHY_SCC_TO_DPB_19_DN")
	)
	(arc
		(start 97.852484 -10.8712)
		(mid 97.916538 -10.71656)
		(end 98.071178 -10.652506)
		(width 0.1016)
		(layer "In5.Cu")
		(net "PHY_SCC_TO_DPB_19_DN")
	)
	(arc
		(start 107.00004 -52.684172)
		(mid 107.026078 -52.62131)
		(end 107.08894 -52.595272)
		(width 0.0889)
		(layer "In5.Cu")
		(net "PHY_SCC_TO_DPB_19_DN")
	)
	(segment
		(start 106.499914 -51.500024)
		(end 106.000042 -51.000152)
		(width 0.104902)
		(layer "F.Cu")
		(net "PHY_SCC_TO_DPB_18_DP")
	)
	(via
		(at 106.000042 -51.000152)
		(size 0.4572)
		(drill 0.2032)
		(layers "F.Cu" "B.Cu")
		(net "PHY_SCC_TO_DPB_18_DP")
	)
	(segment
		(start 95.74784 -13.280644)
		(end 95.74784 -12.071096)
		(width 0.1016)
		(layer "In5.Cu")
		(net "PHY_SCC_TO_DPB_18_DP")
	)
	(segment
		(start 106.408728 -50.620676)
		(end 106.351578 -50.563526)
		(width 0.0889)
		(layer "In5.Cu")
		(net "PHY_SCC_TO_DPB_18_DP")
	)
	(segment
		(start 106.088942 -51.404774)
		(end 106.197146 -51.404774)
		(width 0.0889)
		(layer "In5.Cu")
		(net "PHY_SCC_TO_DPB_18_DP")
	)
	(segment
		(start 106.408728 -51.193192)
		(end 106.408728 -50.620676)
		(width 0.0889)
		(layer "In5.Cu")
		(net "PHY_SCC_TO_DPB_18_DP")
	)
	(segment
		(start 106.351578 -49.933606)
		(end 105.496106 -45.911008)
		(width 0.1016)
		(layer "In5.Cu")
		(net "PHY_SCC_TO_DPB_18_DP")
	)
	(segment
		(start 102.658418 -25.23871)
		(end 96.163638 -15.238222)
		(width 0.1016)
		(layer "In5.Cu")
		(net "PHY_SCC_TO_DPB_18_DP")
	)
	(segment
		(start 105.154984 -45.011086)
		(end 105.154984 -43.526964)
		(width 0.1016)
		(layer "In5.Cu")
		(net "PHY_SCC_TO_DPB_18_DP")
	)
	(segment
		(start 104.957118 -41.454324)
		(end 105.03154 -41.032938)
		(width 0.1016)
		(layer "In5.Cu")
		(net "PHY_SCC_TO_DPB_18_DP")
	)
	(segment
		(start 96.163638 -15.238222)
		(end 95.74784 -13.280644)
		(width 0.1016)
		(layer "In5.Cu")
		(net "PHY_SCC_TO_DPB_18_DP")
	)
	(segment
		(start 104.873298 -41.929304)
		(end 104.957118 -41.454324)
		(width 0.1016)
		(layer "In5.Cu")
		(net "PHY_SCC_TO_DPB_18_DP")
	)
	(segment
		(start 105.03154 -41.032938)
		(end 105.18013 -40.190166)
		(width 0.1016)
		(layer "In5.Cu")
		(net "PHY_SCC_TO_DPB_18_DP")
	)
	(segment
		(start 106.351578 -50.563526)
		(end 106.351578 -50.541428)
		(width 0.0889)
		(layer "In5.Cu")
		(net "PHY_SCC_TO_DPB_18_DP")
	)
	(segment
		(start 96.271334 -11.547602)
		(end 96.620838 -11.547602)
		(width 0.1016)
		(layer "In5.Cu")
		(net "PHY_SCC_TO_DPB_18_DP")
	)
	(segment
		(start 105.47731 -38.503606)
		(end 102.658418 -25.23871)
		(width 0.1016)
		(layer "In5.Cu")
		(net "PHY_SCC_TO_DPB_18_DP")
	)
	(segment
		(start 105.496106 -45.911008)
		(end 105.46842 -45.753528)
		(width 0.1016)
		(layer "In5.Cu")
		(net "PHY_SCC_TO_DPB_18_DP")
	)
	(segment
		(start 105.154984 -43.526964)
		(end 104.873298 -41.929304)
		(width 0.1016)
		(layer "In5.Cu")
		(net "PHY_SCC_TO_DPB_18_DP")
	)
	(segment
		(start 96.800162 -11.368278)
		(end 96.800162 -10.999978)
		(width 0.1016)
		(layer "In5.Cu")
		(net "PHY_SCC_TO_DPB_18_DP")
	)
	(segment
		(start 105.18013 -40.190166)
		(end 105.47731 -38.503606)
		(width 0.1016)
		(layer "In5.Cu")
		(net "PHY_SCC_TO_DPB_18_DP")
	)
	(segment
		(start 105.46842 -45.753528)
		(end 105.224326 -45.404532)
		(width 0.1016)
		(layer "In5.Cu")
		(net "PHY_SCC_TO_DPB_18_DP")
	)
	(segment
		(start 106.351578 -50.541428)
		(end 106.351578 -49.933606)
		(width 0.1016)
		(layer "In5.Cu")
		(net "PHY_SCC_TO_DPB_18_DP")
	)
	(segment
		(start 105.224326 -45.404532)
		(end 105.154984 -45.011086)
		(width 0.1016)
		(layer "In5.Cu")
		(net "PHY_SCC_TO_DPB_18_DP")
	)
	(segment
		(start 106.000042 -51.000152)
		(end 106.000042 -51.315874)
		(width 0.0889)
		(layer "In5.Cu")
		(net "PHY_SCC_TO_DPB_18_DP")
	)
	(arc
		(start 95.74784 -12.071096)
		(mid 95.901168 -11.70093)
		(end 96.271334 -11.547602)
		(width 0.1016)
		(layer "In5.Cu")
		(net "PHY_SCC_TO_DPB_18_DP")
	)
	(arc
		(start 106.346752 -51.342798)
		(mid 106.392616 -51.274158)
		(end 106.408728 -51.193192)
		(width 0.0889)
		(layer "In5.Cu")
		(net "PHY_SCC_TO_DPB_18_DP")
	)
	(arc
		(start 106.197146 -51.404774)
		(mid 106.278115 -51.388668)
		(end 106.346752 -51.342798)
		(width 0.0889)
		(layer "In5.Cu")
		(net "PHY_SCC_TO_DPB_18_DP")
	)
	(arc
		(start 106.000042 -51.315874)
		(mid 106.02608 -51.378736)
		(end 106.088942 -51.404774)
		(width 0.0889)
		(layer "In5.Cu")
		(net "PHY_SCC_TO_DPB_18_DP")
	)
	(arc
		(start 96.620838 -11.547602)
		(mid 96.747639 -11.495079)
		(end 96.800162 -11.368278)
		(width 0.1016)
		(layer "In5.Cu")
		(net "PHY_SCC_TO_DPB_18_DP")
	)
	(segment
		(start 106.499914 -52.500022)
		(end 106.000042 -52.00015)
		(width 0.104902)
		(layer "F.Cu")
		(net "PHY_SCC_TO_DPB_18_DN")
	)
	(via
		(at 106.000042 -52.00015)
		(size 0.4572)
		(drill 0.2032)
		(layers "F.Cu" "B.Cu")
		(net "PHY_SCC_TO_DPB_18_DN")
	)
	(segment
		(start 105.459784 -44.984162)
		(end 105.459784 -43.500294)
		(width 0.1016)
		(layer "In5.Cu")
		(net "PHY_SCC_TO_DPB_18_DN")
	)
	(segment
		(start 105.182924 -41.929304)
		(end 105.294938 -41.296336)
		(width 0.1016)
		(layer "In5.Cu")
		(net "PHY_SCC_TO_DPB_18_DN")
	)
	(segment
		(start 106.205274 -46.864016)
		(end 105.979214 -46.717204)
		(width 0.1016)
		(layer "In5.Cu")
		(net "PHY_SCC_TO_DPB_18_DN")
	)
	(segment
		(start 105.294938 -41.296336)
		(end 105.331768 -41.08577)
		(width 0.1016)
		(layer "In5.Cu")
		(net "PHY_SCC_TO_DPB_18_DN")
	)
	(segment
		(start 96.05264 -13.248386)
		(end 96.05264 -12.071096)
		(width 0.1016)
		(layer "In5.Cu")
		(net "PHY_SCC_TO_DPB_18_DN")
	)
	(segment
		(start 105.331768 -41.08577)
		(end 105.480358 -40.242998)
		(width 0.1016)
		(layer "In5.Cu")
		(net "PHY_SCC_TO_DPB_18_DN")
	)
	(segment
		(start 105.787952 -38.498272)
		(end 104.36606 -31.807912)
		(width 0.1016)
		(layer "In5.Cu")
		(net "PHY_SCC_TO_DPB_18_DN")
	)
	(segment
		(start 106.656378 -49.901348)
		(end 106.121962 -47.388018)
		(width 0.1016)
		(layer "In5.Cu")
		(net "PHY_SCC_TO_DPB_18_DN")
	)
	(segment
		(start 96.271334 -11.852402)
		(end 96.620838 -11.852402)
		(width 0.1016)
		(layer "In5.Cu")
		(net "PHY_SCC_TO_DPB_18_DN")
	)
	(segment
		(start 106.26852 -47.161958)
		(end 106.205274 -46.864016)
		(width 0.1016)
		(layer "In5.Cu")
		(net "PHY_SCC_TO_DPB_18_DN")
	)
	(segment
		(start 102.94493 -25.120092)
		(end 96.45015 -15.119604)
		(width 0.1016)
		(layer "In5.Cu")
		(net "PHY_SCC_TO_DPB_18_DN")
	)
	(segment
		(start 106.599228 -51.193192)
		(end 106.599228 -50.620676)
		(width 0.0889)
		(layer "In5.Cu")
		(net "PHY_SCC_TO_DPB_18_DN")
	)
	(segment
		(start 106.088942 -51.595274)
		(end 106.197146 -51.595274)
		(width 0.0889)
		(layer "In5.Cu")
		(net "PHY_SCC_TO_DPB_18_DN")
	)
	(segment
		(start 105.459784 -43.500294)
		(end 105.182924 -41.929304)
		(width 0.1016)
		(layer "In5.Cu")
		(net "PHY_SCC_TO_DPB_18_DN")
	)
	(segment
		(start 96.45015 -15.119604)
		(end 96.05264 -13.248386)
		(width 0.1016)
		(layer "In5.Cu")
		(net "PHY_SCC_TO_DPB_18_DN")
	)
	(segment
		(start 105.756964 -45.634148)
		(end 105.51287 -45.285152)
		(width 0.1016)
		(layer "In5.Cu")
		(net "PHY_SCC_TO_DPB_18_DN")
	)
	(segment
		(start 96.800162 -12.031726)
		(end 96.800162 -12.400026)
		(width 0.1016)
		(layer "In5.Cu")
		(net "PHY_SCC_TO_DPB_18_DN")
	)
	(segment
		(start 106.656378 -50.563526)
		(end 106.656378 -50.541428)
		(width 0.0889)
		(layer "In5.Cu")
		(net "PHY_SCC_TO_DPB_18_DN")
	)
	(segment
		(start 105.795318 -45.851826)
		(end 105.756964 -45.634148)
		(width 0.1016)
		(layer "In5.Cu")
		(net "PHY_SCC_TO_DPB_18_DN")
	)
	(segment
		(start 104.36606 -31.807912)
		(end 102.94493 -25.120092)
		(width 0.1016)
		(layer "In5.Cu")
		(net "PHY_SCC_TO_DPB_18_DN")
	)
	(segment
		(start 105.979214 -46.717204)
		(end 105.795318 -45.851826)
		(width 0.1016)
		(layer "In5.Cu")
		(net "PHY_SCC_TO_DPB_18_DN")
	)
	(segment
		(start 106.000042 -52.00015)
		(end 106.000042 -51.684174)
		(width 0.0889)
		(layer "In5.Cu")
		(net "PHY_SCC_TO_DPB_18_DN")
	)
	(segment
		(start 106.599228 -50.620676)
		(end 106.656378 -50.563526)
		(width 0.0889)
		(layer "In5.Cu")
		(net "PHY_SCC_TO_DPB_18_DN")
	)
	(segment
		(start 106.656378 -50.541428)
		(end 106.656378 -49.901348)
		(width 0.1016)
		(layer "In5.Cu")
		(net "PHY_SCC_TO_DPB_18_DN")
	)
	(segment
		(start 105.480358 -40.242998)
		(end 105.787952 -38.498272)
		(width 0.1016)
		(layer "In5.Cu")
		(net "PHY_SCC_TO_DPB_18_DN")
	)
	(segment
		(start 105.51287 -45.285152)
		(end 105.459784 -44.984162)
		(width 0.1016)
		(layer "In5.Cu")
		(net "PHY_SCC_TO_DPB_18_DN")
	)
	(segment
		(start 106.121962 -47.388018)
		(end 106.26852 -47.161958)
		(width 0.1016)
		(layer "In5.Cu")
		(net "PHY_SCC_TO_DPB_18_DN")
	)
	(arc
		(start 96.05264 -12.071096)
		(mid 96.116694 -11.916456)
		(end 96.271334 -11.852402)
		(width 0.1016)
		(layer "In5.Cu")
		(net "PHY_SCC_TO_DPB_18_DN")
	)
	(arc
		(start 96.620838 -11.852402)
		(mid 96.747639 -11.904925)
		(end 96.800162 -12.031726)
		(width 0.1016)
		(layer "In5.Cu")
		(net "PHY_SCC_TO_DPB_18_DN")
	)
	(arc
		(start 106.481626 -51.477672)
		(mid 106.568754 -51.347136)
		(end 106.599228 -51.193192)
		(width 0.0889)
		(layer "In5.Cu")
		(net "PHY_SCC_TO_DPB_18_DN")
	)
	(arc
		(start 106.000042 -51.684174)
		(mid 106.02608 -51.621312)
		(end 106.088942 -51.595274)
		(width 0.0889)
		(layer "In5.Cu")
		(net "PHY_SCC_TO_DPB_18_DN")
	)
	(arc
		(start 106.197146 -51.595274)
		(mid 106.35107 -51.56475)
		(end 106.481626 -51.477672)
		(width 0.0889)
		(layer "In5.Cu")
		(net "PHY_SCC_TO_DPB_18_DN")
	)
	(segment
		(start 105.499916 -52.500022)
		(end 105.000044 -52.00015)
		(width 0.104902)
		(layer "F.Cu")
		(net "PHY_SCC_TO_DPB_17_DP")
	)
	(via
		(at 105.000044 -52.00015)
		(size 0.4572)
		(drill 0.2032)
		(layers "F.Cu" "B.Cu")
		(net "PHY_SCC_TO_DPB_17_DP")
	)
	(segment
		(start 94.33306 -15.028926)
		(end 93.947488 -13.214604)
		(width 0.1016)
		(layer "In5.Cu")
		(net "PHY_SCC_TO_DPB_17_DP")
	)
	(segment
		(start 104.263952 -38.335458)
		(end 101.731318 -26.420826)
		(width 0.1016)
		(layer "In5.Cu")
		(net "PHY_SCC_TO_DPB_17_DP")
	)
	(segment
		(start 105.404412 -52.250086)
		(end 105.404412 -50.60315)
		(width 0.0889)
		(layer "In5.Cu")
		(net "PHY_SCC_TO_DPB_17_DP")
	)
	(segment
		(start 105.000044 -52.00015)
		(end 105.000044 -52.315872)
		(width 0.0889)
		(layer "In5.Cu")
		(net "PHY_SCC_TO_DPB_17_DP")
	)
	(segment
		(start 105.088944 -52.404772)
		(end 105.24998 -52.404772)
		(width 0.0889)
		(layer "In5.Cu")
		(net "PHY_SCC_TO_DPB_17_DP")
	)
	(segment
		(start 95.000064 -10.168382)
		(end 95.000064 -9.800082)
		(width 0.1016)
		(layer "In5.Cu")
		(net "PHY_SCC_TO_DPB_17_DP")
	)
	(segment
		(start 103.418132 -42.320972)
		(end 103.424228 -42.286174)
		(width 0.1016)
		(layer "In5.Cu")
		(net "PHY_SCC_TO_DPB_17_DP")
	)
	(segment
		(start 105.358946 -52.359814)
		(end 105.3592 -52.35956)
		(width 0.0889)
		(layer "In5.Cu")
		(net "PHY_SCC_TO_DPB_17_DP")
	)
	(segment
		(start 105.347262 -50.523902)
		(end 105.347262 -49.667922)
		(width 0.1016)
		(layer "In5.Cu")
		(net "PHY_SCC_TO_DPB_17_DP")
	)
	(segment
		(start 101.731318 -26.420826)
		(end 94.33306 -15.028926)
		(width 0.1016)
		(layer "In5.Cu")
		(net "PHY_SCC_TO_DPB_17_DP")
	)
	(segment
		(start 105.347262 -50.546)
		(end 105.347262 -50.523902)
		(width 0.0889)
		(layer "In5.Cu")
		(net "PHY_SCC_TO_DPB_17_DP")
	)
	(segment
		(start 103.94442 -45.756576)
		(end 103.943658 -45.75175)
		(width 0.1016)
		(layer "In5.Cu")
		(net "PHY_SCC_TO_DPB_17_DP")
	)
	(segment
		(start 93.947488 -13.214604)
		(end 93.947488 -10.871454)
		(width 0.1016)
		(layer "In5.Cu")
		(net "PHY_SCC_TO_DPB_17_DP")
	)
	(segment
		(start 103.943658 -45.75175)
		(end 103.841296 -45.605954)
		(width 0.1016)
		(layer "In5.Cu")
		(net "PHY_SCC_TO_DPB_17_DP")
	)
	(segment
		(start 94.471236 -10.347706)
		(end 94.82074 -10.347706)
		(width 0.1016)
		(layer "In5.Cu")
		(net "PHY_SCC_TO_DPB_17_DP")
	)
	(segment
		(start 105.157016 -48.772572)
		(end 104.30764 -47.464726)
		(width 0.1016)
		(layer "In5.Cu")
		(net "PHY_SCC_TO_DPB_17_DP")
	)
	(segment
		(start 105.404412 -50.60315)
		(end 105.347262 -50.546)
		(width 0.0889)
		(layer "In5.Cu")
		(net "PHY_SCC_TO_DPB_17_DP")
	)
	(segment
		(start 105.347262 -49.667922)
		(end 105.157016 -48.772572)
		(width 0.1016)
		(layer "In5.Cu")
		(net "PHY_SCC_TO_DPB_17_DP")
	)
	(segment
		(start 104.30764 -47.464726)
		(end 103.94442 -45.756576)
		(width 0.1016)
		(layer "In5.Cu")
		(net "PHY_SCC_TO_DPB_17_DP")
	)
	(segment
		(start 103.630984 -45.011086)
		(end 103.630984 -43.526964)
		(width 0.1016)
		(layer "In5.Cu")
		(net "PHY_SCC_TO_DPB_17_DP")
	)
	(segment
		(start 103.700326 -45.404532)
		(end 103.630984 -45.011086)
		(width 0.1016)
		(layer "In5.Cu")
		(net "PHY_SCC_TO_DPB_17_DP")
	)
	(segment
		(start 103.841296 -45.605954)
		(end 103.700326 -45.404532)
		(width 0.1016)
		(layer "In5.Cu")
		(net "PHY_SCC_TO_DPB_17_DP")
	)
	(segment
		(start 103.630984 -43.526964)
		(end 103.418132 -42.320972)
		(width 0.1016)
		(layer "In5.Cu")
		(net "PHY_SCC_TO_DPB_17_DP")
	)
	(segment
		(start 103.424228 -42.286174)
		(end 104.263952 -38.335458)
		(width 0.1016)
		(layer "In5.Cu")
		(net "PHY_SCC_TO_DPB_17_DP")
	)
	(arc
		(start 93.947488 -10.871454)
		(mid 94.10089 -10.501108)
		(end 94.471236 -10.347706)
		(width 0.1016)
		(layer "In5.Cu")
		(net "PHY_SCC_TO_DPB_17_DP")
	)
	(arc
		(start 105.24998 -52.404772)
		(mid 105.308913 -52.393085)
		(end 105.358946 -52.359814)
		(width 0.0889)
		(layer "In5.Cu")
		(net "PHY_SCC_TO_DPB_17_DP")
	)
	(arc
		(start 94.82074 -10.347706)
		(mid 94.947541 -10.295183)
		(end 95.000064 -10.168382)
		(width 0.1016)
		(layer "In5.Cu")
		(net "PHY_SCC_TO_DPB_17_DP")
	)
	(arc
		(start 105.000044 -52.315872)
		(mid 105.026082 -52.378734)
		(end 105.088944 -52.404772)
		(width 0.0889)
		(layer "In5.Cu")
		(net "PHY_SCC_TO_DPB_17_DP")
	)
	(arc
		(start 105.3592 -52.35956)
		(mid 105.392654 -52.309305)
		(end 105.404412 -52.250086)
		(width 0.0889)
		(layer "In5.Cu")
		(net "PHY_SCC_TO_DPB_17_DP")
	)
	(segment
		(start 105.499916 -53.50002)
		(end 105.000044 -53.000148)
		(width 0.104902)
		(layer "F.Cu")
		(net "PHY_SCC_TO_DPB_17_DN")
	)
	(via
		(at 105.000044 -53.000148)
		(size 0.4572)
		(drill 0.2032)
		(layers "F.Cu" "B.Cu")
		(net "PHY_SCC_TO_DPB_17_DN")
	)
	(segment
		(start 105.652062 -49.635664)
		(end 105.443528 -48.653954)
		(width 0.1016)
		(layer "In5.Cu")
		(net "PHY_SCC_TO_DPB_17_DN")
	)
	(segment
		(start 105.652062 -50.523902)
		(end 105.652062 -49.635664)
		(width 0.1016)
		(layer "In5.Cu")
		(net "PHY_SCC_TO_DPB_17_DN")
	)
	(segment
		(start 103.98887 -45.285152)
		(end 103.935784 -44.984162)
		(width 0.1016)
		(layer "In5.Cu")
		(net "PHY_SCC_TO_DPB_17_DN")
	)
	(segment
		(start 102.01783 -26.302208)
		(end 94.619572 -14.910308)
		(width 0.1016)
		(layer "In5.Cu")
		(net "PHY_SCC_TO_DPB_17_DN")
	)
	(segment
		(start 105.652062 -50.546)
		(end 105.652062 -50.523902)
		(width 0.0889)
		(layer "In5.Cu")
		(net "PHY_SCC_TO_DPB_17_DN")
	)
	(segment
		(start 104.613964 -46.523656)
		(end 104.388158 -46.376844)
		(width 0.1016)
		(layer "In5.Cu")
		(net "PHY_SCC_TO_DPB_17_DN")
	)
	(segment
		(start 104.234996 -45.657516)
		(end 104.23017 -45.629576)
		(width 0.1016)
		(layer "In5.Cu")
		(net "PHY_SCC_TO_DPB_17_DN")
	)
	(segment
		(start 105.594912 -50.60315)
		(end 105.652062 -50.546)
		(width 0.0889)
		(layer "In5.Cu")
		(net "PHY_SCC_TO_DPB_17_DN")
	)
	(segment
		(start 105.000044 -53.000148)
		(end 105.000044 -52.684172)
		(width 0.0889)
		(layer "In5.Cu")
		(net "PHY_SCC_TO_DPB_17_DN")
	)
	(segment
		(start 104.530652 -47.047658)
		(end 104.677464 -46.821852)
		(width 0.1016)
		(layer "In5.Cu")
		(net "PHY_SCC_TO_DPB_17_DN")
	)
	(segment
		(start 103.935784 -43.500294)
		(end 103.72852 -42.32402)
		(width 0.1016)
		(layer "In5.Cu")
		(net "PHY_SCC_TO_DPB_17_DN")
	)
	(segment
		(start 103.72852 -42.32402)
		(end 103.728012 -42.323258)
		(width 0.1016)
		(layer "In5.Cu")
		(net "PHY_SCC_TO_DPB_17_DN")
	)
	(segment
		(start 104.594152 -47.346108)
		(end 104.530652 -47.047658)
		(width 0.1016)
		(layer "In5.Cu")
		(net "PHY_SCC_TO_DPB_17_DN")
	)
	(segment
		(start 105.594912 -52.250086)
		(end 105.594912 -50.60315)
		(width 0.0889)
		(layer "In5.Cu")
		(net "PHY_SCC_TO_DPB_17_DN")
	)
	(segment
		(start 105.493566 -52.494688)
		(end 105.494074 -52.49418)
		(width 0.0889)
		(layer "In5.Cu")
		(net "PHY_SCC_TO_DPB_17_DN")
	)
	(segment
		(start 105.088944 -52.595272)
		(end 105.24998 -52.595272)
		(width 0.0889)
		(layer "In5.Cu")
		(net "PHY_SCC_TO_DPB_17_DN")
	)
	(segment
		(start 94.619572 -14.910308)
		(end 94.252288 -13.182346)
		(width 0.1016)
		(layer "In5.Cu")
		(net "PHY_SCC_TO_DPB_17_DN")
	)
	(segment
		(start 103.935784 -44.984162)
		(end 103.935784 -43.500294)
		(width 0.1016)
		(layer "In5.Cu")
		(net "PHY_SCC_TO_DPB_17_DN")
	)
	(segment
		(start 103.728012 -42.323258)
		(end 104.57561 -38.335458)
		(width 0.1016)
		(layer "In5.Cu")
		(net "PHY_SCC_TO_DPB_17_DN")
	)
	(segment
		(start 95.000064 -10.83183)
		(end 95.000064 -11.20013)
		(width 0.1016)
		(layer "In5.Cu")
		(net "PHY_SCC_TO_DPB_17_DN")
	)
	(segment
		(start 105.443528 -48.653954)
		(end 104.594152 -47.346108)
		(width 0.1016)
		(layer "In5.Cu")
		(net "PHY_SCC_TO_DPB_17_DN")
	)
	(segment
		(start 104.677464 -46.821852)
		(end 104.613964 -46.523656)
		(width 0.1016)
		(layer "In5.Cu")
		(net "PHY_SCC_TO_DPB_17_DN")
	)
	(segment
		(start 94.471236 -10.652506)
		(end 94.82074 -10.652506)
		(width 0.1016)
		(layer "In5.Cu")
		(net "PHY_SCC_TO_DPB_17_DN")
	)
	(segment
		(start 94.252288 -13.182346)
		(end 94.252288 -10.871454)
		(width 0.1016)
		(layer "In5.Cu")
		(net "PHY_SCC_TO_DPB_17_DN")
	)
	(segment
		(start 104.23017 -45.629576)
		(end 103.98887 -45.285152)
		(width 0.1016)
		(layer "In5.Cu")
		(net "PHY_SCC_TO_DPB_17_DN")
	)
	(segment
		(start 104.57561 -38.335458)
		(end 102.01783 -26.302208)
		(width 0.1016)
		(layer "In5.Cu")
		(net "PHY_SCC_TO_DPB_17_DN")
	)
	(segment
		(start 104.388158 -46.376844)
		(end 104.234996 -45.657516)
		(width 0.1016)
		(layer "In5.Cu")
		(net "PHY_SCC_TO_DPB_17_DN")
	)
	(arc
		(start 105.000044 -52.684172)
		(mid 105.026082 -52.62131)
		(end 105.088944 -52.595272)
		(width 0.0889)
		(layer "In5.Cu")
		(net "PHY_SCC_TO_DPB_17_DN")
	)
	(arc
		(start 105.494074 -52.49418)
		(mid 105.56869 -52.382132)
		(end 105.594912 -52.250086)
		(width 0.0889)
		(layer "In5.Cu")
		(net "PHY_SCC_TO_DPB_17_DN")
	)
	(arc
		(start 94.82074 -10.652506)
		(mid 94.947541 -10.705029)
		(end 95.000064 -10.83183)
		(width 0.1016)
		(layer "In5.Cu")
		(net "PHY_SCC_TO_DPB_17_DN")
	)
	(arc
		(start 94.252288 -10.871454)
		(mid 94.316416 -10.716634)
		(end 94.471236 -10.652506)
		(width 0.1016)
		(layer "In5.Cu")
		(net "PHY_SCC_TO_DPB_17_DN")
	)
	(arc
		(start 105.24998 -52.595272)
		(mid 105.381745 -52.569134)
		(end 105.493566 -52.494688)
		(width 0.0889)
		(layer "In5.Cu")
		(net "PHY_SCC_TO_DPB_17_DN")
	)
	(segment
		(start 104.499918 -51.500024)
		(end 104.000046 -51.000152)
		(width 0.104902)
		(layer "F.Cu")
		(net "PHY_SCC_TO_DPB_16_DP")
	)
	(via
		(at 104.000046 -51.000152)
		(size 0.4572)
		(drill 0.2032)
		(layers "F.Cu" "B.Cu")
		(net "PHY_SCC_TO_DPB_16_DP")
	)
	(segment
		(start 104.088946 -51.404774)
		(end 104.252268 -51.404774)
		(width 0.0889)
		(layer "In5.Cu")
		(net "PHY_SCC_TO_DPB_16_DP")
	)
	(segment
		(start 102.176326 -45.404786)
		(end 102.132384 -45.154088)
		(width 0.1016)
		(layer "In5.Cu")
		(net "PHY_SCC_TO_DPB_16_DP")
	)
	(segment
		(start 104.408732 -50.620676)
		(end 104.351582 -50.563526)
		(width 0.0889)
		(layer "In5.Cu")
		(net "PHY_SCC_TO_DPB_16_DP")
	)
	(segment
		(start 104.000046 -51.000152)
		(end 104.000046 -51.315874)
		(width 0.0889)
		(layer "In5.Cu")
		(net "PHY_SCC_TO_DPB_16_DP")
	)
	(segment
		(start 92.303092 -14.10462)
		(end 92.147644 -13.372846)
		(width 0.1016)
		(layer "In5.Cu")
		(net "PHY_SCC_TO_DPB_16_DP")
	)
	(segment
		(start 104.222804 -49.405032)
		(end 102.695248 -47.052992)
		(width 0.1016)
		(layer "In5.Cu")
		(net "PHY_SCC_TO_DPB_16_DP")
	)
	(segment
		(start 104.351582 -50.541428)
		(end 104.351582 -50.011584)
		(width 0.1016)
		(layer "In5.Cu")
		(net "PHY_SCC_TO_DPB_16_DP")
	)
	(segment
		(start 103.090726 -37.945568)
		(end 101.948488 -32.571436)
		(width 0.1016)
		(layer "In5.Cu")
		(net "PHY_SCC_TO_DPB_16_DP")
	)
	(segment
		(start 102.106984 -45.011086)
		(end 102.106984 -43.53052)
		(width 0.1016)
		(layer "In5.Cu")
		(net "PHY_SCC_TO_DPB_16_DP")
	)
	(segment
		(start 92.671138 -11.547602)
		(end 93.020642 -11.547602)
		(width 0.1016)
		(layer "In5.Cu")
		(net "PHY_SCC_TO_DPB_16_DP")
	)
	(segment
		(start 104.408732 -51.24831)
		(end 104.408732 -50.620676)
		(width 0.0889)
		(layer "In5.Cu")
		(net "PHY_SCC_TO_DPB_16_DP")
	)
	(segment
		(start 102.132384 -45.154088)
		(end 102.106984 -45.011086)
		(width 0.1016)
		(layer "In5.Cu")
		(net "PHY_SCC_TO_DPB_16_DP")
	)
	(segment
		(start 104.351582 -50.011584)
		(end 104.222804 -49.405032)
		(width 0.1016)
		(layer "In5.Cu")
		(net "PHY_SCC_TO_DPB_16_DP")
	)
	(segment
		(start 102.418896 -45.750988)
		(end 102.176326 -45.404786)
		(width 0.1016)
		(layer "In5.Cu")
		(net "PHY_SCC_TO_DPB_16_DP")
	)
	(segment
		(start 100.805742 -27.196034)
		(end 92.303092 -14.10462)
		(width 0.1016)
		(layer "In5.Cu")
		(net "PHY_SCC_TO_DPB_16_DP")
	)
	(segment
		(start 102.106984 -43.53052)
		(end 103.090726 -37.945568)
		(width 0.1016)
		(layer "In5.Cu")
		(net "PHY_SCC_TO_DPB_16_DP")
	)
	(segment
		(start 102.695248 -47.052992)
		(end 102.418896 -45.750988)
		(width 0.1016)
		(layer "In5.Cu")
		(net "PHY_SCC_TO_DPB_16_DP")
	)
	(segment
		(start 93.199966 -11.368278)
		(end 93.199966 -10.999978)
		(width 0.1016)
		(layer "In5.Cu")
		(net "PHY_SCC_TO_DPB_16_DP")
	)
	(segment
		(start 92.147644 -13.372846)
		(end 92.147644 -12.071096)
		(width 0.1016)
		(layer "In5.Cu")
		(net "PHY_SCC_TO_DPB_16_DP")
	)
	(segment
		(start 104.351582 -50.563526)
		(end 104.351582 -50.541428)
		(width 0.0889)
		(layer "In5.Cu")
		(net "PHY_SCC_TO_DPB_16_DP")
	)
	(segment
		(start 101.948488 -32.571436)
		(end 100.805742 -27.196034)
		(width 0.1016)
		(layer "In5.Cu")
		(net "PHY_SCC_TO_DPB_16_DP")
	)
	(arc
		(start 92.147644 -12.071096)
		(mid 92.300972 -11.70093)
		(end 92.671138 -11.547602)
		(width 0.1016)
		(layer "In5.Cu")
		(net "PHY_SCC_TO_DPB_16_DP")
	)
	(arc
		(start 104.000046 -51.315874)
		(mid 104.026084 -51.378736)
		(end 104.088946 -51.404774)
		(width 0.0889)
		(layer "In5.Cu")
		(net "PHY_SCC_TO_DPB_16_DP")
	)
	(arc
		(start 104.252268 -51.404774)
		(mid 104.362905 -51.358947)
		(end 104.408732 -51.24831)
		(width 0.0889)
		(layer "In5.Cu")
		(net "PHY_SCC_TO_DPB_16_DP")
	)
	(arc
		(start 93.020642 -11.547602)
		(mid 93.147443 -11.495079)
		(end 93.199966 -11.368278)
		(width 0.1016)
		(layer "In5.Cu")
		(net "PHY_SCC_TO_DPB_16_DP")
	)
	(segment
		(start 104.499918 -52.500022)
		(end 104.000046 -52.00015)
		(width 0.104902)
		(layer "F.Cu")
		(net "PHY_SCC_TO_DPB_16_DN")
	)
	(via
		(at 104.000046 -52.00015)
		(size 0.4572)
		(drill 0.2032)
		(layers "F.Cu" "B.Cu")
		(net "PHY_SCC_TO_DPB_16_DN")
	)
	(segment
		(start 92.671138 -11.852402)
		(end 93.020642 -11.852402)
		(width 0.1016)
		(layer "In5.Cu")
		(net "PHY_SCC_TO_DPB_16_DN")
	)
	(segment
		(start 104.656382 -50.563526)
		(end 104.656382 -50.541428)
		(width 0.0889)
		(layer "In5.Cu")
		(net "PHY_SCC_TO_DPB_16_DN")
	)
	(segment
		(start 103.401368 -37.940234)
		(end 101.092254 -27.077416)
		(width 0.1016)
		(layer "In5.Cu")
		(net "PHY_SCC_TO_DPB_16_DN")
	)
	(segment
		(start 102.411784 -43.55719)
		(end 103.401368 -37.940234)
		(width 0.1016)
		(layer "In5.Cu")
		(net "PHY_SCC_TO_DPB_16_DN")
	)
	(segment
		(start 104.000046 -52.00015)
		(end 104.000046 -51.684174)
		(width 0.0889)
		(layer "In5.Cu")
		(net "PHY_SCC_TO_DPB_16_DN")
	)
	(segment
		(start 92.452444 -13.340588)
		(end 92.452444 -12.071096)
		(width 0.1016)
		(layer "In5.Cu")
		(net "PHY_SCC_TO_DPB_16_DN")
	)
	(segment
		(start 104.656382 -50.541428)
		(end 104.656382 -49.97958)
		(width 0.1016)
		(layer "In5.Cu")
		(net "PHY_SCC_TO_DPB_16_DN")
	)
	(segment
		(start 92.589604 -13.986002)
		(end 92.452444 -13.340588)
		(width 0.1016)
		(layer "In5.Cu")
		(net "PHY_SCC_TO_DPB_16_DN")
	)
	(segment
		(start 102.982014 -46.934628)
		(end 102.918514 -46.636178)
		(width 0.1016)
		(layer "In5.Cu")
		(net "PHY_SCC_TO_DPB_16_DN")
	)
	(segment
		(start 104.599232 -51.24831)
		(end 104.599232 -50.620676)
		(width 0.0889)
		(layer "In5.Cu")
		(net "PHY_SCC_TO_DPB_16_DN")
	)
	(segment
		(start 104.656382 -49.97958)
		(end 104.509316 -49.286414)
		(width 0.1016)
		(layer "In5.Cu")
		(net "PHY_SCC_TO_DPB_16_DN")
	)
	(segment
		(start 103.065326 -46.410372)
		(end 103.001826 -46.112176)
		(width 0.1016)
		(layer "In5.Cu")
		(net "PHY_SCC_TO_DPB_16_DN")
	)
	(segment
		(start 102.704392 -45.626782)
		(end 102.46487 -45.285152)
		(width 0.1016)
		(layer "In5.Cu")
		(net "PHY_SCC_TO_DPB_16_DN")
	)
	(segment
		(start 102.46487 -45.285152)
		(end 102.411784 -44.984162)
		(width 0.1016)
		(layer "In5.Cu")
		(net "PHY_SCC_TO_DPB_16_DN")
	)
	(segment
		(start 102.918514 -46.636178)
		(end 103.065326 -46.410372)
		(width 0.1016)
		(layer "In5.Cu")
		(net "PHY_SCC_TO_DPB_16_DN")
	)
	(segment
		(start 93.199966 -12.031726)
		(end 93.199966 -12.400026)
		(width 0.1016)
		(layer "In5.Cu")
		(net "PHY_SCC_TO_DPB_16_DN")
	)
	(segment
		(start 104.599232 -50.620676)
		(end 104.656382 -50.563526)
		(width 0.0889)
		(layer "In5.Cu")
		(net "PHY_SCC_TO_DPB_16_DN")
	)
	(segment
		(start 101.092254 -27.077416)
		(end 92.589604 -13.986002)
		(width 0.1016)
		(layer "In5.Cu")
		(net "PHY_SCC_TO_DPB_16_DN")
	)
	(segment
		(start 103.001826 -46.112176)
		(end 102.77602 -45.965364)
		(width 0.1016)
		(layer "In5.Cu")
		(net "PHY_SCC_TO_DPB_16_DN")
	)
	(segment
		(start 104.509316 -49.286414)
		(end 102.982014 -46.934628)
		(width 0.1016)
		(layer "In5.Cu")
		(net "PHY_SCC_TO_DPB_16_DN")
	)
	(segment
		(start 102.77602 -45.965364)
		(end 102.704392 -45.626782)
		(width 0.1016)
		(layer "In5.Cu")
		(net "PHY_SCC_TO_DPB_16_DN")
	)
	(segment
		(start 104.088946 -51.595274)
		(end 104.252268 -51.595274)
		(width 0.0889)
		(layer "In5.Cu")
		(net "PHY_SCC_TO_DPB_16_DN")
	)
	(segment
		(start 102.411784 -44.984162)
		(end 102.411784 -43.55719)
		(width 0.1016)
		(layer "In5.Cu")
		(net "PHY_SCC_TO_DPB_16_DN")
	)
	(arc
		(start 104.000046 -51.684174)
		(mid 104.026084 -51.621312)
		(end 104.088946 -51.595274)
		(width 0.0889)
		(layer "In5.Cu")
		(net "PHY_SCC_TO_DPB_16_DN")
	)
	(arc
		(start 92.452444 -12.071096)
		(mid 92.516498 -11.916456)
		(end 92.671138 -11.852402)
		(width 0.1016)
		(layer "In5.Cu")
		(net "PHY_SCC_TO_DPB_16_DN")
	)
	(arc
		(start 93.020642 -11.852402)
		(mid 93.147443 -11.904925)
		(end 93.199966 -12.031726)
		(width 0.1016)
		(layer "In5.Cu")
		(net "PHY_SCC_TO_DPB_16_DN")
	)
	(arc
		(start 104.252268 -51.595274)
		(mid 104.497609 -51.493651)
		(end 104.599232 -51.24831)
		(width 0.0889)
		(layer "In5.Cu")
		(net "PHY_SCC_TO_DPB_16_DN")
	)
	(segment
		(start 130.50012 -66.499994)
		(end 130.999992 -66.000122)
		(width 0.104902)
		(layer "F.Cu")
		(net "PHY_SCC_TO_DPB_1_DP")
	)
	(via
		(at 130.999992 -66.000122)
		(size 0.4572)
		(drill 0.2032)
		(layers "F.Cu" "B.Cu")
		(net "PHY_SCC_TO_DPB_1_DP")
	)
	(segment
		(start 136.648698 -55.211218)
		(end 136.81456 -54.95544)
		(width 0.1016)
		(layer "In5.Cu")
		(net "PHY_SCC_TO_DPB_1_DP")
	)
	(segment
		(start 136.108948 -56.041798)
		(end 136.275064 -55.786274)
		(width 0.1016)
		(layer "In5.Cu")
		(net "PHY_SCC_TO_DPB_1_DP")
	)
	(segment
		(start 135.818626 -56.838342)
		(end 136.164828 -56.30545)
		(width 0.1016)
		(layer "In5.Cu")
		(net "PHY_SCC_TO_DPB_1_DP")
	)
	(segment
		(start 134.47268 -60.407804)
		(end 135.489696 -59.390788)
		(width 0.1016)
		(layer "In5.Cu")
		(net "PHY_SCC_TO_DPB_1_DP")
	)
	(segment
		(start 130.595116 -66.089022)
		(end 130.595116 -66.482214)
		(width 0.0889)
		(layer "In5.Cu")
		(net "PHY_SCC_TO_DPB_1_DP")
	)
	(segment
		(start 135.489696 -59.390788)
		(end 135.489696 -59.235848)
		(width 0.1016)
		(layer "In5.Cu")
		(net "PHY_SCC_TO_DPB_1_DP")
	)
	(segment
		(start 131.768342 -66.5734)
		(end 133.553454 -64.788288)
		(width 0.1016)
		(layer "In5.Cu")
		(net "PHY_SCC_TO_DPB_1_DP")
	)
	(segment
		(start 137.783824 -53.813202)
		(end 139.779756 -44.420536)
		(width 0.1016)
		(layer "In5.Cu")
		(net "PHY_SCC_TO_DPB_1_DP")
	)
	(segment
		(start 130.743452 -66.63055)
		(end 131.037838 -66.63055)
		(width 0.0889)
		(layer "In5.Cu")
		(net "PHY_SCC_TO_DPB_1_DP")
	)
	(segment
		(start 137.077958 -54.89956)
		(end 137.783824 -53.813202)
		(width 0.1016)
		(layer "In5.Cu")
		(net "PHY_SCC_TO_DPB_1_DP")
	)
	(segment
		(start 133.553454 -64.183006)
		(end 134.47268 -63.26378)
		(width 0.1016)
		(layer "In5.Cu")
		(net "PHY_SCC_TO_DPB_1_DP")
	)
	(segment
		(start 136.275064 -55.786274)
		(end 136.538462 -55.73014)
		(width 0.1016)
		(layer "In5.Cu")
		(net "PHY_SCC_TO_DPB_1_DP")
	)
	(segment
		(start 133.553454 -64.788288)
		(end 133.553454 -64.183006)
		(width 0.1016)
		(layer "In5.Cu")
		(net "PHY_SCC_TO_DPB_1_DP")
	)
	(segment
		(start 131.037838 -66.63055)
		(end 131.094988 -66.5734)
		(width 0.0889)
		(layer "In5.Cu")
		(net "PHY_SCC_TO_DPB_1_DP")
	)
	(segment
		(start 136.164828 -56.30545)
		(end 136.108948 -56.041798)
		(width 0.1016)
		(layer "In5.Cu")
		(net "PHY_SCC_TO_DPB_1_DP")
	)
	(segment
		(start 138.20013 -10.168382)
		(end 138.20013 -9.800082)
		(width 0.1016)
		(layer "In5.Cu")
		(net "PHY_SCC_TO_DPB_1_DP")
	)
	(segment
		(start 137.078212 -54.89956)
		(end 137.077958 -54.89956)
		(width 0.1016)
		(layer "In5.Cu")
		(net "PHY_SCC_TO_DPB_1_DP")
	)
	(segment
		(start 131.094988 -66.5734)
		(end 131.117086 -66.5734)
		(width 0.0889)
		(layer "In5.Cu")
		(net "PHY_SCC_TO_DPB_1_DP")
	)
	(segment
		(start 130.999992 -66.000122)
		(end 130.684016 -66.000122)
		(width 0.0889)
		(layer "In5.Cu")
		(net "PHY_SCC_TO_DPB_1_DP")
	)
	(segment
		(start 136.81456 -54.95544)
		(end 137.078212 -54.89956)
		(width 0.1016)
		(layer "In5.Cu")
		(net "PHY_SCC_TO_DPB_1_DP")
	)
	(segment
		(start 135.489696 -59.235848)
		(end 135.571738 -58.637932)
		(width 0.1016)
		(layer "In5.Cu")
		(net "PHY_SCC_TO_DPB_1_DP")
	)
	(segment
		(start 136.666224 -29.766768)
		(end 138.456416 -21.342858)
		(width 0.1016)
		(layer "In5.Cu")
		(net "PHY_SCC_TO_DPB_1_DP")
	)
	(segment
		(start 137.147554 -15.185136)
		(end 137.147554 -10.871454)
		(width 0.1016)
		(layer "In5.Cu")
		(net "PHY_SCC_TO_DPB_1_DP")
	)
	(segment
		(start 136.538462 -55.73014)
		(end 136.704578 -55.474616)
		(width 0.1016)
		(layer "In5.Cu")
		(net "PHY_SCC_TO_DPB_1_DP")
	)
	(segment
		(start 135.571738 -58.637932)
		(end 135.818626 -56.838342)
		(width 0.1016)
		(layer "In5.Cu")
		(net "PHY_SCC_TO_DPB_1_DP")
	)
	(segment
		(start 137.671302 -10.347706)
		(end 138.020806 -10.347706)
		(width 0.1016)
		(layer "In5.Cu")
		(net "PHY_SCC_TO_DPB_1_DP")
	)
	(segment
		(start 139.779756 -44.420536)
		(end 136.666224 -29.766768)
		(width 0.1016)
		(layer "In5.Cu")
		(net "PHY_SCC_TO_DPB_1_DP")
	)
	(segment
		(start 136.704578 -55.474616)
		(end 136.648698 -55.211218)
		(width 0.1016)
		(layer "In5.Cu")
		(net "PHY_SCC_TO_DPB_1_DP")
	)
	(segment
		(start 134.47268 -63.26378)
		(end 134.47268 -60.407804)
		(width 0.1016)
		(layer "In5.Cu")
		(net "PHY_SCC_TO_DPB_1_DP")
	)
	(segment
		(start 131.117086 -66.5734)
		(end 131.768342 -66.5734)
		(width 0.1016)
		(layer "In5.Cu")
		(net "PHY_SCC_TO_DPB_1_DP")
	)
	(segment
		(start 138.456416 -21.342858)
		(end 137.147554 -15.185136)
		(width 0.1016)
		(layer "In5.Cu")
		(net "PHY_SCC_TO_DPB_1_DP")
	)
	(arc
		(start 137.147554 -10.871454)
		(mid 137.300956 -10.501108)
		(end 137.671302 -10.347706)
		(width 0.1016)
		(layer "In5.Cu")
		(net "PHY_SCC_TO_DPB_1_DP")
	)
	(arc
		(start 130.684016 -66.000122)
		(mid 130.621154 -66.02616)
		(end 130.595116 -66.089022)
		(width 0.0889)
		(layer "In5.Cu")
		(net "PHY_SCC_TO_DPB_1_DP")
	)
	(arc
		(start 138.020806 -10.347706)
		(mid 138.147607 -10.295183)
		(end 138.20013 -10.168382)
		(width 0.1016)
		(layer "In5.Cu")
		(net "PHY_SCC_TO_DPB_1_DP")
	)
	(arc
		(start 130.595116 -66.482214)
		(mid 130.638563 -66.587103)
		(end 130.743452 -66.63055)
		(width 0.0889)
		(layer "In5.Cu")
		(net "PHY_SCC_TO_DPB_1_DP")
	)
	(segment
		(start 129.500122 -66.499994)
		(end 129.999994 -66.000122)
		(width 0.104902)
		(layer "F.Cu")
		(net "PHY_SCC_TO_DPB_1_DN")
	)
	(via
		(at 129.999994 -66.000122)
		(size 0.4572)
		(drill 0.2032)
		(layers "F.Cu" "B.Cu")
		(net "PHY_SCC_TO_DPB_1_DN")
	)
	(segment
		(start 134.77748 -60.534296)
		(end 135.794496 -59.51728)
		(width 0.1016)
		(layer "In5.Cu")
		(net "PHY_SCC_TO_DPB_1_DN")
	)
	(segment
		(start 137.671302 -10.652506)
		(end 138.020806 -10.652506)
		(width 0.1016)
		(layer "In5.Cu")
		(net "PHY_SCC_TO_DPB_1_DN")
	)
	(segment
		(start 134.77748 -63.390272)
		(end 134.77748 -60.534296)
		(width 0.1016)
		(layer "In5.Cu")
		(net "PHY_SCC_TO_DPB_1_DN")
	)
	(segment
		(start 130.404616 -66.089022)
		(end 130.404616 -66.482214)
		(width 0.0889)
		(layer "In5.Cu")
		(net "PHY_SCC_TO_DPB_1_DN")
	)
	(segment
		(start 138.768074 -21.342858)
		(end 137.452354 -15.152878)
		(width 0.1016)
		(layer "In5.Cu")
		(net "PHY_SCC_TO_DPB_1_DN")
	)
	(segment
		(start 133.858254 -64.309498)
		(end 134.77748 -63.390272)
		(width 0.1016)
		(layer "In5.Cu")
		(net "PHY_SCC_TO_DPB_1_DN")
	)
	(segment
		(start 135.794496 -59.51728)
		(end 135.794496 -59.256676)
		(width 0.1016)
		(layer "In5.Cu")
		(net "PHY_SCC_TO_DPB_1_DN")
	)
	(segment
		(start 129.999994 -66.000122)
		(end 130.315716 -66.000122)
		(width 0.0889)
		(layer "In5.Cu")
		(net "PHY_SCC_TO_DPB_1_DN")
	)
	(segment
		(start 131.037838 -66.82105)
		(end 131.094988 -66.8782)
		(width 0.0889)
		(layer "In5.Cu")
		(net "PHY_SCC_TO_DPB_1_DN")
	)
	(segment
		(start 130.743452 -66.82105)
		(end 131.037838 -66.82105)
		(width 0.0889)
		(layer "In5.Cu")
		(net "PHY_SCC_TO_DPB_1_DN")
	)
	(segment
		(start 138.20013 -10.83183)
		(end 138.20013 -11.20013)
		(width 0.1016)
		(layer "In5.Cu")
		(net "PHY_SCC_TO_DPB_1_DN")
	)
	(segment
		(start 136.977882 -29.766768)
		(end 138.768074 -21.342858)
		(width 0.1016)
		(layer "In5.Cu")
		(net "PHY_SCC_TO_DPB_1_DN")
	)
	(segment
		(start 131.117086 -66.8782)
		(end 131.894834 -66.8782)
		(width 0.1016)
		(layer "In5.Cu")
		(net "PHY_SCC_TO_DPB_1_DN")
	)
	(segment
		(start 138.070336 -53.93182)
		(end 140.091414 -44.420536)
		(width 0.1016)
		(layer "In5.Cu")
		(net "PHY_SCC_TO_DPB_1_DN")
	)
	(segment
		(start 131.894834 -66.8782)
		(end 133.858254 -64.91478)
		(width 0.1016)
		(layer "In5.Cu")
		(net "PHY_SCC_TO_DPB_1_DN")
	)
	(segment
		(start 135.952992 -58.101738)
		(end 136.111488 -56.947308)
		(width 0.1016)
		(layer "In5.Cu")
		(net "PHY_SCC_TO_DPB_1_DN")
	)
	(segment
		(start 140.091414 -44.420536)
		(end 136.977882 -29.766768)
		(width 0.1016)
		(layer "In5.Cu")
		(net "PHY_SCC_TO_DPB_1_DN")
	)
	(segment
		(start 137.452354 -15.152878)
		(end 137.452354 -10.871454)
		(width 0.1016)
		(layer "In5.Cu")
		(net "PHY_SCC_TO_DPB_1_DN")
	)
	(segment
		(start 136.111488 -56.947308)
		(end 138.070336 -53.93182)
		(width 0.1016)
		(layer "In5.Cu")
		(net "PHY_SCC_TO_DPB_1_DN")
	)
	(segment
		(start 133.858254 -64.91478)
		(end 133.858254 -64.309498)
		(width 0.1016)
		(layer "In5.Cu")
		(net "PHY_SCC_TO_DPB_1_DN")
	)
	(segment
		(start 135.794496 -59.256676)
		(end 135.952992 -58.101738)
		(width 0.1016)
		(layer "In5.Cu")
		(net "PHY_SCC_TO_DPB_1_DN")
	)
	(segment
		(start 131.094988 -66.8782)
		(end 131.117086 -66.8782)
		(width 0.0889)
		(layer "In5.Cu")
		(net "PHY_SCC_TO_DPB_1_DN")
	)
	(arc
		(start 130.315716 -66.000122)
		(mid 130.378578 -66.02616)
		(end 130.404616 -66.089022)
		(width 0.0889)
		(layer "In5.Cu")
		(net "PHY_SCC_TO_DPB_1_DN")
	)
	(arc
		(start 130.404616 -66.482214)
		(mid 130.503859 -66.721807)
		(end 130.743452 -66.82105)
		(width 0.0889)
		(layer "In5.Cu")
		(net "PHY_SCC_TO_DPB_1_DN")
	)
	(arc
		(start 137.452354 -10.871454)
		(mid 137.516482 -10.716634)
		(end 137.671302 -10.652506)
		(width 0.1016)
		(layer "In5.Cu")
		(net "PHY_SCC_TO_DPB_1_DN")
	)
	(arc
		(start 138.020806 -10.652506)
		(mid 138.147607 -10.705029)
		(end 138.20013 -10.83183)
		(width 0.1016)
		(layer "In5.Cu")
		(net "PHY_SCC_TO_DPB_1_DN")
	)
	(segment
		(start 129.500122 -65.499996)
		(end 129.999994 -65.000124)
		(width 0.104902)
		(layer "F.Cu")
		(net "PHY_SCC_TO_DPB_0_DP")
	)
	(via
		(at 129.999994 -65.000124)
		(size 0.4572)
		(drill 0.2032)
		(layers "F.Cu" "B.Cu")
		(net "PHY_SCC_TO_DPB_0_DP")
	)
	(segment
		(start 135.871204 -11.547602)
		(end 136.220708 -11.547602)
		(width 0.1016)
		(layer "In5.Cu")
		(net "PHY_SCC_TO_DPB_0_DP")
	)
	(segment
		(start 131.778502 -65.34785)
		(end 132.85216 -64.274192)
		(width 0.1016)
		(layer "In5.Cu")
		(net "PHY_SCC_TO_DPB_0_DP")
	)
	(segment
		(start 135.878316 -51.726846)
		(end 136.141714 -51.670966)
		(width 0.1016)
		(layer "In5.Cu")
		(net "PHY_SCC_TO_DPB_0_DP")
	)
	(segment
		(start 131.572 -65.34785)
		(end 131.594098 -65.34785)
		(width 0.0889)
		(layer "In5.Cu")
		(net "PHY_SCC_TO_DPB_0_DP")
	)
	(segment
		(start 129.999994 -65.000124)
		(end 129.684018 -65.000124)
		(width 0.0889)
		(layer "In5.Cu")
		(net "PHY_SCC_TO_DPB_0_DP")
	)
	(segment
		(start 129.728976 -65.405)
		(end 131.51485 -65.405)
		(width 0.0889)
		(layer "In5.Cu")
		(net "PHY_SCC_TO_DPB_0_DP")
	)
	(segment
		(start 136.400032 -11.368278)
		(end 136.400032 -10.999978)
		(width 0.1016)
		(layer "In5.Cu")
		(net "PHY_SCC_TO_DPB_0_DP")
	)
	(segment
		(start 135.33882 -52.55768)
		(end 135.602472 -52.5018)
		(width 0.1016)
		(layer "In5.Cu")
		(net "PHY_SCC_TO_DPB_0_DP")
	)
	(segment
		(start 135.602472 -52.5018)
		(end 135.768334 -52.246022)
		(width 0.1016)
		(layer "In5.Cu")
		(net "PHY_SCC_TO_DPB_0_DP")
	)
	(segment
		(start 132.85216 -63.877952)
		(end 133.734556 -62.995556)
		(width 0.1016)
		(layer "In5.Cu")
		(net "PHY_SCC_TO_DPB_0_DP")
	)
	(segment
		(start 136.846056 -23.19147)
		(end 135.34771 -16.143478)
		(width 0.1016)
		(layer "In5.Cu")
		(net "PHY_SCC_TO_DPB_0_DP")
	)
	(segment
		(start 135.454898 -29.738066)
		(end 136.846056 -23.19147)
		(width 0.1016)
		(layer "In5.Cu")
		(net "PHY_SCC_TO_DPB_0_DP")
	)
	(segment
		(start 132.85216 -64.274192)
		(end 132.85216 -63.877952)
		(width 0.1016)
		(layer "In5.Cu")
		(net "PHY_SCC_TO_DPB_0_DP")
	)
	(segment
		(start 135.172958 -52.813458)
		(end 135.33882 -52.55768)
		(width 0.1016)
		(layer "In5.Cu")
		(net "PHY_SCC_TO_DPB_0_DP")
	)
	(segment
		(start 131.51485 -65.405)
		(end 131.572 -65.34785)
		(width 0.0889)
		(layer "In5.Cu")
		(net "PHY_SCC_TO_DPB_0_DP")
	)
	(segment
		(start 135.712454 -51.982624)
		(end 135.878316 -51.726846)
		(width 0.1016)
		(layer "In5.Cu")
		(net "PHY_SCC_TO_DPB_0_DP")
	)
	(segment
		(start 137.74039 -49.208182)
		(end 138.666728 -44.850812)
		(width 0.1016)
		(layer "In5.Cu")
		(net "PHY_SCC_TO_DPB_0_DP")
	)
	(segment
		(start 133.734556 -55.378604)
		(end 135.228838 -53.076856)
		(width 0.1016)
		(layer "In5.Cu")
		(net "PHY_SCC_TO_DPB_0_DP")
	)
	(segment
		(start 135.228838 -53.076856)
		(end 135.172958 -52.813458)
		(width 0.1016)
		(layer "In5.Cu")
		(net "PHY_SCC_TO_DPB_0_DP")
	)
	(segment
		(start 131.594098 -65.34785)
		(end 131.778502 -65.34785)
		(width 0.1016)
		(layer "In5.Cu")
		(net "PHY_SCC_TO_DPB_0_DP")
	)
	(segment
		(start 133.734556 -62.995556)
		(end 133.734556 -55.378604)
		(width 0.1016)
		(layer "In5.Cu")
		(net "PHY_SCC_TO_DPB_0_DP")
	)
	(segment
		(start 138.666728 -44.850812)
		(end 135.454898 -29.738066)
		(width 0.1016)
		(layer "In5.Cu")
		(net "PHY_SCC_TO_DPB_0_DP")
	)
	(segment
		(start 136.141714 -51.670966)
		(end 137.74039 -49.208182)
		(width 0.1016)
		(layer "In5.Cu")
		(net "PHY_SCC_TO_DPB_0_DP")
	)
	(segment
		(start 129.595118 -65.089024)
		(end 129.595118 -65.271142)
		(width 0.0889)
		(layer "In5.Cu")
		(net "PHY_SCC_TO_DPB_0_DP")
	)
	(segment
		(start 135.34771 -16.143478)
		(end 135.34771 -12.071096)
		(width 0.1016)
		(layer "In5.Cu")
		(net "PHY_SCC_TO_DPB_0_DP")
	)
	(segment
		(start 135.768334 -52.246022)
		(end 135.712454 -51.982624)
		(width 0.1016)
		(layer "In5.Cu")
		(net "PHY_SCC_TO_DPB_0_DP")
	)
	(arc
		(start 129.595118 -65.271142)
		(mid 129.605357 -65.322436)
		(end 129.634488 -65.365884)
		(width 0.0889)
		(layer "In5.Cu")
		(net "PHY_SCC_TO_DPB_0_DP")
	)
	(arc
		(start 136.220708 -11.547602)
		(mid 136.347509 -11.495079)
		(end 136.400032 -11.368278)
		(width 0.1016)
		(layer "In5.Cu")
		(net "PHY_SCC_TO_DPB_0_DP")
	)
	(arc
		(start 129.634488 -65.365884)
		(mid 129.677839 -65.394851)
		(end 129.728976 -65.405)
		(width 0.0889)
		(layer "In5.Cu")
		(net "PHY_SCC_TO_DPB_0_DP")
	)
	(arc
		(start 129.684018 -65.000124)
		(mid 129.621156 -65.026162)
		(end 129.595118 -65.089024)
		(width 0.0889)
		(layer "In5.Cu")
		(net "PHY_SCC_TO_DPB_0_DP")
	)
	(arc
		(start 135.34771 -12.071096)
		(mid 135.501038 -11.70093)
		(end 135.871204 -11.547602)
		(width 0.1016)
		(layer "In5.Cu")
		(net "PHY_SCC_TO_DPB_0_DP")
	)
	(segment
		(start 128.500124 -65.499996)
		(end 128.999996 -65.000124)
		(width 0.104902)
		(layer "F.Cu")
		(net "PHY_SCC_TO_DPB_0_DN")
	)
	(via
		(at 128.999996 -65.000124)
		(size 0.4572)
		(drill 0.2032)
		(layers "F.Cu" "B.Cu")
		(net "PHY_SCC_TO_DPB_0_DN")
	)
	(segment
		(start 134.039356 -55.469028)
		(end 138.026648 -49.328578)
		(width 0.1016)
		(layer "In5.Cu")
		(net "PHY_SCC_TO_DPB_0_DN")
	)
	(segment
		(start 135.871204 -11.852402)
		(end 136.220708 -11.852402)
		(width 0.1016)
		(layer "In5.Cu")
		(net "PHY_SCC_TO_DPB_0_DN")
	)
	(segment
		(start 128.999996 -65.000124)
		(end 129.315718 -65.000124)
		(width 0.0889)
		(layer "In5.Cu")
		(net "PHY_SCC_TO_DPB_0_DN")
	)
	(segment
		(start 137.157714 -23.19147)
		(end 135.65251 -16.11122)
		(width 0.1016)
		(layer "In5.Cu")
		(net "PHY_SCC_TO_DPB_0_DN")
	)
	(segment
		(start 131.904994 -65.65265)
		(end 133.15696 -64.400684)
		(width 0.1016)
		(layer "In5.Cu")
		(net "PHY_SCC_TO_DPB_0_DN")
	)
	(segment
		(start 138.026648 -49.328578)
		(end 138.978386 -44.850812)
		(width 0.1016)
		(layer "In5.Cu")
		(net "PHY_SCC_TO_DPB_0_DN")
	)
	(segment
		(start 138.978386 -44.850812)
		(end 135.766556 -29.738066)
		(width 0.1016)
		(layer "In5.Cu")
		(net "PHY_SCC_TO_DPB_0_DN")
	)
	(segment
		(start 131.594098 -65.65265)
		(end 131.904994 -65.65265)
		(width 0.1016)
		(layer "In5.Cu")
		(net "PHY_SCC_TO_DPB_0_DN")
	)
	(segment
		(start 129.404618 -65.089024)
		(end 129.404618 -65.271142)
		(width 0.0889)
		(layer "In5.Cu")
		(net "PHY_SCC_TO_DPB_0_DN")
	)
	(segment
		(start 131.51485 -65.5955)
		(end 131.572 -65.65265)
		(width 0.0889)
		(layer "In5.Cu")
		(net "PHY_SCC_TO_DPB_0_DN")
	)
	(segment
		(start 136.400032 -12.031726)
		(end 136.400032 -12.400026)
		(width 0.1016)
		(layer "In5.Cu")
		(net "PHY_SCC_TO_DPB_0_DN")
	)
	(segment
		(start 129.728976 -65.5955)
		(end 131.51485 -65.5955)
		(width 0.0889)
		(layer "In5.Cu")
		(net "PHY_SCC_TO_DPB_0_DN")
	)
	(segment
		(start 131.572 -65.65265)
		(end 131.594098 -65.65265)
		(width 0.0889)
		(layer "In5.Cu")
		(net "PHY_SCC_TO_DPB_0_DN")
	)
	(segment
		(start 135.766556 -29.738066)
		(end 137.157714 -23.19147)
		(width 0.1016)
		(layer "In5.Cu")
		(net "PHY_SCC_TO_DPB_0_DN")
	)
	(segment
		(start 134.039356 -63.122048)
		(end 134.039356 -55.469028)
		(width 0.1016)
		(layer "In5.Cu")
		(net "PHY_SCC_TO_DPB_0_DN")
	)
	(segment
		(start 135.65251 -16.11122)
		(end 135.65251 -12.071096)
		(width 0.1016)
		(layer "In5.Cu")
		(net "PHY_SCC_TO_DPB_0_DN")
	)
	(segment
		(start 133.15696 -64.400684)
		(end 133.15696 -64.004444)
		(width 0.1016)
		(layer "In5.Cu")
		(net "PHY_SCC_TO_DPB_0_DN")
	)
	(segment
		(start 133.15696 -64.004444)
		(end 134.039356 -63.122048)
		(width 0.1016)
		(layer "In5.Cu")
		(net "PHY_SCC_TO_DPB_0_DN")
	)
	(arc
		(start 129.499868 -65.500758)
		(mid 129.605012 -65.570887)
		(end 129.728976 -65.5955)
		(width 0.0889)
		(layer "In5.Cu")
		(net "PHY_SCC_TO_DPB_0_DN")
	)
	(arc
		(start 136.220708 -11.852402)
		(mid 136.347509 -11.904925)
		(end 136.400032 -12.031726)
		(width 0.1016)
		(layer "In5.Cu")
		(net "PHY_SCC_TO_DPB_0_DN")
	)
	(arc
		(start 129.315718 -65.000124)
		(mid 129.37858 -65.026162)
		(end 129.404618 -65.089024)
		(width 0.0889)
		(layer "In5.Cu")
		(net "PHY_SCC_TO_DPB_0_DN")
	)
	(arc
		(start 129.404618 -65.271142)
		(mid 129.429377 -65.395434)
		(end 129.499868 -65.500758)
		(width 0.0889)
		(layer "In5.Cu")
		(net "PHY_SCC_TO_DPB_0_DN")
	)
	(arc
		(start 135.65251 -12.071096)
		(mid 135.716564 -11.916456)
		(end 135.871204 -11.852402)
		(width 0.1016)
		(layer "In5.Cu")
		(net "PHY_SCC_TO_DPB_0_DN")
	)
	(segment
		(start 126.500128 -60.500006)
		(end 127 -60.000134)
		(width 0.104902)
		(layer "F.Cu")
		(net "PHY_IOC_TO_SCC_C_47_DP")
	)
	(segment
		(start 142.266924 -63.791084)
		(end 142.178024 -63.879984)
		(width 0.12446)
		(layer "F.Cu")
		(net "PHY_IOC_TO_SCC_C_47_DP")
	)
	(segment
		(start 142.178024 -63.879984)
		(end 139.74191 -63.879984)
		(width 0.12446)
		(layer "F.Cu")
		(net "PHY_IOC_TO_SCC_C_47_DP")
	)
	(segment
		(start 142.498826 -63.791084)
		(end 142.266924 -63.791084)
		(width 0.12446)
		(layer "F.Cu")
		(net "PHY_IOC_TO_SCC_C_47_DP")
	)
	(segment
		(start 139.107418 -64.514476)
		(end 139.107418 -64.846962)
		(width 0.12446)
		(layer "F.Cu")
		(net "PHY_IOC_TO_SCC_C_47_DP")
	)
	(segment
		(start 138.981942 -64.972184)
		(end 138.739118 -64.972184)
		(width 0.12446)
		(layer "F.Cu")
		(net "PHY_IOC_TO_SCC_C_47_DP")
	)
	(via
		(at 127 -60.000134)
		(size 0.4572)
		(drill 0.2032)
		(layers "F.Cu" "B.Cu")
		(net "PHY_IOC_TO_SCC_C_47_DP")
	)
	(arc
		(start 139.070842 -64.935354)
		(mid 139.030054 -64.962607)
		(end 138.981942 -64.972184)
		(width 0.12446)
		(layer "F.Cu")
		(net "PHY_IOC_TO_SCC_C_47_DP")
	)
	(arc
		(start 139.107418 -64.846962)
		(mid 139.097905 -64.894785)
		(end 139.070842 -64.935354)
		(width 0.12446)
		(layer "F.Cu")
		(net "PHY_IOC_TO_SCC_C_47_DP")
	)
	(arc
		(start 139.293092 -64.065658)
		(mid 139.155638 -64.271607)
		(end 139.107418 -64.514476)
		(width 0.12446)
		(layer "F.Cu")
		(net "PHY_IOC_TO_SCC_C_47_DP")
	)
	(arc
		(start 139.74191 -63.879984)
		(mid 139.499033 -63.928184)
		(end 139.293092 -64.065658)
		(width 0.12446)
		(layer "F.Cu")
		(net "PHY_IOC_TO_SCC_C_47_DP")
	)
	(segment
		(start 138.973814 -64.972184)
		(end 138.739118 -64.972184)
		(width 0.1016)
		(layer "In2.Cu")
		(net "PHY_IOC_TO_SCC_C_47_DP")
	)
	(segment
		(start 135.268716 -63.918846)
		(end 135.484362 -64.134238)
		(width 0.1016)
		(layer "In2.Cu")
		(net "PHY_IOC_TO_SCC_C_47_DP")
	)
	(segment
		(start 127 -60.000134)
		(end 126.684024 -60.000134)
		(width 0.0889)
		(layer "In2.Cu")
		(net "PHY_IOC_TO_SCC_C_47_DP")
	)
	(segment
		(start 130.032252 -59.652662)
		(end 130.672586 -60.292996)
		(width 0.1016)
		(layer "In2.Cu")
		(net "PHY_IOC_TO_SCC_C_47_DP")
	)
	(segment
		(start 126.595124 -59.911234)
		(end 126.595124 -59.685682)
		(width 0.0889)
		(layer "In2.Cu")
		(net "PHY_IOC_TO_SCC_C_47_DP")
	)
	(segment
		(start 129.583434 -59.595512)
		(end 129.640584 -59.652662)
		(width 0.0889)
		(layer "In2.Cu")
		(net "PHY_IOC_TO_SCC_C_47_DP")
	)
	(segment
		(start 135.753602 -64.134238)
		(end 135.969248 -64.349884)
		(width 0.1016)
		(layer "In2.Cu")
		(net "PHY_IOC_TO_SCC_C_47_DP")
	)
	(segment
		(start 129.662682 -59.652662)
		(end 130.032252 -59.652662)
		(width 0.1016)
		(layer "In2.Cu")
		(net "PHY_IOC_TO_SCC_C_47_DP")
	)
	(segment
		(start 129.640584 -59.652662)
		(end 129.662682 -59.652662)
		(width 0.0889)
		(layer "In2.Cu")
		(net "PHY_IOC_TO_SCC_C_47_DP")
	)
	(segment
		(start 139.158218 -64.566292)
		(end 139.158218 -64.788034)
		(width 0.1016)
		(layer "In2.Cu")
		(net "PHY_IOC_TO_SCC_C_47_DP")
	)
	(segment
		(start 135.484362 -64.134238)
		(end 135.753602 -64.134238)
		(width 0.1016)
		(layer "In2.Cu")
		(net "PHY_IOC_TO_SCC_C_47_DP")
	)
	(segment
		(start 135.969248 -64.349884)
		(end 138.94181 -64.349884)
		(width 0.1016)
		(layer "In2.Cu")
		(net "PHY_IOC_TO_SCC_C_47_DP")
	)
	(segment
		(start 131.91236 -60.292996)
		(end 135.268716 -63.649352)
		(width 0.1016)
		(layer "In2.Cu")
		(net "PHY_IOC_TO_SCC_C_47_DP")
	)
	(segment
		(start 130.672586 -60.292996)
		(end 131.91236 -60.292996)
		(width 0.1016)
		(layer "In2.Cu")
		(net "PHY_IOC_TO_SCC_C_47_DP")
	)
	(segment
		(start 139.104624 -64.918082)
		(end 139.10437 -64.918336)
		(width 0.1016)
		(layer "In2.Cu")
		(net "PHY_IOC_TO_SCC_C_47_DP")
	)
	(segment
		(start 126.685294 -59.595512)
		(end 129.583434 -59.595512)
		(width 0.0889)
		(layer "In2.Cu")
		(net "PHY_IOC_TO_SCC_C_47_DP")
	)
	(segment
		(start 135.268716 -63.649352)
		(end 135.268716 -63.918846)
		(width 0.1016)
		(layer "In2.Cu")
		(net "PHY_IOC_TO_SCC_C_47_DP")
	)
	(arc
		(start 126.595124 -59.685682)
		(mid 126.601988 -59.651175)
		(end 126.62154 -59.621928)
		(width 0.0889)
		(layer "In2.Cu")
		(net "PHY_IOC_TO_SCC_C_47_DP")
	)
	(arc
		(start 126.62154 -59.621928)
		(mid 126.650791 -59.602383)
		(end 126.685294 -59.595512)
		(width 0.0889)
		(layer "In2.Cu")
		(net "PHY_IOC_TO_SCC_C_47_DP")
	)
	(arc
		(start 126.684024 -60.000134)
		(mid 126.621162 -59.974096)
		(end 126.595124 -59.911234)
		(width 0.0889)
		(layer "In2.Cu")
		(net "PHY_IOC_TO_SCC_C_47_DP")
	)
	(arc
		(start 138.94181 -64.349884)
		(mid 139.094834 -64.413268)
		(end 139.158218 -64.566292)
		(width 0.1016)
		(layer "In2.Cu")
		(net "PHY_IOC_TO_SCC_C_47_DP")
	)
	(arc
		(start 139.158218 -64.788034)
		(mid 139.144299 -64.858368)
		(end 139.104624 -64.918082)
		(width 0.1016)
		(layer "In2.Cu")
		(net "PHY_IOC_TO_SCC_C_47_DP")
	)
	(arc
		(start 139.10437 -64.918336)
		(mid 139.044455 -64.958277)
		(end 138.973814 -64.972184)
		(width 0.1016)
		(layer "In2.Cu")
		(net "PHY_IOC_TO_SCC_C_47_DP")
	)
	(segment
		(start 125.50013 -60.500006)
		(end 126.000002 -60.000134)
		(width 0.104902)
		(layer "F.Cu")
		(net "PHY_IOC_TO_SCC_C_47_DN")
	)
	(segment
		(start 139.639548 -64.972184)
		(end 139.882118 -64.972184)
		(width 0.12446)
		(layer "F.Cu")
		(net "PHY_IOC_TO_SCC_C_47_DN")
	)
	(segment
		(start 142.498826 -64.375284)
		(end 142.26667 -64.375284)
		(width 0.12446)
		(layer "F.Cu")
		(net "PHY_IOC_TO_SCC_C_47_DN")
	)
	(segment
		(start 142.17777 -64.286384)
		(end 139.74191 -64.286384)
		(width 0.12446)
		(layer "F.Cu")
		(net "PHY_IOC_TO_SCC_C_47_DN")
	)
	(segment
		(start 139.550902 -64.9351)
		(end 139.551156 -64.935354)
		(width 0.12446)
		(layer "F.Cu")
		(net "PHY_IOC_TO_SCC_C_47_DN")
	)
	(segment
		(start 139.513818 -64.514476)
		(end 139.513818 -64.845946)
		(width 0.12446)
		(layer "F.Cu")
		(net "PHY_IOC_TO_SCC_C_47_DN")
	)
	(segment
		(start 142.26667 -64.375284)
		(end 142.17777 -64.286384)
		(width 0.12446)
		(layer "F.Cu")
		(net "PHY_IOC_TO_SCC_C_47_DN")
	)
	(via
		(at 126.000002 -60.000134)
		(size 0.4572)
		(drill 0.2032)
		(layers "F.Cu" "B.Cu")
		(net "PHY_IOC_TO_SCC_C_47_DN")
	)
	(arc
		(start 139.74191 -64.286384)
		(mid 139.654623 -64.303746)
		(end 139.58062 -64.353186)
		(width 0.12446)
		(layer "F.Cu")
		(net "PHY_IOC_TO_SCC_C_47_DN")
	)
	(arc
		(start 139.551156 -64.935354)
		(mid 139.591668 -64.962614)
		(end 139.639548 -64.972184)
		(width 0.12446)
		(layer "F.Cu")
		(net "PHY_IOC_TO_SCC_C_47_DN")
	)
	(arc
		(start 139.58062 -64.353186)
		(mid 139.531174 -64.427186)
		(end 139.513818 -64.514476)
		(width 0.12446)
		(layer "F.Cu")
		(net "PHY_IOC_TO_SCC_C_47_DN")
	)
	(arc
		(start 139.513818 -64.845946)
		(mid 139.52351 -64.894202)
		(end 139.550902 -64.9351)
		(width 0.12446)
		(layer "F.Cu")
		(net "PHY_IOC_TO_SCC_C_47_DN")
	)
	(segment
		(start 126.685294 -59.405012)
		(end 129.583434 -59.405012)
		(width 0.0889)
		(layer "In2.Cu")
		(net "PHY_IOC_TO_SCC_C_47_DN")
	)
	(segment
		(start 130.799078 -59.988196)
		(end 132.038852 -59.988196)
		(width 0.1016)
		(layer "In2.Cu")
		(net "PHY_IOC_TO_SCC_C_47_DN")
	)
	(segment
		(start 130.158744 -59.347862)
		(end 130.799078 -59.988196)
		(width 0.1016)
		(layer "In2.Cu")
		(net "PHY_IOC_TO_SCC_C_47_DN")
	)
	(segment
		(start 129.583434 -59.405012)
		(end 129.640584 -59.347862)
		(width 0.0889)
		(layer "In2.Cu")
		(net "PHY_IOC_TO_SCC_C_47_DN")
	)
	(segment
		(start 129.640584 -59.347862)
		(end 129.662682 -59.347862)
		(width 0.0889)
		(layer "In2.Cu")
		(net "PHY_IOC_TO_SCC_C_47_DN")
	)
	(segment
		(start 136.09574 -64.045084)
		(end 138.94181 -64.045084)
		(width 0.1016)
		(layer "In2.Cu")
		(net "PHY_IOC_TO_SCC_C_47_DN")
	)
	(segment
		(start 139.630658 -64.972184)
		(end 139.882118 -64.972184)
		(width 0.1016)
		(layer "In2.Cu")
		(net "PHY_IOC_TO_SCC_C_47_DN")
	)
	(segment
		(start 139.463018 -64.566292)
		(end 139.463018 -64.80429)
		(width 0.1016)
		(layer "In2.Cu")
		(net "PHY_IOC_TO_SCC_C_47_DN")
	)
	(segment
		(start 126.000002 -60.000134)
		(end 126.315724 -60.000134)
		(width 0.0889)
		(layer "In2.Cu")
		(net "PHY_IOC_TO_SCC_C_47_DN")
	)
	(segment
		(start 129.662682 -59.347862)
		(end 130.158744 -59.347862)
		(width 0.1016)
		(layer "In2.Cu")
		(net "PHY_IOC_TO_SCC_C_47_DN")
	)
	(segment
		(start 132.038852 -59.988196)
		(end 136.09574 -64.045084)
		(width 0.1016)
		(layer "In2.Cu")
		(net "PHY_IOC_TO_SCC_C_47_DN")
	)
	(segment
		(start 126.404624 -59.911234)
		(end 126.404624 -59.685682)
		(width 0.0889)
		(layer "In2.Cu")
		(net "PHY_IOC_TO_SCC_C_47_DN")
	)
	(arc
		(start 126.315724 -60.000134)
		(mid 126.378586 -59.974096)
		(end 126.404624 -59.911234)
		(width 0.0889)
		(layer "In2.Cu")
		(net "PHY_IOC_TO_SCC_C_47_DN")
	)
	(arc
		(start 126.404624 -59.685682)
		(mid 126.425906 -59.578221)
		(end 126.486666 -59.487054)
		(width 0.0889)
		(layer "In2.Cu")
		(net "PHY_IOC_TO_SCC_C_47_DN")
	)
	(arc
		(start 139.512294 -64.923162)
		(mid 139.5666 -64.959448)
		(end 139.630658 -64.972184)
		(width 0.1016)
		(layer "In2.Cu")
		(net "PHY_IOC_TO_SCC_C_47_DN")
	)
	(arc
		(start 138.94181 -64.045084)
		(mid 139.31036 -64.197742)
		(end 139.463018 -64.566292)
		(width 0.1016)
		(layer "In2.Cu")
		(net "PHY_IOC_TO_SCC_C_47_DN")
	)
	(arc
		(start 139.463018 -64.80429)
		(mid 139.475833 -64.868623)
		(end 139.512294 -64.923162)
		(width 0.1016)
		(layer "In2.Cu")
		(net "PHY_IOC_TO_SCC_C_47_DN")
	)
	(arc
		(start 126.486666 -59.487054)
		(mid 126.577812 -59.426245)
		(end 126.685294 -59.405012)
		(width 0.0889)
		(layer "In2.Cu")
		(net "PHY_IOC_TO_SCC_C_47_DN")
	)
	(segment
		(start 142.07236 -61.863986)
		(end 141.98346 -61.952886)
		(width 0.12446)
		(layer "F.Cu")
		(net "PHY_IOC_TO_SCC_C_46_DP")
	)
	(segment
		(start 139.047474 -63.045086)
		(end 138.80465 -63.045086)
		(width 0.12446)
		(layer "F.Cu")
		(net "PHY_IOC_TO_SCC_C_46_DP")
	)
	(segment
		(start 126.500128 -59.500008)
		(end 127 -59.000136)
		(width 0.104902)
		(layer "F.Cu")
		(net "PHY_IOC_TO_SCC_C_46_DP")
	)
	(segment
		(start 139.17295 -62.587378)
		(end 139.17295 -62.919864)
		(width 0.12446)
		(layer "F.Cu")
		(net "PHY_IOC_TO_SCC_C_46_DP")
	)
	(segment
		(start 141.98346 -61.952886)
		(end 139.807442 -61.952886)
		(width 0.12446)
		(layer "F.Cu")
		(net "PHY_IOC_TO_SCC_C_46_DP")
	)
	(via
		(at 127 -59.000136)
		(size 0.4572)
		(drill 0.2032)
		(layers "F.Cu" "B.Cu")
		(net "PHY_IOC_TO_SCC_C_46_DP")
	)
	(arc
		(start 139.807442 -61.952886)
		(mid 139.564565 -62.001086)
		(end 139.358624 -62.13856)
		(width 0.12446)
		(layer "F.Cu")
		(net "PHY_IOC_TO_SCC_C_46_DP")
	)
	(arc
		(start 139.136374 -63.008256)
		(mid 139.095586 -63.035509)
		(end 139.047474 -63.045086)
		(width 0.12446)
		(layer "F.Cu")
		(net "PHY_IOC_TO_SCC_C_46_DP")
	)
	(arc
		(start 139.17295 -62.919864)
		(mid 139.163437 -62.967687)
		(end 139.136374 -63.008256)
		(width 0.12446)
		(layer "F.Cu")
		(net "PHY_IOC_TO_SCC_C_46_DP")
	)
	(arc
		(start 139.358624 -62.13856)
		(mid 139.22117 -62.344509)
		(end 139.17295 -62.587378)
		(width 0.12446)
		(layer "F.Cu")
		(net "PHY_IOC_TO_SCC_C_46_DP")
	)
	(segment
		(start 135.23087 -61.991748)
		(end 135.446516 -62.20714)
		(width 0.1016)
		(layer "In2.Cu")
		(net "PHY_IOC_TO_SCC_C_46_DP")
	)
	(segment
		(start 135.23087 -61.722254)
		(end 135.23087 -61.991748)
		(width 0.1016)
		(layer "In2.Cu")
		(net "PHY_IOC_TO_SCC_C_46_DP")
	)
	(segment
		(start 126.595124 -58.911236)
		(end 126.595124 -58.703972)
		(width 0.0889)
		(layer "In2.Cu")
		(net "PHY_IOC_TO_SCC_C_46_DP")
	)
	(segment
		(start 135.931402 -62.422786)
		(end 139.007342 -62.422786)
		(width 0.1016)
		(layer "In2.Cu")
		(net "PHY_IOC_TO_SCC_C_46_DP")
	)
	(segment
		(start 135.446516 -62.20714)
		(end 135.715756 -62.20714)
		(width 0.1016)
		(layer "In2.Cu")
		(net "PHY_IOC_TO_SCC_C_46_DP")
	)
	(segment
		(start 131.61264 -58.997596)
		(end 131.66979 -59.054746)
		(width 0.0889)
		(layer "In2.Cu")
		(net "PHY_IOC_TO_SCC_C_46_DP")
	)
	(segment
		(start 130.72237 -58.997596)
		(end 131.61264 -58.997596)
		(width 0.0889)
		(layer "In2.Cu")
		(net "PHY_IOC_TO_SCC_C_46_DP")
	)
	(segment
		(start 139.170156 -62.990984)
		(end 139.169902 -62.991238)
		(width 0.1016)
		(layer "In2.Cu")
		(net "PHY_IOC_TO_SCC_C_46_DP")
	)
	(segment
		(start 130.320288 -58.595514)
		(end 130.72237 -58.997596)
		(width 0.0889)
		(layer "In2.Cu")
		(net "PHY_IOC_TO_SCC_C_46_DP")
	)
	(segment
		(start 127 -59.000136)
		(end 126.684024 -59.000136)
		(width 0.0889)
		(layer "In2.Cu")
		(net "PHY_IOC_TO_SCC_C_46_DP")
	)
	(segment
		(start 126.703582 -58.595514)
		(end 130.320288 -58.595514)
		(width 0.0889)
		(layer "In2.Cu")
		(net "PHY_IOC_TO_SCC_C_46_DP")
	)
	(segment
		(start 135.715756 -62.20714)
		(end 135.931402 -62.422786)
		(width 0.1016)
		(layer "In2.Cu")
		(net "PHY_IOC_TO_SCC_C_46_DP")
	)
	(segment
		(start 139.22375 -62.639194)
		(end 139.22375 -62.860936)
		(width 0.1016)
		(layer "In2.Cu")
		(net "PHY_IOC_TO_SCC_C_46_DP")
	)
	(segment
		(start 131.691888 -59.054746)
		(end 132.563362 -59.054746)
		(width 0.1016)
		(layer "In2.Cu")
		(net "PHY_IOC_TO_SCC_C_46_DP")
	)
	(segment
		(start 139.039346 -63.045086)
		(end 138.80465 -63.045086)
		(width 0.1016)
		(layer "In2.Cu")
		(net "PHY_IOC_TO_SCC_C_46_DP")
	)
	(segment
		(start 131.66979 -59.054746)
		(end 131.691888 -59.054746)
		(width 0.0889)
		(layer "In2.Cu")
		(net "PHY_IOC_TO_SCC_C_46_DP")
	)
	(segment
		(start 132.563362 -59.054746)
		(end 135.23087 -61.722254)
		(width 0.1016)
		(layer "In2.Cu")
		(net "PHY_IOC_TO_SCC_C_46_DP")
	)
	(arc
		(start 126.595124 -58.703972)
		(mid 126.60338 -58.662467)
		(end 126.626874 -58.627264)
		(width 0.0889)
		(layer "In2.Cu")
		(net "PHY_IOC_TO_SCC_C_46_DP")
	)
	(arc
		(start 126.684024 -59.000136)
		(mid 126.621162 -58.974098)
		(end 126.595124 -58.911236)
		(width 0.0889)
		(layer "In2.Cu")
		(net "PHY_IOC_TO_SCC_C_46_DP")
	)
	(arc
		(start 139.22375 -62.860936)
		(mid 139.209831 -62.93127)
		(end 139.170156 -62.990984)
		(width 0.1016)
		(layer "In2.Cu")
		(net "PHY_IOC_TO_SCC_C_46_DP")
	)
	(arc
		(start 126.626874 -58.627264)
		(mid 126.662068 -58.603748)
		(end 126.703582 -58.595514)
		(width 0.0889)
		(layer "In2.Cu")
		(net "PHY_IOC_TO_SCC_C_46_DP")
	)
	(arc
		(start 139.169902 -62.991238)
		(mid 139.109987 -63.031179)
		(end 139.039346 -63.045086)
		(width 0.1016)
		(layer "In2.Cu")
		(net "PHY_IOC_TO_SCC_C_46_DP")
	)
	(arc
		(start 139.007342 -62.422786)
		(mid 139.160366 -62.48617)
		(end 139.22375 -62.639194)
		(width 0.1016)
		(layer "In2.Cu")
		(net "PHY_IOC_TO_SCC_C_46_DP")
	)
	(segment
		(start 139.616434 -63.008002)
		(end 139.616688 -63.008256)
		(width 0.12446)
		(layer "F.Cu")
		(net "PHY_IOC_TO_SCC_C_46_DN")
	)
	(segment
		(start 139.70508 -63.045086)
		(end 139.94765 -63.045086)
		(width 0.12446)
		(layer "F.Cu")
		(net "PHY_IOC_TO_SCC_C_46_DN")
	)
	(segment
		(start 125.50013 -59.500008)
		(end 126.000002 -59.000136)
		(width 0.104902)
		(layer "F.Cu")
		(net "PHY_IOC_TO_SCC_C_46_DN")
	)
	(segment
		(start 139.57935 -62.587378)
		(end 139.57935 -62.918848)
		(width 0.12446)
		(layer "F.Cu")
		(net "PHY_IOC_TO_SCC_C_46_DN")
	)
	(segment
		(start 142.07236 -62.448186)
		(end 141.98346 -62.359286)
		(width 0.12446)
		(layer "F.Cu")
		(net "PHY_IOC_TO_SCC_C_46_DN")
	)
	(segment
		(start 141.98346 -62.359286)
		(end 139.807442 -62.359286)
		(width 0.12446)
		(layer "F.Cu")
		(net "PHY_IOC_TO_SCC_C_46_DN")
	)
	(via
		(at 126.000002 -59.000136)
		(size 0.4572)
		(drill 0.2032)
		(layers "F.Cu" "B.Cu")
		(net "PHY_IOC_TO_SCC_C_46_DN")
	)
	(arc
		(start 139.57935 -62.918848)
		(mid 139.589042 -62.967104)
		(end 139.616434 -63.008002)
		(width 0.12446)
		(layer "F.Cu")
		(net "PHY_IOC_TO_SCC_C_46_DN")
	)
	(arc
		(start 139.807442 -62.359286)
		(mid 139.720155 -62.376648)
		(end 139.646152 -62.426088)
		(width 0.12446)
		(layer "F.Cu")
		(net "PHY_IOC_TO_SCC_C_46_DN")
	)
	(arc
		(start 139.646152 -62.426088)
		(mid 139.596706 -62.500088)
		(end 139.57935 -62.587378)
		(width 0.12446)
		(layer "F.Cu")
		(net "PHY_IOC_TO_SCC_C_46_DN")
	)
	(arc
		(start 139.616688 -63.008256)
		(mid 139.6572 -63.035516)
		(end 139.70508 -63.045086)
		(width 0.12446)
		(layer "F.Cu")
		(net "PHY_IOC_TO_SCC_C_46_DN")
	)
	(segment
		(start 131.66979 -58.749946)
		(end 131.691888 -58.749946)
		(width 0.0889)
		(layer "In2.Cu")
		(net "PHY_IOC_TO_SCC_C_46_DN")
	)
	(segment
		(start 131.61264 -58.807096)
		(end 131.66979 -58.749946)
		(width 0.0889)
		(layer "In2.Cu")
		(net "PHY_IOC_TO_SCC_C_46_DN")
	)
	(segment
		(start 126.000002 -59.000136)
		(end 126.315724 -59.000136)
		(width 0.0889)
		(layer "In2.Cu")
		(net "PHY_IOC_TO_SCC_C_46_DN")
	)
	(segment
		(start 131.691888 -58.749946)
		(end 132.689854 -58.749946)
		(width 0.1016)
		(layer "In2.Cu")
		(net "PHY_IOC_TO_SCC_C_46_DN")
	)
	(segment
		(start 139.52855 -62.639194)
		(end 139.52855 -62.877192)
		(width 0.1016)
		(layer "In2.Cu")
		(net "PHY_IOC_TO_SCC_C_46_DN")
	)
	(segment
		(start 130.399282 -58.405014)
		(end 130.801364 -58.807096)
		(width 0.0889)
		(layer "In2.Cu")
		(net "PHY_IOC_TO_SCC_C_46_DN")
	)
	(segment
		(start 126.703582 -58.405014)
		(end 130.399282 -58.405014)
		(width 0.0889)
		(layer "In2.Cu")
		(net "PHY_IOC_TO_SCC_C_46_DN")
	)
	(segment
		(start 130.801364 -58.807096)
		(end 131.61264 -58.807096)
		(width 0.0889)
		(layer "In2.Cu")
		(net "PHY_IOC_TO_SCC_C_46_DN")
	)
	(segment
		(start 132.689854 -58.749946)
		(end 136.057894 -62.117986)
		(width 0.1016)
		(layer "In2.Cu")
		(net "PHY_IOC_TO_SCC_C_46_DN")
	)
	(segment
		(start 126.404624 -58.911236)
		(end 126.404624 -58.703972)
		(width 0.0889)
		(layer "In2.Cu")
		(net "PHY_IOC_TO_SCC_C_46_DN")
	)
	(segment
		(start 139.69619 -63.045086)
		(end 139.94765 -63.045086)
		(width 0.1016)
		(layer "In2.Cu")
		(net "PHY_IOC_TO_SCC_C_46_DN")
	)
	(segment
		(start 136.057894 -62.117986)
		(end 139.007342 -62.117986)
		(width 0.1016)
		(layer "In2.Cu")
		(net "PHY_IOC_TO_SCC_C_46_DN")
	)
	(arc
		(start 139.007342 -62.117986)
		(mid 139.375892 -62.270644)
		(end 139.52855 -62.639194)
		(width 0.1016)
		(layer "In2.Cu")
		(net "PHY_IOC_TO_SCC_C_46_DN")
	)
	(arc
		(start 126.315724 -59.000136)
		(mid 126.378586 -58.974098)
		(end 126.404624 -58.911236)
		(width 0.0889)
		(layer "In2.Cu")
		(net "PHY_IOC_TO_SCC_C_46_DN")
	)
	(arc
		(start 126.404624 -58.703972)
		(mid 126.427283 -58.589498)
		(end 126.492 -58.49239)
		(width 0.0889)
		(layer "In2.Cu")
		(net "PHY_IOC_TO_SCC_C_46_DN")
	)
	(arc
		(start 139.577826 -62.996064)
		(mid 139.632132 -63.03235)
		(end 139.69619 -63.045086)
		(width 0.1016)
		(layer "In2.Cu")
		(net "PHY_IOC_TO_SCC_C_46_DN")
	)
	(arc
		(start 139.52855 -62.877192)
		(mid 139.541365 -62.941525)
		(end 139.577826 -62.996064)
		(width 0.1016)
		(layer "In2.Cu")
		(net "PHY_IOC_TO_SCC_C_46_DN")
	)
	(arc
		(start 126.492 -58.49239)
		(mid 126.589104 -58.427663)
		(end 126.703582 -58.405014)
		(width 0.0889)
		(layer "In2.Cu")
		(net "PHY_IOC_TO_SCC_C_46_DN")
	)
	(segment
		(start 142.20952 -60.029852)
		(end 140.033502 -60.029852)
		(width 0.12446)
		(layer "F.Cu")
		(net "PHY_IOC_TO_SCC_C_45_DP")
	)
	(segment
		(start 139.39901 -60.664344)
		(end 139.39901 -60.99683)
		(width 0.12446)
		(layer "F.Cu")
		(net "PHY_IOC_TO_SCC_C_45_DP")
	)
	(segment
		(start 142.29842 -59.940952)
		(end 142.20952 -60.029852)
		(width 0.12446)
		(layer "F.Cu")
		(net "PHY_IOC_TO_SCC_C_45_DP")
	)
	(segment
		(start 126.500128 -58.50001)
		(end 127 -58.000138)
		(width 0.104902)
		(layer "F.Cu")
		(net "PHY_IOC_TO_SCC_C_45_DP")
	)
	(segment
		(start 139.273534 -61.122052)
		(end 139.03071 -61.122052)
		(width 0.12446)
		(layer "F.Cu")
		(net "PHY_IOC_TO_SCC_C_45_DP")
	)
	(via
		(at 127 -58.000138)
		(size 0.4572)
		(drill 0.2032)
		(layers "F.Cu" "B.Cu")
		(net "PHY_IOC_TO_SCC_C_45_DP")
	)
	(arc
		(start 139.362434 -61.085222)
		(mid 139.321646 -61.112475)
		(end 139.273534 -61.122052)
		(width 0.12446)
		(layer "F.Cu")
		(net "PHY_IOC_TO_SCC_C_45_DP")
	)
	(arc
		(start 139.584684 -60.215526)
		(mid 139.44723 -60.421475)
		(end 139.39901 -60.664344)
		(width 0.12446)
		(layer "F.Cu")
		(net "PHY_IOC_TO_SCC_C_45_DP")
	)
	(arc
		(start 140.033502 -60.029852)
		(mid 139.790625 -60.078052)
		(end 139.584684 -60.215526)
		(width 0.12446)
		(layer "F.Cu")
		(net "PHY_IOC_TO_SCC_C_45_DP")
	)
	(arc
		(start 139.39901 -60.99683)
		(mid 139.389497 -61.044653)
		(end 139.362434 -61.085222)
		(width 0.12446)
		(layer "F.Cu")
		(net "PHY_IOC_TO_SCC_C_45_DP")
	)
	(segment
		(start 131.695952 -58.242962)
		(end 133.863334 -58.242962)
		(width 0.1016)
		(layer "In2.Cu")
		(net "PHY_IOC_TO_SCC_C_45_DP")
	)
	(segment
		(start 135.419592 -59.79922)
		(end 135.419592 -60.068714)
		(width 0.1016)
		(layer "In2.Cu")
		(net "PHY_IOC_TO_SCC_C_45_DP")
	)
	(segment
		(start 139.44981 -60.71616)
		(end 139.44981 -60.937902)
		(width 0.1016)
		(layer "In2.Cu")
		(net "PHY_IOC_TO_SCC_C_45_DP")
	)
	(segment
		(start 131.673854 -58.242962)
		(end 131.695952 -58.242962)
		(width 0.0889)
		(layer "In2.Cu")
		(net "PHY_IOC_TO_SCC_C_45_DP")
	)
	(segment
		(start 133.863334 -58.242962)
		(end 135.419592 -59.79922)
		(width 0.1016)
		(layer "In2.Cu")
		(net "PHY_IOC_TO_SCC_C_45_DP")
	)
	(segment
		(start 139.396216 -61.06795)
		(end 139.395962 -61.068204)
		(width 0.1016)
		(layer "In2.Cu")
		(net "PHY_IOC_TO_SCC_C_45_DP")
	)
	(segment
		(start 131.616704 -58.185812)
		(end 131.673854 -58.242962)
		(width 0.0889)
		(layer "In2.Cu")
		(net "PHY_IOC_TO_SCC_C_45_DP")
	)
	(segment
		(start 127 -58.000138)
		(end 126.684024 -58.000138)
		(width 0.0889)
		(layer "In2.Cu")
		(net "PHY_IOC_TO_SCC_C_45_DP")
	)
	(segment
		(start 130.923284 -58.185812)
		(end 131.616704 -58.185812)
		(width 0.0889)
		(layer "In2.Cu")
		(net "PHY_IOC_TO_SCC_C_45_DP")
	)
	(segment
		(start 139.265406 -61.122052)
		(end 139.03071 -61.122052)
		(width 0.1016)
		(layer "In2.Cu")
		(net "PHY_IOC_TO_SCC_C_45_DP")
	)
	(segment
		(start 130.33502 -57.597548)
		(end 130.923284 -58.185812)
		(width 0.0889)
		(layer "In2.Cu")
		(net "PHY_IOC_TO_SCC_C_45_DP")
	)
	(segment
		(start 126.595124 -57.911238)
		(end 126.595124 -57.738518)
		(width 0.0889)
		(layer "In2.Cu")
		(net "PHY_IOC_TO_SCC_C_45_DP")
	)
	(segment
		(start 135.904478 -60.284106)
		(end 136.120124 -60.499752)
		(width 0.1016)
		(layer "In2.Cu")
		(net "PHY_IOC_TO_SCC_C_45_DP")
	)
	(segment
		(start 126.73584 -57.597548)
		(end 130.33502 -57.597548)
		(width 0.0889)
		(layer "In2.Cu")
		(net "PHY_IOC_TO_SCC_C_45_DP")
	)
	(segment
		(start 135.635238 -60.284106)
		(end 135.904478 -60.284106)
		(width 0.1016)
		(layer "In2.Cu")
		(net "PHY_IOC_TO_SCC_C_45_DP")
	)
	(segment
		(start 135.419592 -60.068714)
		(end 135.635238 -60.284106)
		(width 0.1016)
		(layer "In2.Cu")
		(net "PHY_IOC_TO_SCC_C_45_DP")
	)
	(segment
		(start 136.120124 -60.499752)
		(end 139.233402 -60.499752)
		(width 0.1016)
		(layer "In2.Cu")
		(net "PHY_IOC_TO_SCC_C_45_DP")
	)
	(arc
		(start 139.395962 -61.068204)
		(mid 139.336047 -61.108145)
		(end 139.265406 -61.122052)
		(width 0.1016)
		(layer "In2.Cu")
		(net "PHY_IOC_TO_SCC_C_45_DP")
	)
	(arc
		(start 126.636526 -57.638696)
		(mid 126.682092 -57.60825)
		(end 126.73584 -57.597548)
		(width 0.0889)
		(layer "In2.Cu")
		(net "PHY_IOC_TO_SCC_C_45_DP")
	)
	(arc
		(start 126.595124 -57.738518)
		(mid 126.605889 -57.684488)
		(end 126.636526 -57.638696)
		(width 0.0889)
		(layer "In2.Cu")
		(net "PHY_IOC_TO_SCC_C_45_DP")
	)
	(arc
		(start 139.233402 -60.499752)
		(mid 139.386426 -60.563136)
		(end 139.44981 -60.71616)
		(width 0.1016)
		(layer "In2.Cu")
		(net "PHY_IOC_TO_SCC_C_45_DP")
	)
	(arc
		(start 139.44981 -60.937902)
		(mid 139.435891 -61.008236)
		(end 139.396216 -61.06795)
		(width 0.1016)
		(layer "In2.Cu")
		(net "PHY_IOC_TO_SCC_C_45_DP")
	)
	(arc
		(start 126.684024 -58.000138)
		(mid 126.621162 -57.9741)
		(end 126.595124 -57.911238)
		(width 0.0889)
		(layer "In2.Cu")
		(net "PHY_IOC_TO_SCC_C_45_DP")
	)
	(segment
		(start 125.50013 -58.50001)
		(end 126.000002 -58.000138)
		(width 0.104902)
		(layer "F.Cu")
		(net "PHY_IOC_TO_SCC_C_45_DN")
	)
	(segment
		(start 139.842494 -61.084968)
		(end 139.842748 -61.085222)
		(width 0.12446)
		(layer "F.Cu")
		(net "PHY_IOC_TO_SCC_C_45_DN")
	)
	(segment
		(start 139.80541 -60.664344)
		(end 139.80541 -60.995814)
		(width 0.12446)
		(layer "F.Cu")
		(net "PHY_IOC_TO_SCC_C_45_DN")
	)
	(segment
		(start 139.93114 -61.122052)
		(end 140.17371 -61.122052)
		(width 0.12446)
		(layer "F.Cu")
		(net "PHY_IOC_TO_SCC_C_45_DN")
	)
	(segment
		(start 142.20952 -60.436252)
		(end 140.033502 -60.436252)
		(width 0.12446)
		(layer "F.Cu")
		(net "PHY_IOC_TO_SCC_C_45_DN")
	)
	(segment
		(start 142.29842 -60.525152)
		(end 142.20952 -60.436252)
		(width 0.12446)
		(layer "F.Cu")
		(net "PHY_IOC_TO_SCC_C_45_DN")
	)
	(via
		(at 126.000002 -58.000138)
		(size 0.4572)
		(drill 0.2032)
		(layers "F.Cu" "B.Cu")
		(net "PHY_IOC_TO_SCC_C_45_DN")
	)
	(arc
		(start 139.80541 -60.995814)
		(mid 139.815102 -61.04407)
		(end 139.842494 -61.084968)
		(width 0.12446)
		(layer "F.Cu")
		(net "PHY_IOC_TO_SCC_C_45_DN")
	)
	(arc
		(start 139.872212 -60.503054)
		(mid 139.822766 -60.577054)
		(end 139.80541 -60.664344)
		(width 0.12446)
		(layer "F.Cu")
		(net "PHY_IOC_TO_SCC_C_45_DN")
	)
	(arc
		(start 139.842748 -61.085222)
		(mid 139.88326 -61.112482)
		(end 139.93114 -61.122052)
		(width 0.12446)
		(layer "F.Cu")
		(net "PHY_IOC_TO_SCC_C_45_DN")
	)
	(arc
		(start 140.033502 -60.436252)
		(mid 139.946215 -60.453614)
		(end 139.872212 -60.503054)
		(width 0.12446)
		(layer "F.Cu")
		(net "PHY_IOC_TO_SCC_C_45_DN")
	)
	(segment
		(start 131.673854 -57.938162)
		(end 131.695952 -57.938162)
		(width 0.0889)
		(layer "In2.Cu")
		(net "PHY_IOC_TO_SCC_C_45_DN")
	)
	(segment
		(start 133.989826 -57.938162)
		(end 136.246616 -60.194952)
		(width 0.1016)
		(layer "In2.Cu")
		(net "PHY_IOC_TO_SCC_C_45_DN")
	)
	(segment
		(start 139.75461 -60.71616)
		(end 139.75461 -60.954158)
		(width 0.1016)
		(layer "In2.Cu")
		(net "PHY_IOC_TO_SCC_C_45_DN")
	)
	(segment
		(start 136.246616 -60.194952)
		(end 139.233402 -60.194952)
		(width 0.1016)
		(layer "In2.Cu")
		(net "PHY_IOC_TO_SCC_C_45_DN")
	)
	(segment
		(start 139.92225 -61.122052)
		(end 140.17371 -61.122052)
		(width 0.1016)
		(layer "In2.Cu")
		(net "PHY_IOC_TO_SCC_C_45_DN")
	)
	(segment
		(start 130.414014 -57.407048)
		(end 131.002278 -57.995312)
		(width 0.0889)
		(layer "In2.Cu")
		(net "PHY_IOC_TO_SCC_C_45_DN")
	)
	(segment
		(start 126.73584 -57.407048)
		(end 130.414014 -57.407048)
		(width 0.0889)
		(layer "In2.Cu")
		(net "PHY_IOC_TO_SCC_C_45_DN")
	)
	(segment
		(start 126.404624 -57.911238)
		(end 126.404624 -57.738518)
		(width 0.0889)
		(layer "In2.Cu")
		(net "PHY_IOC_TO_SCC_C_45_DN")
	)
	(segment
		(start 131.616704 -57.995312)
		(end 131.673854 -57.938162)
		(width 0.0889)
		(layer "In2.Cu")
		(net "PHY_IOC_TO_SCC_C_45_DN")
	)
	(segment
		(start 131.695952 -57.938162)
		(end 133.989826 -57.938162)
		(width 0.1016)
		(layer "In2.Cu")
		(net "PHY_IOC_TO_SCC_C_45_DN")
	)
	(segment
		(start 131.002278 -57.995312)
		(end 131.616704 -57.995312)
		(width 0.0889)
		(layer "In2.Cu")
		(net "PHY_IOC_TO_SCC_C_45_DN")
	)
	(segment
		(start 126.000002 -58.000138)
		(end 126.315724 -58.000138)
		(width 0.0889)
		(layer "In2.Cu")
		(net "PHY_IOC_TO_SCC_C_45_DN")
	)
	(arc
		(start 126.315724 -58.000138)
		(mid 126.378586 -57.9741)
		(end 126.404624 -57.911238)
		(width 0.0889)
		(layer "In2.Cu")
		(net "PHY_IOC_TO_SCC_C_45_DN")
	)
	(arc
		(start 126.501906 -57.503822)
		(mid 126.609264 -57.432214)
		(end 126.73584 -57.407048)
		(width 0.0889)
		(layer "In2.Cu")
		(net "PHY_IOC_TO_SCC_C_45_DN")
	)
	(arc
		(start 139.75461 -60.954158)
		(mid 139.767425 -61.018491)
		(end 139.803886 -61.07303)
		(width 0.1016)
		(layer "In2.Cu")
		(net "PHY_IOC_TO_SCC_C_45_DN")
	)
	(arc
		(start 139.803886 -61.07303)
		(mid 139.858192 -61.109316)
		(end 139.92225 -61.122052)
		(width 0.1016)
		(layer "In2.Cu")
		(net "PHY_IOC_TO_SCC_C_45_DN")
	)
	(arc
		(start 139.233402 -60.194952)
		(mid 139.601952 -60.34761)
		(end 139.75461 -60.71616)
		(width 0.1016)
		(layer "In2.Cu")
		(net "PHY_IOC_TO_SCC_C_45_DN")
	)
	(arc
		(start 126.404624 -57.738518)
		(mid 126.429909 -57.61149)
		(end 126.501906 -57.503822)
		(width 0.0889)
		(layer "In2.Cu")
		(net "PHY_IOC_TO_SCC_C_45_DN")
	)
	(segment
		(start 139.8143 -58.444892)
		(end 139.8143 -58.777378)
		(width 0.12446)
		(layer "F.Cu")
		(net "PHY_IOC_TO_SCC_C_44_DP")
	)
	(segment
		(start 126.500128 -57.500012)
		(end 127 -57.00014)
		(width 0.104902)
		(layer "F.Cu")
		(net "PHY_IOC_TO_SCC_C_44_DP")
	)
	(segment
		(start 142.62481 -57.8104)
		(end 140.448792 -57.8104)
		(width 0.12446)
		(layer "F.Cu")
		(net "PHY_IOC_TO_SCC_C_44_DP")
	)
	(segment
		(start 142.71371 -57.7215)
		(end 142.62481 -57.8104)
		(width 0.12446)
		(layer "F.Cu")
		(net "PHY_IOC_TO_SCC_C_44_DP")
	)
	(segment
		(start 139.688824 -58.9026)
		(end 139.446 -58.9026)
		(width 0.12446)
		(layer "F.Cu")
		(net "PHY_IOC_TO_SCC_C_44_DP")
	)
	(via
		(at 127 -57.00014)
		(size 0.4572)
		(drill 0.2032)
		(layers "F.Cu" "B.Cu")
		(net "PHY_IOC_TO_SCC_C_44_DP")
	)
	(arc
		(start 140.448792 -57.8104)
		(mid 140.205915 -57.8586)
		(end 139.999974 -57.996074)
		(width 0.12446)
		(layer "F.Cu")
		(net "PHY_IOC_TO_SCC_C_44_DP")
	)
	(arc
		(start 139.8143 -58.777378)
		(mid 139.804787 -58.825201)
		(end 139.777724 -58.86577)
		(width 0.12446)
		(layer "F.Cu")
		(net "PHY_IOC_TO_SCC_C_44_DP")
	)
	(arc
		(start 139.777724 -58.86577)
		(mid 139.736936 -58.893023)
		(end 139.688824 -58.9026)
		(width 0.12446)
		(layer "F.Cu")
		(net "PHY_IOC_TO_SCC_C_44_DP")
	)
	(arc
		(start 139.999974 -57.996074)
		(mid 139.86252 -58.202023)
		(end 139.8143 -58.444892)
		(width 0.12446)
		(layer "F.Cu")
		(net "PHY_IOC_TO_SCC_C_44_DP")
	)
	(segment
		(start 126.595124 -56.91124)
		(end 126.595124 -56.701944)
		(width 0.0889)
		(layer "In2.Cu")
		(net "PHY_IOC_TO_SCC_C_44_DP")
	)
	(segment
		(start 129.276602 -56.651144)
		(end 129.2987 -56.651144)
		(width 0.0889)
		(layer "In2.Cu")
		(net "PHY_IOC_TO_SCC_C_44_DP")
	)
	(segment
		(start 134.451852 -56.651144)
		(end 136.081008 -58.2803)
		(width 0.1016)
		(layer "In2.Cu")
		(net "PHY_IOC_TO_SCC_C_44_DP")
	)
	(segment
		(start 127 -57.00014)
		(end 126.684024 -57.00014)
		(width 0.0889)
		(layer "In2.Cu")
		(net "PHY_IOC_TO_SCC_C_44_DP")
	)
	(segment
		(start 129.2987 -56.651144)
		(end 134.451852 -56.651144)
		(width 0.1016)
		(layer "In2.Cu")
		(net "PHY_IOC_TO_SCC_C_44_DP")
	)
	(segment
		(start 137.080244 -58.4708)
		(end 137.270744 -58.2803)
		(width 0.1016)
		(layer "In2.Cu")
		(net "PHY_IOC_TO_SCC_C_44_DP")
	)
	(segment
		(start 139.8651 -58.496708)
		(end 139.8651 -58.71845)
		(width 0.1016)
		(layer "In2.Cu")
		(net "PHY_IOC_TO_SCC_C_44_DP")
	)
	(segment
		(start 139.680696 -58.9026)
		(end 139.446 -58.9026)
		(width 0.1016)
		(layer "In2.Cu")
		(net "PHY_IOC_TO_SCC_C_44_DP")
	)
	(segment
		(start 129.219452 -56.593994)
		(end 129.276602 -56.651144)
		(width 0.0889)
		(layer "In2.Cu")
		(net "PHY_IOC_TO_SCC_C_44_DP")
	)
	(segment
		(start 136.775444 -58.4708)
		(end 137.080244 -58.4708)
		(width 0.1016)
		(layer "In2.Cu")
		(net "PHY_IOC_TO_SCC_C_44_DP")
	)
	(segment
		(start 136.081008 -58.2803)
		(end 136.584944 -58.2803)
		(width 0.1016)
		(layer "In2.Cu")
		(net "PHY_IOC_TO_SCC_C_44_DP")
	)
	(segment
		(start 136.584944 -58.2803)
		(end 136.775444 -58.4708)
		(width 0.1016)
		(layer "In2.Cu")
		(net "PHY_IOC_TO_SCC_C_44_DP")
	)
	(segment
		(start 137.270744 -58.2803)
		(end 139.648692 -58.2803)
		(width 0.1016)
		(layer "In2.Cu")
		(net "PHY_IOC_TO_SCC_C_44_DP")
	)
	(segment
		(start 126.626874 -56.625744)
		(end 126.632208 -56.62041)
		(width 0.0889)
		(layer "In2.Cu")
		(net "PHY_IOC_TO_SCC_C_44_DP")
	)
	(segment
		(start 126.695454 -56.593994)
		(end 129.219452 -56.593994)
		(width 0.0889)
		(layer "In2.Cu")
		(net "PHY_IOC_TO_SCC_C_44_DP")
	)
	(segment
		(start 139.811506 -58.848498)
		(end 139.811252 -58.848752)
		(width 0.1016)
		(layer "In2.Cu")
		(net "PHY_IOC_TO_SCC_C_44_DP")
	)
	(arc
		(start 126.595124 -56.701944)
		(mid 126.603424 -56.660687)
		(end 126.626874 -56.625744)
		(width 0.0889)
		(layer "In2.Cu")
		(net "PHY_IOC_TO_SCC_C_44_DP")
	)
	(arc
		(start 139.648692 -58.2803)
		(mid 139.801716 -58.343684)
		(end 139.8651 -58.496708)
		(width 0.1016)
		(layer "In2.Cu")
		(net "PHY_IOC_TO_SCC_C_44_DP")
	)
	(arc
		(start 139.811252 -58.848752)
		(mid 139.751337 -58.888693)
		(end 139.680696 -58.9026)
		(width 0.1016)
		(layer "In2.Cu")
		(net "PHY_IOC_TO_SCC_C_44_DP")
	)
	(arc
		(start 126.684024 -57.00014)
		(mid 126.621162 -56.974102)
		(end 126.595124 -56.91124)
		(width 0.0889)
		(layer "In2.Cu")
		(net "PHY_IOC_TO_SCC_C_44_DP")
	)
	(arc
		(start 139.8651 -58.71845)
		(mid 139.851181 -58.788784)
		(end 139.811506 -58.848498)
		(width 0.1016)
		(layer "In2.Cu")
		(net "PHY_IOC_TO_SCC_C_44_DP")
	)
	(arc
		(start 126.632208 -56.62041)
		(mid 126.661182 -56.600859)
		(end 126.695454 -56.593994)
		(width 0.0889)
		(layer "In2.Cu")
		(net "PHY_IOC_TO_SCC_C_44_DP")
	)
	(segment
		(start 142.71371 -58.3057)
		(end 142.62481 -58.2168)
		(width 0.12446)
		(layer "F.Cu")
		(net "PHY_IOC_TO_SCC_C_44_DN")
	)
	(segment
		(start 140.2207 -58.444892)
		(end 140.2207 -58.776362)
		(width 0.12446)
		(layer "F.Cu")
		(net "PHY_IOC_TO_SCC_C_44_DN")
	)
	(segment
		(start 140.257784 -58.865516)
		(end 140.258038 -58.86577)
		(width 0.12446)
		(layer "F.Cu")
		(net "PHY_IOC_TO_SCC_C_44_DN")
	)
	(segment
		(start 140.34643 -58.9026)
		(end 140.589 -58.9026)
		(width 0.12446)
		(layer "F.Cu")
		(net "PHY_IOC_TO_SCC_C_44_DN")
	)
	(segment
		(start 142.62481 -58.2168)
		(end 140.448792 -58.2168)
		(width 0.12446)
		(layer "F.Cu")
		(net "PHY_IOC_TO_SCC_C_44_DN")
	)
	(segment
		(start 125.50013 -57.500012)
		(end 126.000002 -57.00014)
		(width 0.104902)
		(layer "F.Cu")
		(net "PHY_IOC_TO_SCC_C_44_DN")
	)
	(via
		(at 126.000002 -57.00014)
		(size 0.4572)
		(drill 0.2032)
		(layers "F.Cu" "B.Cu")
		(net "PHY_IOC_TO_SCC_C_44_DN")
	)
	(arc
		(start 140.2207 -58.776362)
		(mid 140.230392 -58.824618)
		(end 140.257784 -58.865516)
		(width 0.12446)
		(layer "F.Cu")
		(net "PHY_IOC_TO_SCC_C_44_DN")
	)
	(arc
		(start 140.258038 -58.86577)
		(mid 140.29855 -58.89303)
		(end 140.34643 -58.9026)
		(width 0.12446)
		(layer "F.Cu")
		(net "PHY_IOC_TO_SCC_C_44_DN")
	)
	(arc
		(start 140.448792 -58.2168)
		(mid 140.361505 -58.234162)
		(end 140.287502 -58.283602)
		(width 0.12446)
		(layer "F.Cu")
		(net "PHY_IOC_TO_SCC_C_44_DN")
	)
	(arc
		(start 140.287502 -58.283602)
		(mid 140.238056 -58.357602)
		(end 140.2207 -58.444892)
		(width 0.12446)
		(layer "F.Cu")
		(net "PHY_IOC_TO_SCC_C_44_DN")
	)
	(segment
		(start 136.2075 -57.9755)
		(end 139.648692 -57.9755)
		(width 0.1016)
		(layer "In2.Cu")
		(net "PHY_IOC_TO_SCC_C_44_DN")
	)
	(segment
		(start 126.000002 -57.00014)
		(end 126.315724 -57.00014)
		(width 0.0889)
		(layer "In2.Cu")
		(net "PHY_IOC_TO_SCC_C_44_DN")
	)
	(segment
		(start 140.1699 -58.496708)
		(end 140.1699 -58.734706)
		(width 0.1016)
		(layer "In2.Cu")
		(net "PHY_IOC_TO_SCC_C_44_DN")
	)
	(segment
		(start 129.276602 -56.346344)
		(end 129.2987 -56.346344)
		(width 0.0889)
		(layer "In2.Cu")
		(net "PHY_IOC_TO_SCC_C_44_DN")
	)
	(segment
		(start 129.2987 -56.346344)
		(end 134.578344 -56.346344)
		(width 0.1016)
		(layer "In2.Cu")
		(net "PHY_IOC_TO_SCC_C_44_DN")
	)
	(segment
		(start 129.219452 -56.403494)
		(end 129.276602 -56.346344)
		(width 0.0889)
		(layer "In2.Cu")
		(net "PHY_IOC_TO_SCC_C_44_DN")
	)
	(segment
		(start 126.492254 -56.49087)
		(end 126.49708 -56.48579)
		(width 0.0889)
		(layer "In2.Cu")
		(net "PHY_IOC_TO_SCC_C_44_DN")
	)
	(segment
		(start 140.33754 -58.9026)
		(end 140.589 -58.9026)
		(width 0.1016)
		(layer "In2.Cu")
		(net "PHY_IOC_TO_SCC_C_44_DN")
	)
	(segment
		(start 134.578344 -56.346344)
		(end 136.2075 -57.9755)
		(width 0.1016)
		(layer "In2.Cu")
		(net "PHY_IOC_TO_SCC_C_44_DN")
	)
	(segment
		(start 126.695454 -56.403494)
		(end 129.219452 -56.403494)
		(width 0.0889)
		(layer "In2.Cu")
		(net "PHY_IOC_TO_SCC_C_44_DN")
	)
	(segment
		(start 126.404624 -56.91124)
		(end 126.404624 -56.70169)
		(width 0.0889)
		(layer "In2.Cu")
		(net "PHY_IOC_TO_SCC_C_44_DN")
	)
	(arc
		(start 139.648692 -57.9755)
		(mid 140.017242 -58.128158)
		(end 140.1699 -58.496708)
		(width 0.1016)
		(layer "In2.Cu")
		(net "PHY_IOC_TO_SCC_C_44_DN")
	)
	(arc
		(start 126.49708 -56.48579)
		(mid 126.588053 -56.424844)
		(end 126.695454 -56.403494)
		(width 0.0889)
		(layer "In2.Cu")
		(net "PHY_IOC_TO_SCC_C_44_DN")
	)
	(arc
		(start 126.315724 -57.00014)
		(mid 126.378586 -56.974102)
		(end 126.404624 -56.91124)
		(width 0.0889)
		(layer "In2.Cu")
		(net "PHY_IOC_TO_SCC_C_44_DN")
	)
	(arc
		(start 140.219176 -58.853578)
		(mid 140.273482 -58.889864)
		(end 140.33754 -58.9026)
		(width 0.1016)
		(layer "In2.Cu")
		(net "PHY_IOC_TO_SCC_C_44_DN")
	)
	(arc
		(start 140.1699 -58.734706)
		(mid 140.182715 -58.799039)
		(end 140.219176 -58.853578)
		(width 0.1016)
		(layer "In2.Cu")
		(net "PHY_IOC_TO_SCC_C_44_DN")
	)
	(arc
		(start 126.404624 -56.70169)
		(mid 126.427508 -56.587586)
		(end 126.492254 -56.49087)
		(width 0.0889)
		(layer "In2.Cu")
		(net "PHY_IOC_TO_SCC_C_44_DN")
	)
	(segment
		(start 133.23443 -45.437552)
		(end 133.14553 -45.348652)
		(width 0.12446)
		(layer "F.Cu")
		(net "PHY_IOC_TO_SCC_C_43_DP")
	)
	(segment
		(start 132.331206 -46.183042)
		(end 132.883402 -46.183042)
		(width 0.12446)
		(layer "F.Cu")
		(net "PHY_IOC_TO_SCC_C_43_DP")
	)
	(segment
		(start 132.220208 -45.814742)
		(end 132.220208 -46.072044)
		(width 0.12446)
		(layer "F.Cu")
		(net "PHY_IOC_TO_SCC_C_43_DP")
	)
	(segment
		(start 133.14553 -45.348652)
		(end 133.14553 -44.982384)
		(width 0.12446)
		(layer "F.Cu")
		(net "PHY_IOC_TO_SCC_C_43_DP")
	)
	(segment
		(start 126.500128 -56.500014)
		(end 127 -56.000142)
		(width 0.104902)
		(layer "F.Cu")
		(net "PHY_IOC_TO_SCC_C_43_DP")
	)
	(segment
		(start 133.23443 -45.832014)
		(end 133.23443 -45.437552)
		(width 0.12446)
		(layer "F.Cu")
		(net "PHY_IOC_TO_SCC_C_43_DP")
	)
	(via
		(at 127 -56.000142)
		(size 0.4572)
		(drill 0.2032)
		(layers "F.Cu" "B.Cu")
		(net "PHY_IOC_TO_SCC_C_43_DP")
	)
	(arc
		(start 132.25272 -46.15053)
		(mid 132.28873 -46.174591)
		(end 132.331206 -46.183042)
		(width 0.12446)
		(layer "F.Cu")
		(net "PHY_IOC_TO_SCC_C_43_DP")
	)
	(arc
		(start 132.883402 -46.183042)
		(mid 133.01772 -46.156307)
		(end 133.13156 -46.080172)
		(width 0.12446)
		(layer "F.Cu")
		(net "PHY_IOC_TO_SCC_C_43_DP")
	)
	(arc
		(start 132.220208 -46.072044)
		(mid 132.228657 -46.114521)
		(end 132.25272 -46.15053)
		(width 0.12446)
		(layer "F.Cu")
		(net "PHY_IOC_TO_SCC_C_43_DP")
	)
	(arc
		(start 133.13156 -46.080172)
		(mid 133.20769 -45.96633)
		(end 133.23443 -45.832014)
		(width 0.12446)
		(layer "F.Cu")
		(net "PHY_IOC_TO_SCC_C_43_DP")
	)
	(segment
		(start 133.18617 -48.721264)
		(end 133.18617 -48.990504)
		(width 0.1016)
		(layer "In2.Cu")
		(net "PHY_IOC_TO_SCC_C_43_DP")
	)
	(segment
		(start 130.70205 -54.892194)
		(end 130.000502 -55.593742)
		(width 0.0889)
		(layer "In2.Cu")
		(net "PHY_IOC_TO_SCC_C_43_DP")
	)
	(segment
		(start 132.220208 -45.814742)
		(end 132.220208 -46.09973)
		(width 0.1016)
		(layer "In2.Cu")
		(net "PHY_IOC_TO_SCC_C_43_DP")
	)
	(segment
		(start 130.7592 -53.806852)
		(end 130.7592 -53.82895)
		(width 0.0889)
		(layer "In2.Cu")
		(net "PHY_IOC_TO_SCC_C_43_DP")
	)
	(segment
		(start 130.7592 -51.148234)
		(end 130.7592 -53.806852)
		(width 0.1016)
		(layer "In2.Cu")
		(net "PHY_IOC_TO_SCC_C_43_DP")
	)
	(segment
		(start 130.000502 -55.593742)
		(end 126.810516 -55.593742)
		(width 0.0889)
		(layer "In2.Cu")
		(net "PHY_IOC_TO_SCC_C_43_DP")
	)
	(segment
		(start 132.701284 -49.20615)
		(end 130.7592 -51.148234)
		(width 0.1016)
		(layer "In2.Cu")
		(net "PHY_IOC_TO_SCC_C_43_DP")
	)
	(segment
		(start 132.354066 -46.233842)
		(end 132.885688 -46.233842)
		(width 0.1016)
		(layer "In2.Cu")
		(net "PHY_IOC_TO_SCC_C_43_DP")
	)
	(segment
		(start 132.970778 -49.20615)
		(end 132.701284 -49.20615)
		(width 0.1016)
		(layer "In2.Cu")
		(net "PHY_IOC_TO_SCC_C_43_DP")
	)
	(segment
		(start 126.595124 -55.809134)
		(end 126.595124 -55.911242)
		(width 0.0889)
		(layer "In2.Cu")
		(net "PHY_IOC_TO_SCC_C_43_DP")
	)
	(segment
		(start 126.684024 -56.000142)
		(end 127 -56.000142)
		(width 0.0889)
		(layer "In2.Cu")
		(net "PHY_IOC_TO_SCC_C_43_DP")
	)
	(segment
		(start 133.401816 -48.505618)
		(end 133.18617 -48.721264)
		(width 0.1016)
		(layer "In2.Cu")
		(net "PHY_IOC_TO_SCC_C_43_DP")
	)
	(segment
		(start 133.401816 -46.74997)
		(end 133.401816 -48.505618)
		(width 0.1016)
		(layer "In2.Cu")
		(net "PHY_IOC_TO_SCC_C_43_DP")
	)
	(segment
		(start 130.7592 -53.82895)
		(end 130.70205 -53.8861)
		(width 0.0889)
		(layer "In2.Cu")
		(net "PHY_IOC_TO_SCC_C_43_DP")
	)
	(segment
		(start 133.18617 -48.990504)
		(end 132.970778 -49.20615)
		(width 0.1016)
		(layer "In2.Cu")
		(net "PHY_IOC_TO_SCC_C_43_DP")
	)
	(segment
		(start 130.70205 -53.8861)
		(end 130.70205 -54.892194)
		(width 0.0889)
		(layer "In2.Cu")
		(net "PHY_IOC_TO_SCC_C_43_DP")
	)
	(arc
		(start 126.595124 -55.911242)
		(mid 126.621162 -55.974104)
		(end 126.684024 -56.000142)
		(width 0.0889)
		(layer "In2.Cu")
		(net "PHY_IOC_TO_SCC_C_43_DP")
	)
	(arc
		(start 126.810516 -55.593742)
		(mid 126.72802 -55.610187)
		(end 126.658116 -55.656988)
		(width 0.0889)
		(layer "In2.Cu")
		(net "PHY_IOC_TO_SCC_C_43_DP")
	)
	(arc
		(start 126.658116 -55.656988)
		(mid 126.611474 -55.726793)
		(end 126.595124 -55.809134)
		(width 0.0889)
		(layer "In2.Cu")
		(net "PHY_IOC_TO_SCC_C_43_DP")
	)
	(arc
		(start 132.220208 -46.09973)
		(mid 132.230436 -46.15115)
		(end 132.259578 -46.194726)
		(width 0.1016)
		(layer "In2.Cu")
		(net "PHY_IOC_TO_SCC_C_43_DP")
	)
	(arc
		(start 132.885688 -46.233842)
		(mid 133.250646 -46.385012)
		(end 133.401816 -46.74997)
		(width 0.1016)
		(layer "In2.Cu")
		(net "PHY_IOC_TO_SCC_C_43_DP")
	)
	(arc
		(start 132.259578 -46.194726)
		(mid 132.302929 -46.223693)
		(end 132.354066 -46.233842)
		(width 0.1016)
		(layer "In2.Cu")
		(net "PHY_IOC_TO_SCC_C_43_DP")
	)
	(segment
		(start 133.64083 -45.832014)
		(end 133.64083 -45.437552)
		(width 0.12446)
		(layer "F.Cu")
		(net "PHY_IOC_TO_SCC_C_43_DN")
	)
	(segment
		(start 133.72973 -45.348652)
		(end 133.72973 -44.982384)
		(width 0.12446)
		(layer "F.Cu")
		(net "PHY_IOC_TO_SCC_C_43_DN")
	)
	(segment
		(start 125.50013 -56.500014)
		(end 126.000002 -56.000142)
		(width 0.104902)
		(layer "F.Cu")
		(net "PHY_IOC_TO_SCC_C_43_DN")
	)
	(segment
		(start 133.64083 -45.437552)
		(end 133.72973 -45.348652)
		(width 0.12446)
		(layer "F.Cu")
		(net "PHY_IOC_TO_SCC_C_43_DN")
	)
	(segment
		(start 132.331206 -46.589442)
		(end 132.883402 -46.589442)
		(width 0.12446)
		(layer "F.Cu")
		(net "PHY_IOC_TO_SCC_C_43_DN")
	)
	(segment
		(start 132.220208 -46.957742)
		(end 132.220208 -46.70044)
		(width 0.12446)
		(layer "F.Cu")
		(net "PHY_IOC_TO_SCC_C_43_DN")
	)
	(via
		(at 126.000002 -56.000142)
		(size 0.4572)
		(drill 0.2032)
		(layers "F.Cu" "B.Cu")
		(net "PHY_IOC_TO_SCC_C_43_DN")
	)
	(arc
		(start 132.883402 -46.589442)
		(mid 133.17334 -46.531752)
		(end 133.419088 -46.367446)
		(width 0.12446)
		(layer "F.Cu")
		(net "PHY_IOC_TO_SCC_C_43_DN")
	)
	(arc
		(start 132.25272 -46.621954)
		(mid 132.28873 -46.597893)
		(end 132.331206 -46.589442)
		(width 0.12446)
		(layer "F.Cu")
		(net "PHY_IOC_TO_SCC_C_43_DN")
	)
	(arc
		(start 133.419088 -46.367446)
		(mid 133.583178 -46.121773)
		(end 133.64083 -45.832014)
		(width 0.12446)
		(layer "F.Cu")
		(net "PHY_IOC_TO_SCC_C_43_DN")
	)
	(arc
		(start 132.220208 -46.70044)
		(mid 132.228657 -46.657963)
		(end 132.25272 -46.621954)
		(width 0.12446)
		(layer "F.Cu")
		(net "PHY_IOC_TO_SCC_C_43_DN")
	)
	(segment
		(start 130.51155 -54.8132)
		(end 129.921508 -55.403242)
		(width 0.0889)
		(layer "In2.Cu")
		(net "PHY_IOC_TO_SCC_C_43_DN")
	)
	(segment
		(start 132.220208 -46.957742)
		(end 132.220208 -46.6725)
		(width 0.1016)
		(layer "In2.Cu")
		(net "PHY_IOC_TO_SCC_C_43_DN")
	)
	(segment
		(start 130.51155 -53.8861)
		(end 130.51155 -54.8132)
		(width 0.0889)
		(layer "In2.Cu")
		(net "PHY_IOC_TO_SCC_C_43_DN")
	)
	(segment
		(start 132.340858 -46.538642)
		(end 132.885688 -46.538642)
		(width 0.1016)
		(layer "In2.Cu")
		(net "PHY_IOC_TO_SCC_C_43_DN")
	)
	(segment
		(start 126.404624 -55.809134)
		(end 126.404624 -55.911242)
		(width 0.0889)
		(layer "In2.Cu")
		(net "PHY_IOC_TO_SCC_C_43_DN")
	)
	(segment
		(start 133.097016 -48.379126)
		(end 130.4544 -51.021742)
		(width 0.1016)
		(layer "In2.Cu")
		(net "PHY_IOC_TO_SCC_C_43_DN")
	)
	(segment
		(start 130.4544 -51.021742)
		(end 130.4544 -53.806852)
		(width 0.1016)
		(layer "In2.Cu")
		(net "PHY_IOC_TO_SCC_C_43_DN")
	)
	(segment
		(start 133.097016 -46.74997)
		(end 133.097016 -48.379126)
		(width 0.1016)
		(layer "In2.Cu")
		(net "PHY_IOC_TO_SCC_C_43_DN")
	)
	(segment
		(start 129.921508 -55.403242)
		(end 126.810516 -55.403242)
		(width 0.0889)
		(layer "In2.Cu")
		(net "PHY_IOC_TO_SCC_C_43_DN")
	)
	(segment
		(start 132.259578 -46.578012)
		(end 132.268976 -46.568614)
		(width 0.1016)
		(layer "In2.Cu")
		(net "PHY_IOC_TO_SCC_C_43_DN")
	)
	(segment
		(start 130.4544 -53.806852)
		(end 130.4544 -53.82895)
		(width 0.0889)
		(layer "In2.Cu")
		(net "PHY_IOC_TO_SCC_C_43_DN")
	)
	(segment
		(start 130.4544 -53.82895)
		(end 130.51155 -53.8861)
		(width 0.0889)
		(layer "In2.Cu")
		(net "PHY_IOC_TO_SCC_C_43_DN")
	)
	(segment
		(start 126.315724 -56.000142)
		(end 126.000002 -56.000142)
		(width 0.0889)
		(layer "In2.Cu")
		(net "PHY_IOC_TO_SCC_C_43_DN")
	)
	(arc
		(start 126.810516 -55.403242)
		(mid 126.655022 -55.434207)
		(end 126.523242 -55.522368)
		(width 0.0889)
		(layer "In2.Cu")
		(net "PHY_IOC_TO_SCC_C_43_DN")
	)
	(arc
		(start 132.268976 -46.568614)
		(mid 132.301926 -46.546441)
		(end 132.340858 -46.538642)
		(width 0.1016)
		(layer "In2.Cu")
		(net "PHY_IOC_TO_SCC_C_43_DN")
	)
	(arc
		(start 126.404624 -55.911242)
		(mid 126.378586 -55.974104)
		(end 126.315724 -56.000142)
		(width 0.0889)
		(layer "In2.Cu")
		(net "PHY_IOC_TO_SCC_C_43_DN")
	)
	(arc
		(start 132.220208 -46.6725)
		(mid 132.23048 -46.621328)
		(end 132.259578 -46.578012)
		(width 0.1016)
		(layer "In2.Cu")
		(net "PHY_IOC_TO_SCC_C_43_DN")
	)
	(arc
		(start 126.523242 -55.522368)
		(mid 126.435437 -55.653966)
		(end 126.404624 -55.809134)
		(width 0.0889)
		(layer "In2.Cu")
		(net "PHY_IOC_TO_SCC_C_43_DN")
	)
	(arc
		(start 132.885688 -46.538642)
		(mid 133.035119 -46.600539)
		(end 133.097016 -46.74997)
		(width 0.1016)
		(layer "In2.Cu")
		(net "PHY_IOC_TO_SCC_C_43_DN")
	)
	(segment
		(start 126.500128 -55.500016)
		(end 127 -55.000144)
		(width 0.104902)
		(layer "F.Cu")
		(net "PHY_IOC_TO_SCC_C_42_DP")
	)
	(segment
		(start 130.387344 -46.197774)
		(end 129.759456 -46.197774)
		(width 0.12446)
		(layer "F.Cu")
		(net "PHY_IOC_TO_SCC_C_42_DP")
	)
	(segment
		(start 130.66268 -45.452284)
		(end 130.66268 -45.922438)
		(width 0.12446)
		(layer "F.Cu")
		(net "PHY_IOC_TO_SCC_C_42_DP")
	)
	(segment
		(start 130.57378 -44.997116)
		(end 130.57378 -45.363384)
		(width 0.12446)
		(layer "F.Cu")
		(net "PHY_IOC_TO_SCC_C_42_DP")
	)
	(segment
		(start 129.648458 -46.086776)
		(end 129.648458 -45.829474)
		(width 0.12446)
		(layer "F.Cu")
		(net "PHY_IOC_TO_SCC_C_42_DP")
	)
	(segment
		(start 130.57378 -45.363384)
		(end 130.66268 -45.452284)
		(width 0.12446)
		(layer "F.Cu")
		(net "PHY_IOC_TO_SCC_C_42_DP")
	)
	(via
		(at 127 -55.000144)
		(size 0.4572)
		(drill 0.2032)
		(layers "F.Cu" "B.Cu")
		(net "PHY_IOC_TO_SCC_C_42_DP")
	)
	(arc
		(start 129.759456 -46.197774)
		(mid 129.716979 -46.189325)
		(end 129.68097 -46.165262)
		(width 0.12446)
		(layer "F.Cu")
		(net "PHY_IOC_TO_SCC_C_42_DP")
	)
	(arc
		(start 130.581908 -46.117002)
		(mid 130.492656 -46.176731)
		(end 130.387344 -46.197774)
		(width 0.12446)
		(layer "F.Cu")
		(net "PHY_IOC_TO_SCC_C_42_DP")
	)
	(arc
		(start 130.66268 -45.922438)
		(mid 130.641638 -46.027751)
		(end 130.581908 -46.117002)
		(width 0.12446)
		(layer "F.Cu")
		(net "PHY_IOC_TO_SCC_C_42_DP")
	)
	(arc
		(start 129.68097 -46.165262)
		(mid 129.656909 -46.129252)
		(end 129.648458 -46.086776)
		(width 0.12446)
		(layer "F.Cu")
		(net "PHY_IOC_TO_SCC_C_42_DP")
	)
	(segment
		(start 126.634748 -54.635146)
		(end 126.634494 -54.6354)
		(width 0.0889)
		(layer "In2.Cu")
		(net "PHY_IOC_TO_SCC_C_42_DP")
	)
	(segment
		(start 126.595124 -54.730904)
		(end 126.595124 -54.911244)
		(width 0.0889)
		(layer "In2.Cu")
		(net "PHY_IOC_TO_SCC_C_42_DP")
	)
	(segment
		(start 129.59715 -50.805842)
		(end 129.59715 -54.216554)
		(width 0.0889)
		(layer "In2.Cu")
		(net "PHY_IOC_TO_SCC_C_42_DP")
	)
	(segment
		(start 129.6543 -50.748692)
		(end 129.59715 -50.805842)
		(width 0.0889)
		(layer "In2.Cu")
		(net "PHY_IOC_TO_SCC_C_42_DP")
	)
	(segment
		(start 130.646932 -48.357028)
		(end 129.6543 -49.34966)
		(width 0.1016)
		(layer "In2.Cu")
		(net "PHY_IOC_TO_SCC_C_42_DP")
	)
	(segment
		(start 130.837432 -47.80534)
		(end 130.646932 -47.99584)
		(width 0.1016)
		(layer "In2.Cu")
		(net "PHY_IOC_TO_SCC_C_42_DP")
	)
	(segment
		(start 129.218182 -54.595522)
		(end 126.73076 -54.595522)
		(width 0.0889)
		(layer "In2.Cu")
		(net "PHY_IOC_TO_SCC_C_42_DP")
	)
	(segment
		(start 130.646932 -47.99584)
		(end 130.646932 -48.357028)
		(width 0.1016)
		(layer "In2.Cu")
		(net "PHY_IOC_TO_SCC_C_42_DP")
	)
	(segment
		(start 129.648458 -45.829474)
		(end 129.648458 -46.114462)
		(width 0.1016)
		(layer "In2.Cu")
		(net "PHY_IOC_TO_SCC_C_42_DP")
	)
	(segment
		(start 129.59715 -54.216554)
		(end 129.218182 -54.595522)
		(width 0.0889)
		(layer "In2.Cu")
		(net "PHY_IOC_TO_SCC_C_42_DP")
	)
	(segment
		(start 129.6543 -50.726594)
		(end 129.6543 -50.748692)
		(width 0.0889)
		(layer "In2.Cu")
		(net "PHY_IOC_TO_SCC_C_42_DP")
	)
	(segment
		(start 130.837432 -47.50054)
		(end 130.837432 -47.80534)
		(width 0.1016)
		(layer "In2.Cu")
		(net "PHY_IOC_TO_SCC_C_42_DP")
	)
	(segment
		(start 129.6543 -49.34966)
		(end 129.6543 -50.726594)
		(width 0.1016)
		(layer "In2.Cu")
		(net "PHY_IOC_TO_SCC_C_42_DP")
	)
	(segment
		(start 130.646932 -46.769274)
		(end 130.646932 -47.31004)
		(width 0.1016)
		(layer "In2.Cu")
		(net "PHY_IOC_TO_SCC_C_42_DP")
	)
	(segment
		(start 126.684024 -55.000144)
		(end 127 -55.000144)
		(width 0.0889)
		(layer "In2.Cu")
		(net "PHY_IOC_TO_SCC_C_42_DP")
	)
	(segment
		(start 129.782316 -46.248574)
		(end 130.126232 -46.248574)
		(width 0.1016)
		(layer "In2.Cu")
		(net "PHY_IOC_TO_SCC_C_42_DP")
	)
	(segment
		(start 130.646932 -47.31004)
		(end 130.837432 -47.50054)
		(width 0.1016)
		(layer "In2.Cu")
		(net "PHY_IOC_TO_SCC_C_42_DP")
	)
	(arc
		(start 126.634494 -54.6354)
		(mid 126.605376 -54.67926)
		(end 126.595124 -54.730904)
		(width 0.0889)
		(layer "In2.Cu")
		(net "PHY_IOC_TO_SCC_C_42_DP")
	)
	(arc
		(start 130.126232 -46.248574)
		(mid 130.494423 -46.401083)
		(end 130.646932 -46.769274)
		(width 0.1016)
		(layer "In2.Cu")
		(net "PHY_IOC_TO_SCC_C_42_DP")
	)
	(arc
		(start 129.648458 -46.114462)
		(mid 129.658686 -46.165882)
		(end 129.687828 -46.209458)
		(width 0.1016)
		(layer "In2.Cu")
		(net "PHY_IOC_TO_SCC_C_42_DP")
	)
	(arc
		(start 126.595124 -54.911244)
		(mid 126.621162 -54.974106)
		(end 126.684024 -55.000144)
		(width 0.0889)
		(layer "In2.Cu")
		(net "PHY_IOC_TO_SCC_C_42_DP")
	)
	(arc
		(start 129.687828 -46.209458)
		(mid 129.731179 -46.238425)
		(end 129.782316 -46.248574)
		(width 0.1016)
		(layer "In2.Cu")
		(net "PHY_IOC_TO_SCC_C_42_DP")
	)
	(arc
		(start 126.73076 -54.595522)
		(mid 126.67884 -54.605832)
		(end 126.634748 -54.635146)
		(width 0.0889)
		(layer "In2.Cu")
		(net "PHY_IOC_TO_SCC_C_42_DP")
	)
	(segment
		(start 131.15798 -44.997116)
		(end 131.15798 -45.363384)
		(width 0.12446)
		(layer "F.Cu")
		(net "PHY_IOC_TO_SCC_C_42_DN")
	)
	(segment
		(start 131.06908 -45.452284)
		(end 131.06908 -45.922438)
		(width 0.12446)
		(layer "F.Cu")
		(net "PHY_IOC_TO_SCC_C_42_DN")
	)
	(segment
		(start 130.387344 -46.604174)
		(end 129.759456 -46.604174)
		(width 0.12446)
		(layer "F.Cu")
		(net "PHY_IOC_TO_SCC_C_42_DN")
	)
	(segment
		(start 129.648458 -46.715172)
		(end 129.648458 -46.972474)
		(width 0.12446)
		(layer "F.Cu")
		(net "PHY_IOC_TO_SCC_C_42_DN")
	)
	(segment
		(start 131.15798 -45.363384)
		(end 131.06908 -45.452284)
		(width 0.12446)
		(layer "F.Cu")
		(net "PHY_IOC_TO_SCC_C_42_DN")
	)
	(segment
		(start 125.50013 -55.500016)
		(end 126.000002 -55.000144)
		(width 0.104902)
		(layer "F.Cu")
		(net "PHY_IOC_TO_SCC_C_42_DN")
	)
	(via
		(at 126.000002 -55.000144)
		(size 0.4572)
		(drill 0.2032)
		(layers "F.Cu" "B.Cu")
		(net "PHY_IOC_TO_SCC_C_42_DN")
	)
	(arc
		(start 130.869436 -46.40453)
		(mid 130.648236 -46.552268)
		(end 130.387344 -46.604174)
		(width 0.12446)
		(layer "F.Cu")
		(net "PHY_IOC_TO_SCC_C_42_DN")
	)
	(arc
		(start 129.759456 -46.604174)
		(mid 129.716979 -46.612623)
		(end 129.68097 -46.636686)
		(width 0.12446)
		(layer "F.Cu")
		(net "PHY_IOC_TO_SCC_C_42_DN")
	)
	(arc
		(start 131.06908 -45.922438)
		(mid 131.017201 -46.183341)
		(end 130.869436 -46.40453)
		(width 0.12446)
		(layer "F.Cu")
		(net "PHY_IOC_TO_SCC_C_42_DN")
	)
	(arc
		(start 129.68097 -46.636686)
		(mid 129.656909 -46.672696)
		(end 129.648458 -46.715172)
		(width 0.12446)
		(layer "F.Cu")
		(net "PHY_IOC_TO_SCC_C_42_DN")
	)
	(segment
		(start 126.500128 -54.500272)
		(end 126.49962 -54.50078)
		(width 0.0889)
		(layer "In2.Cu")
		(net "PHY_IOC_TO_SCC_C_42_DN")
	)
	(segment
		(start 130.342132 -46.769274)
		(end 130.342132 -48.230536)
		(width 0.1016)
		(layer "In2.Cu")
		(net "PHY_IOC_TO_SCC_C_42_DN")
	)
	(segment
		(start 126.315724 -55.000144)
		(end 126.000002 -55.000144)
		(width 0.0889)
		(layer "In2.Cu")
		(net "PHY_IOC_TO_SCC_C_42_DN")
	)
	(segment
		(start 129.139188 -54.405022)
		(end 126.731014 -54.405022)
		(width 0.0889)
		(layer "In2.Cu")
		(net "PHY_IOC_TO_SCC_C_42_DN")
	)
	(segment
		(start 129.3495 -49.223168)
		(end 129.3495 -50.726594)
		(width 0.1016)
		(layer "In2.Cu")
		(net "PHY_IOC_TO_SCC_C_42_DN")
	)
	(segment
		(start 129.769108 -46.553374)
		(end 130.126232 -46.553374)
		(width 0.1016)
		(layer "In2.Cu")
		(net "PHY_IOC_TO_SCC_C_42_DN")
	)
	(segment
		(start 129.3495 -50.726594)
		(end 129.3495 -50.748692)
		(width 0.0889)
		(layer "In2.Cu")
		(net "PHY_IOC_TO_SCC_C_42_DN")
	)
	(segment
		(start 129.687828 -46.592744)
		(end 129.697226 -46.583346)
		(width 0.1016)
		(layer "In2.Cu")
		(net "PHY_IOC_TO_SCC_C_42_DN")
	)
	(segment
		(start 129.40665 -54.13756)
		(end 129.139188 -54.405022)
		(width 0.0889)
		(layer "In2.Cu")
		(net "PHY_IOC_TO_SCC_C_42_DN")
	)
	(segment
		(start 126.404624 -54.730904)
		(end 126.404624 -54.911244)
		(width 0.0889)
		(layer "In2.Cu")
		(net "PHY_IOC_TO_SCC_C_42_DN")
	)
	(segment
		(start 129.40665 -50.805842)
		(end 129.40665 -54.13756)
		(width 0.0889)
		(layer "In2.Cu")
		(net "PHY_IOC_TO_SCC_C_42_DN")
	)
	(segment
		(start 129.3495 -50.748692)
		(end 129.40665 -50.805842)
		(width 0.0889)
		(layer "In2.Cu")
		(net "PHY_IOC_TO_SCC_C_42_DN")
	)
	(segment
		(start 129.648458 -46.972474)
		(end 129.648458 -46.687232)
		(width 0.1016)
		(layer "In2.Cu")
		(net "PHY_IOC_TO_SCC_C_42_DN")
	)
	(segment
		(start 130.342132 -48.230536)
		(end 129.3495 -49.223168)
		(width 0.1016)
		(layer "In2.Cu")
		(net "PHY_IOC_TO_SCC_C_42_DN")
	)
	(arc
		(start 130.126232 -46.553374)
		(mid 130.278896 -46.61661)
		(end 130.342132 -46.769274)
		(width 0.1016)
		(layer "In2.Cu")
		(net "PHY_IOC_TO_SCC_C_42_DN")
	)
	(arc
		(start 129.697226 -46.583346)
		(mid 129.730176 -46.561173)
		(end 129.769108 -46.553374)
		(width 0.1016)
		(layer "In2.Cu")
		(net "PHY_IOC_TO_SCC_C_42_DN")
	)
	(arc
		(start 126.404624 -54.911244)
		(mid 126.378586 -54.974106)
		(end 126.315724 -55.000144)
		(width 0.0889)
		(layer "In2.Cu")
		(net "PHY_IOC_TO_SCC_C_42_DN")
	)
	(arc
		(start 126.49962 -54.50078)
		(mid 126.429287 -54.606419)
		(end 126.404624 -54.730904)
		(width 0.0889)
		(layer "In2.Cu")
		(net "PHY_IOC_TO_SCC_C_42_DN")
	)
	(arc
		(start 126.731014 -54.405022)
		(mid 126.606086 -54.429667)
		(end 126.500128 -54.500272)
		(width 0.0889)
		(layer "In2.Cu")
		(net "PHY_IOC_TO_SCC_C_42_DN")
	)
	(arc
		(start 129.648458 -46.687232)
		(mid 129.65873 -46.63606)
		(end 129.687828 -46.592744)
		(width 0.1016)
		(layer "In2.Cu")
		(net "PHY_IOC_TO_SCC_C_42_DN")
	)
	(segment
		(start 127.076708 -45.844206)
		(end 127.076708 -46.101508)
		(width 0.12446)
		(layer "F.Cu")
		(net "PHY_IOC_TO_SCC_C_41_DP")
	)
	(segment
		(start 128.09093 -45.467016)
		(end 128.00203 -45.378116)
		(width 0.12446)
		(layer "F.Cu")
		(net "PHY_IOC_TO_SCC_C_41_DP")
	)
	(segment
		(start 128.00203 -45.378116)
		(end 128.00203 -45.011848)
		(width 0.12446)
		(layer "F.Cu")
		(net "PHY_IOC_TO_SCC_C_41_DP")
	)
	(segment
		(start 126.500128 -54.500018)
		(end 127 -54.000146)
		(width 0.104902)
		(layer "F.Cu")
		(net "PHY_IOC_TO_SCC_C_41_DP")
	)
	(segment
		(start 128.09093 -45.864018)
		(end 128.09093 -45.467016)
		(width 0.12446)
		(layer "F.Cu")
		(net "PHY_IOC_TO_SCC_C_41_DP")
	)
	(segment
		(start 127.187706 -46.212506)
		(end 127.742696 -46.212506)
		(width 0.12446)
		(layer "F.Cu")
		(net "PHY_IOC_TO_SCC_C_41_DP")
	)
	(via
		(at 127 -54.000146)
		(size 0.4572)
		(drill 0.2032)
		(layers "F.Cu" "B.Cu")
		(net "PHY_IOC_TO_SCC_C_41_DP")
	)
	(arc
		(start 127.742696 -46.212506)
		(mid 127.875876 -46.186033)
		(end 127.988822 -46.110652)
		(width 0.12446)
		(layer "F.Cu")
		(net "PHY_IOC_TO_SCC_C_41_DP")
	)
	(arc
		(start 127.988822 -46.110652)
		(mid 128.064377 -45.997481)
		(end 128.09093 -45.864018)
		(width 0.12446)
		(layer "F.Cu")
		(net "PHY_IOC_TO_SCC_C_41_DP")
	)
	(arc
		(start 127.10922 -46.179994)
		(mid 127.14523 -46.204055)
		(end 127.187706 -46.212506)
		(width 0.12446)
		(layer "F.Cu")
		(net "PHY_IOC_TO_SCC_C_41_DP")
	)
	(arc
		(start 127.076708 -46.101508)
		(mid 127.085157 -46.143985)
		(end 127.10922 -46.179994)
		(width 0.12446)
		(layer "F.Cu")
		(net "PHY_IOC_TO_SCC_C_41_DP")
	)
	(segment
		(start 128.015492 -46.263306)
		(end 127.210566 -46.263306)
		(width 0.1016)
		(layer "In2.Cu")
		(net "PHY_IOC_TO_SCC_C_41_DP")
	)
	(segment
		(start 126.733046 -53.596032)
		(end 128.26746 -53.596032)
		(width 0.0889)
		(layer "In2.Cu")
		(net "PHY_IOC_TO_SCC_C_41_DP")
	)
	(segment
		(start 128.26746 -53.596032)
		(end 128.59766 -53.265832)
		(width 0.0889)
		(layer "In2.Cu")
		(net "PHY_IOC_TO_SCC_C_41_DP")
	)
	(segment
		(start 128.59766 -53.265832)
		(end 128.59766 -50.669698)
		(width 0.0889)
		(layer "In2.Cu")
		(net "PHY_IOC_TO_SCC_C_41_DP")
	)
	(segment
		(start 128.65481 -47.692056)
		(end 128.65481 -46.902624)
		(width 0.1016)
		(layer "In2.Cu")
		(net "PHY_IOC_TO_SCC_C_41_DP")
	)
	(segment
		(start 127.076708 -46.129194)
		(end 127.076708 -45.844206)
		(width 0.1016)
		(layer "In2.Cu")
		(net "PHY_IOC_TO_SCC_C_41_DP")
	)
	(segment
		(start 128.59766 -50.669698)
		(end 128.65481 -50.612548)
		(width 0.0889)
		(layer "In2.Cu")
		(net "PHY_IOC_TO_SCC_C_41_DP")
	)
	(segment
		(start 128.65481 -48.377856)
		(end 128.84531 -48.187356)
		(width 0.1016)
		(layer "In2.Cu")
		(net "PHY_IOC_TO_SCC_C_41_DP")
	)
	(segment
		(start 128.84531 -48.187356)
		(end 128.84531 -47.882556)
		(width 0.1016)
		(layer "In2.Cu")
		(net "PHY_IOC_TO_SCC_C_41_DP")
	)
	(segment
		(start 128.84531 -47.882556)
		(end 128.65481 -47.692056)
		(width 0.1016)
		(layer "In2.Cu")
		(net "PHY_IOC_TO_SCC_C_41_DP")
	)
	(segment
		(start 128.65481 -50.59045)
		(end 128.65481 -48.377856)
		(width 0.1016)
		(layer "In2.Cu")
		(net "PHY_IOC_TO_SCC_C_41_DP")
	)
	(segment
		(start 128.65481 -50.612548)
		(end 128.65481 -50.59045)
		(width 0.0889)
		(layer "In2.Cu")
		(net "PHY_IOC_TO_SCC_C_41_DP")
	)
	(segment
		(start 126.595124 -53.911246)
		(end 126.595124 -53.733954)
		(width 0.0889)
		(layer "In2.Cu")
		(net "PHY_IOC_TO_SCC_C_41_DP")
	)
	(segment
		(start 127 -54.000146)
		(end 126.684024 -54.000146)
		(width 0.0889)
		(layer "In2.Cu")
		(net "PHY_IOC_TO_SCC_C_41_DP")
	)
	(arc
		(start 126.595124 -53.733954)
		(mid 126.605623 -53.681174)
		(end 126.63551 -53.636418)
		(width 0.0889)
		(layer "In2.Cu")
		(net "PHY_IOC_TO_SCC_C_41_DP")
	)
	(arc
		(start 128.65481 -46.902624)
		(mid 128.467558 -46.450558)
		(end 128.015492 -46.263306)
		(width 0.1016)
		(layer "In2.Cu")
		(net "PHY_IOC_TO_SCC_C_41_DP")
	)
	(arc
		(start 127.116078 -46.22419)
		(mid 127.086956 -46.180605)
		(end 127.076708 -46.129194)
		(width 0.1016)
		(layer "In2.Cu")
		(net "PHY_IOC_TO_SCC_C_41_DP")
	)
	(arc
		(start 126.684024 -54.000146)
		(mid 126.621162 -53.974108)
		(end 126.595124 -53.911246)
		(width 0.0889)
		(layer "In2.Cu")
		(net "PHY_IOC_TO_SCC_C_41_DP")
	)
	(arc
		(start 126.63551 -53.636418)
		(mid 126.68026 -53.606517)
		(end 126.733046 -53.596032)
		(width 0.0889)
		(layer "In2.Cu")
		(net "PHY_IOC_TO_SCC_C_41_DP")
	)
	(arc
		(start 127.210566 -46.263306)
		(mid 127.159438 -46.253136)
		(end 127.116078 -46.22419)
		(width 0.1016)
		(layer "In2.Cu")
		(net "PHY_IOC_TO_SCC_C_41_DP")
	)
	(segment
		(start 125.50013 -54.500018)
		(end 126.000002 -54.000146)
		(width 0.104902)
		(layer "F.Cu")
		(net "PHY_IOC_TO_SCC_C_41_DN")
	)
	(segment
		(start 127.076708 -46.987206)
		(end 127.076708 -46.729904)
		(width 0.12446)
		(layer "F.Cu")
		(net "PHY_IOC_TO_SCC_C_41_DN")
	)
	(segment
		(start 127.187706 -46.618906)
		(end 127.742696 -46.618906)
		(width 0.12446)
		(layer "F.Cu")
		(net "PHY_IOC_TO_SCC_C_41_DN")
	)
	(segment
		(start 128.49733 -45.467016)
		(end 128.58623 -45.378116)
		(width 0.12446)
		(layer "F.Cu")
		(net "PHY_IOC_TO_SCC_C_41_DN")
	)
	(segment
		(start 128.58623 -45.378116)
		(end 128.58623 -45.011848)
		(width 0.12446)
		(layer "F.Cu")
		(net "PHY_IOC_TO_SCC_C_41_DN")
	)
	(segment
		(start 128.49733 -45.864018)
		(end 128.49733 -45.467016)
		(width 0.12446)
		(layer "F.Cu")
		(net "PHY_IOC_TO_SCC_C_41_DN")
	)
	(via
		(at 126.000002 -54.000146)
		(size 0.4572)
		(drill 0.2032)
		(layers "F.Cu" "B.Cu")
		(net "PHY_IOC_TO_SCC_C_41_DN")
	)
	(arc
		(start 127.076708 -46.729904)
		(mid 127.085157 -46.687427)
		(end 127.10922 -46.651418)
		(width 0.12446)
		(layer "F.Cu")
		(net "PHY_IOC_TO_SCC_C_41_DN")
	)
	(arc
		(start 127.10922 -46.651418)
		(mid 127.14523 -46.627357)
		(end 127.187706 -46.618906)
		(width 0.12446)
		(layer "F.Cu")
		(net "PHY_IOC_TO_SCC_C_41_DN")
	)
	(arc
		(start 128.276096 -46.39818)
		(mid 128.43985 -46.153104)
		(end 128.49733 -45.864018)
		(width 0.12446)
		(layer "F.Cu")
		(net "PHY_IOC_TO_SCC_C_41_DN")
	)
	(arc
		(start 127.742696 -46.618906)
		(mid 128.03133 -46.561547)
		(end 128.276096 -46.39818)
		(width 0.12446)
		(layer "F.Cu")
		(net "PHY_IOC_TO_SCC_C_41_DN")
	)
	(segment
		(start 128.015492 -46.568106)
		(end 127.197358 -46.568106)
		(width 0.1016)
		(layer "In2.Cu")
		(net "PHY_IOC_TO_SCC_C_41_DN")
	)
	(segment
		(start 127.125476 -46.598078)
		(end 127.116078 -46.607476)
		(width 0.1016)
		(layer "In2.Cu")
		(net "PHY_IOC_TO_SCC_C_41_DN")
	)
	(segment
		(start 128.35001 -50.612548)
		(end 128.35001 -50.59045)
		(width 0.0889)
		(layer "In2.Cu")
		(net "PHY_IOC_TO_SCC_C_41_DN")
	)
	(segment
		(start 128.188466 -53.405532)
		(end 128.40716 -53.186838)
		(width 0.0889)
		(layer "In2.Cu")
		(net "PHY_IOC_TO_SCC_C_41_DN")
	)
	(segment
		(start 127.076708 -46.701964)
		(end 127.076708 -46.987206)
		(width 0.1016)
		(layer "In2.Cu")
		(net "PHY_IOC_TO_SCC_C_41_DN")
	)
	(segment
		(start 128.40716 -53.186838)
		(end 128.40716 -50.669698)
		(width 0.0889)
		(layer "In2.Cu")
		(net "PHY_IOC_TO_SCC_C_41_DN")
	)
	(segment
		(start 128.40716 -50.669698)
		(end 128.35001 -50.612548)
		(width 0.0889)
		(layer "In2.Cu")
		(net "PHY_IOC_TO_SCC_C_41_DN")
	)
	(segment
		(start 128.35001 -50.59045)
		(end 128.35001 -46.902624)
		(width 0.1016)
		(layer "In2.Cu")
		(net "PHY_IOC_TO_SCC_C_41_DN")
	)
	(segment
		(start 126.404624 -53.911246)
		(end 126.404624 -53.733954)
		(width 0.0889)
		(layer "In2.Cu")
		(net "PHY_IOC_TO_SCC_C_41_DN")
	)
	(segment
		(start 126.000002 -54.000146)
		(end 126.315724 -54.000146)
		(width 0.0889)
		(layer "In2.Cu")
		(net "PHY_IOC_TO_SCC_C_41_DN")
	)
	(segment
		(start 126.733046 -53.405532)
		(end 128.188466 -53.405532)
		(width 0.0889)
		(layer "In2.Cu")
		(net "PHY_IOC_TO_SCC_C_41_DN")
	)
	(arc
		(start 126.500636 -53.501544)
		(mid 126.607296 -53.430432)
		(end 126.733046 -53.405532)
		(width 0.0889)
		(layer "In2.Cu")
		(net "PHY_IOC_TO_SCC_C_41_DN")
	)
	(arc
		(start 128.35001 -46.902624)
		(mid 128.252032 -46.666084)
		(end 128.015492 -46.568106)
		(width 0.1016)
		(layer "In2.Cu")
		(net "PHY_IOC_TO_SCC_C_41_DN")
	)
	(arc
		(start 127.116078 -46.607476)
		(mid 127.087029 -46.650812)
		(end 127.076708 -46.701964)
		(width 0.1016)
		(layer "In2.Cu")
		(net "PHY_IOC_TO_SCC_C_41_DN")
	)
	(arc
		(start 126.315724 -54.000146)
		(mid 126.378586 -53.974108)
		(end 126.404624 -53.911246)
		(width 0.0889)
		(layer "In2.Cu")
		(net "PHY_IOC_TO_SCC_C_41_DN")
	)
	(arc
		(start 127.197358 -46.568106)
		(mid 127.158448 -46.575957)
		(end 127.125476 -46.598078)
		(width 0.1016)
		(layer "In2.Cu")
		(net "PHY_IOC_TO_SCC_C_41_DN")
	)
	(arc
		(start 126.404624 -53.733954)
		(mid 126.429526 -53.608204)
		(end 126.500636 -53.501544)
		(width 0.0889)
		(layer "In2.Cu")
		(net "PHY_IOC_TO_SCC_C_41_DN")
	)
	(segment
		(start 125.526546 -45.392848)
		(end 125.526546 -45.02658)
		(width 0.12446)
		(layer "F.Cu")
		(net "PHY_IOC_TO_SCC_C_40_DP")
	)
	(segment
		(start 124.682758 -45.858938)
		(end 124.682758 -46.11624)
		(width 0.12446)
		(layer "F.Cu")
		(net "PHY_IOC_TO_SCC_C_40_DP")
	)
	(segment
		(start 125.520196 -46.131988)
		(end 125.556518 -46.095666)
		(width 0.12446)
		(layer "F.Cu")
		(net "PHY_IOC_TO_SCC_C_40_DP")
	)
	(segment
		(start 125.615446 -45.481748)
		(end 125.526546 -45.392848)
		(width 0.12446)
		(layer "F.Cu")
		(net "PHY_IOC_TO_SCC_C_40_DP")
	)
	(segment
		(start 124.793756 -46.227238)
		(end 125.29058 -46.227238)
		(width 0.12446)
		(layer "F.Cu")
		(net "PHY_IOC_TO_SCC_C_40_DP")
	)
	(segment
		(start 127.500126 -53.50002)
		(end 127.999998 -53.000148)
		(width 0.104902)
		(layer "F.Cu")
		(net "PHY_IOC_TO_SCC_C_40_DP")
	)
	(segment
		(start 125.615446 -45.953934)
		(end 125.615446 -45.481748)
		(width 0.12446)
		(layer "F.Cu")
		(net "PHY_IOC_TO_SCC_C_40_DP")
	)
	(via
		(at 127.999998 -53.000148)
		(size 0.4572)
		(drill 0.2032)
		(layers "F.Cu" "B.Cu")
		(net "PHY_IOC_TO_SCC_C_40_DP")
	)
	(arc
		(start 125.29058 -46.227238)
		(mid 125.414887 -46.202494)
		(end 125.520196 -46.131988)
		(width 0.12446)
		(layer "F.Cu")
		(net "PHY_IOC_TO_SCC_C_40_DP")
	)
	(arc
		(start 125.556518 -46.095666)
		(mid 125.600105 -46.030668)
		(end 125.615446 -45.953934)
		(width 0.12446)
		(layer "F.Cu")
		(net "PHY_IOC_TO_SCC_C_40_DP")
	)
	(arc
		(start 124.71527 -46.194726)
		(mid 124.75128 -46.218787)
		(end 124.793756 -46.227238)
		(width 0.12446)
		(layer "F.Cu")
		(net "PHY_IOC_TO_SCC_C_40_DP")
	)
	(arc
		(start 124.682758 -46.11624)
		(mid 124.691207 -46.158717)
		(end 124.71527 -46.194726)
		(width 0.12446)
		(layer "F.Cu")
		(net "PHY_IOC_TO_SCC_C_40_DP")
	)
	(segment
		(start 125.710696 -46.873414)
		(end 125.710696 -47.738792)
		(width 0.1016)
		(layer "In2.Cu")
		(net "PHY_IOC_TO_SCC_C_40_DP")
	)
	(segment
		(start 127.436626 -49.195482)
		(end 127.436626 -49.464722)
		(width 0.1016)
		(layer "In2.Cu")
		(net "PHY_IOC_TO_SCC_C_40_DP")
	)
	(segment
		(start 124.816616 -46.278038)
		(end 125.11532 -46.278038)
		(width 0.1016)
		(layer "In2.Cu")
		(net "PHY_IOC_TO_SCC_C_40_DP")
	)
	(segment
		(start 127.652272 -50.715418)
		(end 127.652272 -50.737516)
		(width 0.0889)
		(layer "In2.Cu")
		(net "PHY_IOC_TO_SCC_C_40_DP")
	)
	(segment
		(start 127.652272 -50.737516)
		(end 127.595122 -50.794666)
		(width 0.0889)
		(layer "In2.Cu")
		(net "PHY_IOC_TO_SCC_C_40_DP")
	)
	(segment
		(start 127.652272 -49.680368)
		(end 127.652272 -50.715418)
		(width 0.1016)
		(layer "In2.Cu")
		(net "PHY_IOC_TO_SCC_C_40_DP")
	)
	(segment
		(start 127.595122 -50.794666)
		(end 127.595122 -52.911248)
		(width 0.0889)
		(layer "In2.Cu")
		(net "PHY_IOC_TO_SCC_C_40_DP")
	)
	(segment
		(start 125.710696 -47.738792)
		(end 126.95174 -48.979836)
		(width 0.1016)
		(layer "In2.Cu")
		(net "PHY_IOC_TO_SCC_C_40_DP")
	)
	(segment
		(start 124.682758 -45.858938)
		(end 124.682758 -46.143926)
		(width 0.1016)
		(layer "In2.Cu")
		(net "PHY_IOC_TO_SCC_C_40_DP")
	)
	(segment
		(start 126.95174 -48.979836)
		(end 127.221234 -48.979836)
		(width 0.1016)
		(layer "In2.Cu")
		(net "PHY_IOC_TO_SCC_C_40_DP")
	)
	(segment
		(start 127.436626 -49.464722)
		(end 127.652272 -49.680368)
		(width 0.1016)
		(layer "In2.Cu")
		(net "PHY_IOC_TO_SCC_C_40_DP")
	)
	(segment
		(start 127.221234 -48.979836)
		(end 127.436626 -49.195482)
		(width 0.1016)
		(layer "In2.Cu")
		(net "PHY_IOC_TO_SCC_C_40_DP")
	)
	(segment
		(start 127.684022 -53.000148)
		(end 127.999998 -53.000148)
		(width 0.0889)
		(layer "In2.Cu")
		(net "PHY_IOC_TO_SCC_C_40_DP")
	)
	(arc
		(start 124.682758 -46.143926)
		(mid 124.692986 -46.195346)
		(end 124.722128 -46.238922)
		(width 0.1016)
		(layer "In2.Cu")
		(net "PHY_IOC_TO_SCC_C_40_DP")
	)
	(arc
		(start 125.11532 -46.278038)
		(mid 125.536314 -46.45242)
		(end 125.710696 -46.873414)
		(width 0.1016)
		(layer "In2.Cu")
		(net "PHY_IOC_TO_SCC_C_40_DP")
	)
	(arc
		(start 124.722128 -46.238922)
		(mid 124.765479 -46.267889)
		(end 124.816616 -46.278038)
		(width 0.1016)
		(layer "In2.Cu")
		(net "PHY_IOC_TO_SCC_C_40_DP")
	)
	(arc
		(start 127.595122 -52.911248)
		(mid 127.62116 -52.97411)
		(end 127.684022 -53.000148)
		(width 0.0889)
		(layer "In2.Cu")
		(net "PHY_IOC_TO_SCC_C_40_DP")
	)
	(segment
		(start 126.110746 -45.392848)
		(end 126.110746 -45.02658)
		(width 0.12446)
		(layer "F.Cu")
		(net "PHY_IOC_TO_SCC_C_40_DN")
	)
	(segment
		(start 124.682758 -47.001938)
		(end 124.682758 -46.744636)
		(width 0.12446)
		(layer "F.Cu")
		(net "PHY_IOC_TO_SCC_C_40_DN")
	)
	(segment
		(start 126.021846 -45.954188)
		(end 126.021846 -45.481748)
		(width 0.12446)
		(layer "F.Cu")
		(net "PHY_IOC_TO_SCC_C_40_DN")
	)
	(segment
		(start 126.021846 -45.481748)
		(end 126.110746 -45.392848)
		(width 0.12446)
		(layer "F.Cu")
		(net "PHY_IOC_TO_SCC_C_40_DN")
	)
	(segment
		(start 126.500128 -53.50002)
		(end 127 -53.000148)
		(width 0.104902)
		(layer "F.Cu")
		(net "PHY_IOC_TO_SCC_C_40_DN")
	)
	(segment
		(start 125.807724 -46.419262)
		(end 125.843792 -46.383194)
		(width 0.12446)
		(layer "F.Cu")
		(net "PHY_IOC_TO_SCC_C_40_DN")
	)
	(segment
		(start 124.793756 -46.633638)
		(end 125.290834 -46.633638)
		(width 0.12446)
		(layer "F.Cu")
		(net "PHY_IOC_TO_SCC_C_40_DN")
	)
	(via
		(at 127 -53.000148)
		(size 0.4572)
		(drill 0.2032)
		(layers "F.Cu" "B.Cu")
		(net "PHY_IOC_TO_SCC_C_40_DN")
	)
	(arc
		(start 124.682758 -46.744636)
		(mid 124.691207 -46.702159)
		(end 124.71527 -46.66615)
		(width 0.12446)
		(layer "F.Cu")
		(net "PHY_IOC_TO_SCC_C_40_DN")
	)
	(arc
		(start 125.290834 -46.633638)
		(mid 125.570609 -46.577876)
		(end 125.807724 -46.419262)
		(width 0.12446)
		(layer "F.Cu")
		(net "PHY_IOC_TO_SCC_C_40_DN")
	)
	(arc
		(start 124.71527 -46.66615)
		(mid 124.75128 -46.642089)
		(end 124.793756 -46.633638)
		(width 0.12446)
		(layer "F.Cu")
		(net "PHY_IOC_TO_SCC_C_40_DN")
	)
	(arc
		(start 125.843792 -46.383194)
		(mid 125.975529 -46.186409)
		(end 126.021846 -45.954188)
		(width 0.12446)
		(layer "F.Cu")
		(net "PHY_IOC_TO_SCC_C_40_DN")
	)
	(segment
		(start 127.347472 -50.715418)
		(end 127.347472 -50.737516)
		(width 0.0889)
		(layer "In2.Cu")
		(net "PHY_IOC_TO_SCC_C_40_DN")
	)
	(segment
		(start 127.315722 -53.000148)
		(end 127 -53.000148)
		(width 0.0889)
		(layer "In2.Cu")
		(net "PHY_IOC_TO_SCC_C_40_DN")
	)
	(segment
		(start 124.803408 -46.582838)
		(end 125.11532 -46.582838)
		(width 0.1016)
		(layer "In2.Cu")
		(net "PHY_IOC_TO_SCC_C_40_DN")
	)
	(segment
		(start 125.405896 -46.873414)
		(end 125.405896 -47.865284)
		(width 0.1016)
		(layer "In2.Cu")
		(net "PHY_IOC_TO_SCC_C_40_DN")
	)
	(segment
		(start 127.404622 -50.794666)
		(end 127.404622 -52.911248)
		(width 0.0889)
		(layer "In2.Cu")
		(net "PHY_IOC_TO_SCC_C_40_DN")
	)
	(segment
		(start 127.347472 -49.80686)
		(end 127.347472 -50.715418)
		(width 0.1016)
		(layer "In2.Cu")
		(net "PHY_IOC_TO_SCC_C_40_DN")
	)
	(segment
		(start 124.682758 -47.001938)
		(end 124.682758 -46.716696)
		(width 0.1016)
		(layer "In2.Cu")
		(net "PHY_IOC_TO_SCC_C_40_DN")
	)
	(segment
		(start 124.722128 -46.622208)
		(end 124.731526 -46.61281)
		(width 0.1016)
		(layer "In2.Cu")
		(net "PHY_IOC_TO_SCC_C_40_DN")
	)
	(segment
		(start 125.405896 -47.865284)
		(end 127.347472 -49.80686)
		(width 0.1016)
		(layer "In2.Cu")
		(net "PHY_IOC_TO_SCC_C_40_DN")
	)
	(segment
		(start 127.347472 -50.737516)
		(end 127.404622 -50.794666)
		(width 0.0889)
		(layer "In2.Cu")
		(net "PHY_IOC_TO_SCC_C_40_DN")
	)
	(arc
		(start 127.404622 -52.911248)
		(mid 127.378584 -52.97411)
		(end 127.315722 -53.000148)
		(width 0.0889)
		(layer "In2.Cu")
		(net "PHY_IOC_TO_SCC_C_40_DN")
	)
	(arc
		(start 124.731526 -46.61281)
		(mid 124.764476 -46.590637)
		(end 124.803408 -46.582838)
		(width 0.1016)
		(layer "In2.Cu")
		(net "PHY_IOC_TO_SCC_C_40_DN")
	)
	(arc
		(start 125.11532 -46.582838)
		(mid 125.320788 -46.667946)
		(end 125.405896 -46.873414)
		(width 0.1016)
		(layer "In2.Cu")
		(net "PHY_IOC_TO_SCC_C_40_DN")
	)
	(arc
		(start 124.682758 -46.716696)
		(mid 124.69303 -46.665524)
		(end 124.722128 -46.622208)
		(width 0.1016)
		(layer "In2.Cu")
		(net "PHY_IOC_TO_SCC_C_40_DN")
	)
	(segment
		(start 150.539958 -61.665104)
		(end 152.483566 -60.402978)
		(width 0.12446)
		(layer "F.Cu")
		(net "PHY_IOC_TO_SCC_47_DP")
	)
	(segment
		(start 144.194022 -63.884048)
		(end 144.559274 -63.806324)
		(width 0.12446)
		(layer "F.Cu")
		(net "PHY_IOC_TO_SCC_47_DP")
	)
	(segment
		(start 156.017468 -51.434492)
		(end 154.65171 -45.019722)
		(width 0.12446)
		(layer "F.Cu")
		(net "PHY_IOC_TO_SCC_47_DP")
	)
	(segment
		(start 155.355036 -53.264816)
		(end 155.67406 -53.057298)
		(width 0.12446)
		(layer "F.Cu")
		(net "PHY_IOC_TO_SCC_47_DP")
	)
	(segment
		(start 143.15059 -63.884048)
		(end 144.194022 -63.884048)
		(width 0.12446)
		(layer "F.Cu")
		(net "PHY_IOC_TO_SCC_47_DP")
	)
	(segment
		(start 145.81632 -63.538862)
		(end 146.023584 -63.219584)
		(width 0.12446)
		(layer "F.Cu")
		(net "PHY_IOC_TO_SCC_47_DP")
	)
	(segment
		(start 148.550376 -62.957456)
		(end 150.539958 -61.665104)
		(width 0.12446)
		(layer "F.Cu")
		(net "PHY_IOC_TO_SCC_47_DP")
	)
	(segment
		(start 146.388836 -63.14186)
		(end 146.708114 -63.349124)
		(width 0.12446)
		(layer "F.Cu")
		(net "PHY_IOC_TO_SCC_47_DP")
	)
	(segment
		(start 155.67406 -53.057298)
		(end 155.673806 -53.057298)
		(width 0.12446)
		(layer "F.Cu")
		(net "PHY_IOC_TO_SCC_47_DP")
	)
	(segment
		(start 154.897328 -56.727598)
		(end 155.219146 -55.206646)
		(width 0.12446)
		(layer "F.Cu")
		(net "PHY_IOC_TO_SCC_47_DP")
	)
	(segment
		(start 155.407868 -54.314598)
		(end 155.485338 -53.949346)
		(width 0.12446)
		(layer "F.Cu")
		(net "PHY_IOC_TO_SCC_47_DP")
	)
	(segment
		(start 156.096208 -39.969186)
		(end 156.807916 -39.507414)
		(width 0.12446)
		(layer "F.Cu")
		(net "PHY_IOC_TO_SCC_47_DP")
	)
	(segment
		(start 146.708114 -63.349124)
		(end 148.550376 -62.957456)
		(width 0.12446)
		(layer "F.Cu")
		(net "PHY_IOC_TO_SCC_47_DP")
	)
	(segment
		(start 144.559274 -63.806324)
		(end 144.766538 -63.487046)
		(width 0.12446)
		(layer "F.Cu")
		(net "PHY_IOC_TO_SCC_47_DP")
	)
	(segment
		(start 146.023584 -63.219584)
		(end 146.388836 -63.14186)
		(width 0.12446)
		(layer "F.Cu")
		(net "PHY_IOC_TO_SCC_47_DP")
	)
	(segment
		(start 143.057626 -63.791084)
		(end 143.15059 -63.884048)
		(width 0.12446)
		(layer "F.Cu")
		(net "PHY_IOC_TO_SCC_47_DP")
	)
	(segment
		(start 155.277566 -53.630068)
		(end 155.355036 -53.264816)
		(width 0.12446)
		(layer "F.Cu")
		(net "PHY_IOC_TO_SCC_47_DP")
	)
	(segment
		(start 161.659824 -38.476174)
		(end 162.392868 -37.999924)
		(width 0.12446)
		(layer "F.Cu")
		(net "PHY_IOC_TO_SCC_47_DP")
	)
	(segment
		(start 145.13179 -63.409322)
		(end 145.451068 -63.616586)
		(width 0.12446)
		(layer "F.Cu")
		(net "PHY_IOC_TO_SCC_47_DP")
	)
	(segment
		(start 162.392868 -37.999924)
		(end 163.399978 -37.999924)
		(width 0.12446)
		(layer "F.Cu")
		(net "PHY_IOC_TO_SCC_47_DP")
	)
	(segment
		(start 155.673806 -53.057298)
		(end 156.017468 -51.434492)
		(width 0.12446)
		(layer "F.Cu")
		(net "PHY_IOC_TO_SCC_47_DP")
	)
	(segment
		(start 155.219146 -55.206646)
		(end 155.011628 -54.887622)
		(width 0.12446)
		(layer "F.Cu")
		(net "PHY_IOC_TO_SCC_47_DP")
	)
	(segment
		(start 155.088844 -54.522116)
		(end 155.407868 -54.314598)
		(width 0.12446)
		(layer "F.Cu")
		(net "PHY_IOC_TO_SCC_47_DP")
	)
	(segment
		(start 145.451068 -63.616586)
		(end 145.81632 -63.538862)
		(width 0.12446)
		(layer "F.Cu")
		(net "PHY_IOC_TO_SCC_47_DP")
	)
	(segment
		(start 159.30753 -38.9763)
		(end 161.659824 -38.476174)
		(width 0.12446)
		(layer "F.Cu")
		(net "PHY_IOC_TO_SCC_47_DP")
	)
	(segment
		(start 152.483566 -60.402978)
		(end 152.530048 -60.373006)
		(width 0.12446)
		(layer "F.Cu")
		(net "PHY_IOC_TO_SCC_47_DP")
	)
	(segment
		(start 144.766538 -63.487046)
		(end 145.13179 -63.409322)
		(width 0.12446)
		(layer "F.Cu")
		(net "PHY_IOC_TO_SCC_47_DP")
	)
	(segment
		(start 155.485338 -53.949346)
		(end 155.277566 -53.630068)
		(width 0.12446)
		(layer "F.Cu")
		(net "PHY_IOC_TO_SCC_47_DP")
	)
	(segment
		(start 154.65171 -45.019722)
		(end 155.54579 -40.816276)
		(width 0.12446)
		(layer "F.Cu")
		(net "PHY_IOC_TO_SCC_47_DP")
	)
	(segment
		(start 156.807916 -39.507414)
		(end 159.30753 -38.9763)
		(width 0.12446)
		(layer "F.Cu")
		(net "PHY_IOC_TO_SCC_47_DP")
	)
	(segment
		(start 152.530048 -60.373006)
		(end 154.897328 -56.727598)
		(width 0.12446)
		(layer "F.Cu")
		(net "PHY_IOC_TO_SCC_47_DP")
	)
	(segment
		(start 155.54579 -40.816276)
		(end 156.096208 -39.969186)
		(width 0.12446)
		(layer "F.Cu")
		(net "PHY_IOC_TO_SCC_47_DP")
	)
	(segment
		(start 155.011628 -54.887622)
		(end 155.088844 -54.522116)
		(width 0.12446)
		(layer "F.Cu")
		(net "PHY_IOC_TO_SCC_47_DP")
	)
	(segment
		(start 152.823926 -60.666884)
		(end 155.279344 -56.885586)
		(width 0.12446)
		(layer "F.Cu")
		(net "PHY_IOC_TO_SCC_47_DN")
	)
	(segment
		(start 156.337762 -51.884326)
		(end 156.338016 -51.88331)
		(width 0.12446)
		(layer "F.Cu")
		(net "PHY_IOC_TO_SCC_47_DN")
	)
	(segment
		(start 144.314418 -64.273938)
		(end 148.708618 -63.339472)
		(width 0.12446)
		(layer "F.Cu")
		(net "PHY_IOC_TO_SCC_47_DN")
	)
	(segment
		(start 156.390086 -40.263318)
		(end 156.821886 -39.982902)
		(width 0.12446)
		(layer "F.Cu")
		(net "PHY_IOC_TO_SCC_47_DN")
	)
	(segment
		(start 156.338016 -51.88331)
		(end 156.433266 -51.434746)
		(width 0.12446)
		(layer "F.Cu")
		(net "PHY_IOC_TO_SCC_47_DN")
	)
	(segment
		(start 156.433266 -51.434746)
		(end 155.067254 -45.019722)
		(width 0.12446)
		(layer "F.Cu")
		(net "PHY_IOC_TO_SCC_47_DN")
	)
	(segment
		(start 162.513518 -38.406324)
		(end 163.473384 -38.406324)
		(width 0.12446)
		(layer "F.Cu")
		(net "PHY_IOC_TO_SCC_47_DN")
	)
	(segment
		(start 161.818066 -38.85819)
		(end 162.513518 -38.406324)
		(width 0.12446)
		(layer "F.Cu")
		(net "PHY_IOC_TO_SCC_47_DN")
	)
	(segment
		(start 144.297908 -64.290448)
		(end 144.314418 -64.273938)
		(width 0.12446)
		(layer "F.Cu")
		(net "PHY_IOC_TO_SCC_47_DN")
	)
	(segment
		(start 155.927806 -40.974518)
		(end 156.390086 -40.263318)
		(width 0.12446)
		(layer "F.Cu")
		(net "PHY_IOC_TO_SCC_47_DN")
	)
	(segment
		(start 163.473384 -38.406324)
		(end 164.199824 -37.999924)
		(width 0.12446)
		(layer "F.Cu")
		(net "PHY_IOC_TO_SCC_47_DN")
	)
	(segment
		(start 143.057626 -64.375284)
		(end 143.142462 -64.290448)
		(width 0.12446)
		(layer "F.Cu")
		(net "PHY_IOC_TO_SCC_47_DN")
	)
	(segment
		(start 155.067254 -45.019722)
		(end 155.927806 -40.974518)
		(width 0.12446)
		(layer "F.Cu")
		(net "PHY_IOC_TO_SCC_47_DN")
	)
	(segment
		(start 156.821886 -39.982902)
		(end 156.82214 -39.982902)
		(width 0.12446)
		(layer "F.Cu")
		(net "PHY_IOC_TO_SCC_47_DN")
	)
	(segment
		(start 148.708618 -63.339472)
		(end 152.823926 -60.666884)
		(width 0.12446)
		(layer "F.Cu")
		(net "PHY_IOC_TO_SCC_47_DN")
	)
	(segment
		(start 156.966158 -39.88943)
		(end 161.818066 -38.85819)
		(width 0.12446)
		(layer "F.Cu")
		(net "PHY_IOC_TO_SCC_47_DN")
	)
	(segment
		(start 143.142462 -64.290448)
		(end 144.297908 -64.290448)
		(width 0.12446)
		(layer "F.Cu")
		(net "PHY_IOC_TO_SCC_47_DN")
	)
	(segment
		(start 155.279344 -56.885586)
		(end 156.337762 -51.884326)
		(width 0.12446)
		(layer "F.Cu")
		(net "PHY_IOC_TO_SCC_47_DN")
	)
	(segment
		(start 156.82214 -39.982902)
		(end 156.966158 -39.88943)
		(width 0.12446)
		(layer "F.Cu")
		(net "PHY_IOC_TO_SCC_47_DN")
	)
	(segment
		(start 157.274006 -37.771324)
		(end 156.909008 -37.849048)
		(width 0.12446)
		(layer "F.Cu")
		(net "PHY_IOC_TO_SCC_46_DP")
	)
	(segment
		(start 159.215836 -37.63264)
		(end 158.850584 -37.710364)
		(width 0.12446)
		(layer "F.Cu")
		(net "PHY_IOC_TO_SCC_46_DP")
	)
	(segment
		(start 155.345384 -38.890194)
		(end 154.400504 -40.344852)
		(width 0.12446)
		(layer "F.Cu")
		(net "PHY_IOC_TO_SCC_46_DP")
	)
	(segment
		(start 154.400504 -40.344852)
		(end 153.401776 -45.04436)
		(width 0.12446)
		(layer "F.Cu")
		(net "PHY_IOC_TO_SCC_46_DP")
	)
	(segment
		(start 154.619452 -50.773584)
		(end 153.347166 -56.758078)
		(width 0.12446)
		(layer "F.Cu")
		(net "PHY_IOC_TO_SCC_46_DP")
	)
	(segment
		(start 143.504666 -61.952886)
		(end 143.086328 -61.952886)
		(width 0.12446)
		(layer "F.Cu")
		(net "PHY_IOC_TO_SCC_46_DP")
	)
	(segment
		(start 153.347166 -56.758078)
		(end 151.77516 -59.179714)
		(width 0.12446)
		(layer "F.Cu")
		(net "PHY_IOC_TO_SCC_46_DP")
	)
	(segment
		(start 156.699966 -38.169088)
		(end 156.336746 -38.246304)
		(width 0.12446)
		(layer "F.Cu")
		(net "PHY_IOC_TO_SCC_46_DP")
	)
	(segment
		(start 153.41981 -45.128942)
		(end 154.619452 -50.773584)
		(width 0.12446)
		(layer "F.Cu")
		(net "PHY_IOC_TO_SCC_46_DP")
	)
	(segment
		(start 144.416526 -61.952886)
		(end 144.147286 -61.683646)
		(width 0.12446)
		(layer "F.Cu")
		(net "PHY_IOC_TO_SCC_46_DP")
	)
	(segment
		(start 151.77516 -59.179714)
		(end 148.979636 -60.994798)
		(width 0.12446)
		(layer "F.Cu")
		(net "PHY_IOC_TO_SCC_46_DP")
	)
	(segment
		(start 145.274284 -61.952886)
		(end 144.416526 -61.952886)
		(width 0.12446)
		(layer "F.Cu")
		(net "PHY_IOC_TO_SCC_46_DP")
	)
	(segment
		(start 157.593538 -37.978334)
		(end 157.274006 -37.771324)
		(width 0.12446)
		(layer "F.Cu")
		(net "PHY_IOC_TO_SCC_46_DP")
	)
	(segment
		(start 153.401776 -45.04436)
		(end 153.419556 -45.128942)
		(width 0.12446)
		(layer "F.Cu")
		(net "PHY_IOC_TO_SCC_46_DP")
	)
	(segment
		(start 156.701744 -38.16858)
		(end 156.699966 -38.169088)
		(width 0.12446)
		(layer "F.Cu")
		(net "PHY_IOC_TO_SCC_46_DP")
	)
	(segment
		(start 143.086328 -61.952886)
		(end 142.997428 -61.863986)
		(width 0.12446)
		(layer "F.Cu")
		(net "PHY_IOC_TO_SCC_46_DP")
	)
	(segment
		(start 158.531052 -37.503354)
		(end 158.166054 -37.581078)
		(width 0.12446)
		(layer "F.Cu")
		(net "PHY_IOC_TO_SCC_46_DP")
	)
	(segment
		(start 153.419556 -45.128942)
		(end 153.41981 -45.128942)
		(width 0.12446)
		(layer "F.Cu")
		(net "PHY_IOC_TO_SCC_46_DP")
	)
	(segment
		(start 156.336746 -38.246304)
		(end 155.345384 -38.890194)
		(width 0.12446)
		(layer "F.Cu")
		(net "PHY_IOC_TO_SCC_46_DP")
	)
	(segment
		(start 142.997428 -61.863986)
		(end 142.63116 -61.863986)
		(width 0.12446)
		(layer "F.Cu")
		(net "PHY_IOC_TO_SCC_46_DP")
	)
	(segment
		(start 159.4231 -37.313108)
		(end 159.215836 -37.63264)
		(width 0.12446)
		(layer "F.Cu")
		(net "PHY_IOC_TO_SCC_46_DP")
	)
	(segment
		(start 148.979636 -60.994798)
		(end 145.274284 -61.952886)
		(width 0.12446)
		(layer "F.Cu")
		(net "PHY_IOC_TO_SCC_46_DP")
	)
	(segment
		(start 144.147286 -61.683646)
		(end 143.773906 -61.683646)
		(width 0.12446)
		(layer "F.Cu")
		(net "PHY_IOC_TO_SCC_46_DP")
	)
	(segment
		(start 158.166054 -37.581078)
		(end 157.95879 -37.90061)
		(width 0.12446)
		(layer "F.Cu")
		(net "PHY_IOC_TO_SCC_46_DP")
	)
	(segment
		(start 157.95879 -37.90061)
		(end 157.593538 -37.978334)
		(width 0.12446)
		(layer "F.Cu")
		(net "PHY_IOC_TO_SCC_46_DP")
	)
	(segment
		(start 163.399978 -37.199824)
		(end 161.247074 -37.199824)
		(width 0.12446)
		(layer "F.Cu")
		(net "PHY_IOC_TO_SCC_46_DP")
	)
	(segment
		(start 143.773906 -61.683646)
		(end 143.504666 -61.952886)
		(width 0.12446)
		(layer "F.Cu")
		(net "PHY_IOC_TO_SCC_46_DP")
	)
	(segment
		(start 159.788098 -37.235384)
		(end 159.4231 -37.313108)
		(width 0.12446)
		(layer "F.Cu")
		(net "PHY_IOC_TO_SCC_46_DP")
	)
	(segment
		(start 160.10763 -37.442648)
		(end 159.788098 -37.235384)
		(width 0.12446)
		(layer "F.Cu")
		(net "PHY_IOC_TO_SCC_46_DP")
	)
	(segment
		(start 161.247074 -37.199824)
		(end 160.10763 -37.442648)
		(width 0.12446)
		(layer "F.Cu")
		(net "PHY_IOC_TO_SCC_46_DP")
	)
	(segment
		(start 158.850584 -37.710364)
		(end 158.531052 -37.503354)
		(width 0.12446)
		(layer "F.Cu")
		(net "PHY_IOC_TO_SCC_46_DP")
	)
	(segment
		(start 156.909008 -37.849048)
		(end 156.701744 -38.16858)
		(width 0.12446)
		(layer "F.Cu")
		(net "PHY_IOC_TO_SCC_46_DP")
	)
	(segment
		(start 154.78252 -40.503094)
		(end 153.81732 -45.04436)
		(width 0.12446)
		(layer "F.Cu")
		(net "PHY_IOC_TO_SCC_46_DN")
	)
	(segment
		(start 155.639262 -39.184072)
		(end 154.78252 -40.503094)
		(width 0.12446)
		(layer "F.Cu")
		(net "PHY_IOC_TO_SCC_46_DN")
	)
	(segment
		(start 156.067506 -38.906196)
		(end 156.067506 -38.905942)
		(width 0.12446)
		(layer "F.Cu")
		(net "PHY_IOC_TO_SCC_46_DN")
	)
	(segment
		(start 161.29 -37.606224)
		(end 156.494988 -38.62832)
		(width 0.12446)
		(layer "F.Cu")
		(net "PHY_IOC_TO_SCC_46_DN")
	)
	(segment
		(start 149.145498 -61.371734)
		(end 145.3261 -62.359286)
		(width 0.12446)
		(layer "F.Cu")
		(net "PHY_IOC_TO_SCC_46_DN")
	)
	(segment
		(start 163.582858 -37.606224)
		(end 161.29 -37.606224)
		(width 0.12446)
		(layer "F.Cu")
		(net "PHY_IOC_TO_SCC_46_DN")
	)
	(segment
		(start 152.069038 -59.473592)
		(end 149.145498 -61.371734)
		(width 0.12446)
		(layer "F.Cu")
		(net "PHY_IOC_TO_SCC_46_DN")
	)
	(segment
		(start 156.067506 -38.905942)
		(end 155.639262 -39.184072)
		(width 0.12446)
		(layer "F.Cu")
		(net "PHY_IOC_TO_SCC_46_DN")
	)
	(segment
		(start 143.086328 -62.359286)
		(end 142.997428 -62.448186)
		(width 0.12446)
		(layer "F.Cu")
		(net "PHY_IOC_TO_SCC_46_DN")
	)
	(segment
		(start 156.494988 -38.62832)
		(end 156.067506 -38.906196)
		(width 0.12446)
		(layer "F.Cu")
		(net "PHY_IOC_TO_SCC_46_DN")
	)
	(segment
		(start 164.199824 -37.199824)
		(end 163.582858 -37.606224)
		(width 0.12446)
		(layer "F.Cu")
		(net "PHY_IOC_TO_SCC_46_DN")
	)
	(segment
		(start 145.3261 -62.359286)
		(end 143.086328 -62.359286)
		(width 0.12446)
		(layer "F.Cu")
		(net "PHY_IOC_TO_SCC_46_DN")
	)
	(segment
		(start 142.997428 -62.448186)
		(end 142.63116 -62.448186)
		(width 0.12446)
		(layer "F.Cu")
		(net "PHY_IOC_TO_SCC_46_DN")
	)
	(segment
		(start 153.81732 -45.04436)
		(end 155.034996 -50.773584)
		(width 0.12446)
		(layer "F.Cu")
		(net "PHY_IOC_TO_SCC_46_DN")
	)
	(segment
		(start 153.729182 -56.91632)
		(end 152.069038 -59.473592)
		(width 0.12446)
		(layer "F.Cu")
		(net "PHY_IOC_TO_SCC_46_DN")
	)
	(segment
		(start 155.034996 -50.773584)
		(end 153.729182 -56.91632)
		(width 0.12446)
		(layer "F.Cu")
		(net "PHY_IOC_TO_SCC_46_DN")
	)
	(segment
		(start 153.349198 -50.777648)
		(end 153.271474 -51.1429)
		(width 0.12446)
		(layer "F.Cu")
		(net "PHY_IOC_TO_SCC_45_DP")
	)
	(segment
		(start 152.874726 -51.715416)
		(end 153.08199 -52.034948)
		(width 0.12446)
		(layer "F.Cu")
		(net "PHY_IOC_TO_SCC_45_DP")
	)
	(segment
		(start 152.737312 -53.657246)
		(end 152.418034 -53.864764)
		(width 0.12446)
		(layer "F.Cu")
		(net "PHY_IOC_TO_SCC_45_DP")
	)
	(segment
		(start 153.271474 -51.1429)
		(end 152.952196 -51.350164)
		(width 0.12446)
		(layer "F.Cu")
		(net "PHY_IOC_TO_SCC_45_DP")
	)
	(segment
		(start 149.09292 -59.26836)
		(end 147.347432 -59.6392)
		(width 0.12446)
		(layer "F.Cu")
		(net "PHY_IOC_TO_SCC_45_DP")
	)
	(segment
		(start 144.630902 -59.760612)
		(end 144.361662 -60.029852)
		(width 0.12446)
		(layer "F.Cu")
		(net "PHY_IOC_TO_SCC_45_DP")
	)
	(segment
		(start 162.98164 -35.599878)
		(end 162.687762 -35.306)
		(width 0.12446)
		(layer "F.Cu")
		(net "PHY_IOC_TO_SCC_45_DP")
	)
	(segment
		(start 154.52217 -37.922962)
		(end 153.237184 -39.901368)
		(width 0.12446)
		(layer "F.Cu")
		(net "PHY_IOC_TO_SCC_45_DP")
	)
	(segment
		(start 153.00452 -52.399946)
		(end 152.685242 -52.607464)
		(width 0.12446)
		(layer "F.Cu")
		(net "PHY_IOC_TO_SCC_45_DP")
	)
	(segment
		(start 144.361662 -60.029852)
		(end 143.312388 -60.029852)
		(width 0.12446)
		(layer "F.Cu")
		(net "PHY_IOC_TO_SCC_45_DP")
	)
	(segment
		(start 152.340564 -54.229762)
		(end 152.547828 -54.549294)
		(width 0.12446)
		(layer "F.Cu")
		(net "PHY_IOC_TO_SCC_45_DP")
	)
	(segment
		(start 152.547828 -54.549294)
		(end 152.174956 -56.30418)
		(width 0.12446)
		(layer "F.Cu")
		(net "PHY_IOC_TO_SCC_45_DP")
	)
	(segment
		(start 145.754852 -60.029852)
		(end 145.273522 -60.029852)
		(width 0.12446)
		(layer "F.Cu")
		(net "PHY_IOC_TO_SCC_45_DP")
	)
	(segment
		(start 152.607518 -52.972716)
		(end 152.815036 -53.291994)
		(width 0.12446)
		(layer "F.Cu")
		(net "PHY_IOC_TO_SCC_45_DP")
	)
	(segment
		(start 152.685242 -52.607464)
		(end 152.607518 -52.972716)
		(width 0.12446)
		(layer "F.Cu")
		(net "PHY_IOC_TO_SCC_45_DP")
	)
	(segment
		(start 152.418034 -53.864764)
		(end 152.340564 -54.229762)
		(width 0.12446)
		(layer "F.Cu")
		(net "PHY_IOC_TO_SCC_45_DP")
	)
	(segment
		(start 156.409898 -36.696904)
		(end 154.52217 -37.922962)
		(width 0.12446)
		(layer "F.Cu")
		(net "PHY_IOC_TO_SCC_45_DP")
	)
	(segment
		(start 152.952196 -51.350164)
		(end 152.874726 -51.715416)
		(width 0.12446)
		(layer "F.Cu")
		(net "PHY_IOC_TO_SCC_45_DP")
	)
	(segment
		(start 160.814512 -35.760152)
		(end 156.409898 -36.696904)
		(width 0.12446)
		(layer "F.Cu")
		(net "PHY_IOC_TO_SCC_45_DP")
	)
	(segment
		(start 162.687762 -35.306)
		(end 161.514028 -35.306)
		(width 0.12446)
		(layer "F.Cu")
		(net "PHY_IOC_TO_SCC_45_DP")
	)
	(segment
		(start 143.223488 -59.940952)
		(end 142.85722 -59.940952)
		(width 0.12446)
		(layer "F.Cu")
		(net "PHY_IOC_TO_SCC_45_DP")
	)
	(segment
		(start 163.399978 -35.599878)
		(end 162.98164 -35.599878)
		(width 0.12446)
		(layer "F.Cu")
		(net "PHY_IOC_TO_SCC_45_DP")
	)
	(segment
		(start 145.273522 -60.029852)
		(end 145.004282 -59.760612)
		(width 0.12446)
		(layer "F.Cu")
		(net "PHY_IOC_TO_SCC_45_DP")
	)
	(segment
		(start 152.174956 -56.30418)
		(end 151.094186 -57.968388)
		(width 0.12446)
		(layer "F.Cu")
		(net "PHY_IOC_TO_SCC_45_DP")
	)
	(segment
		(start 161.514028 -35.306)
		(end 160.814512 -35.760152)
		(width 0.12446)
		(layer "F.Cu")
		(net "PHY_IOC_TO_SCC_45_DP")
	)
	(segment
		(start 143.312388 -60.029852)
		(end 143.223488 -59.940952)
		(width 0.12446)
		(layer "F.Cu")
		(net "PHY_IOC_TO_SCC_45_DP")
	)
	(segment
		(start 147.347432 -59.6392)
		(end 145.754852 -60.029852)
		(width 0.12446)
		(layer "F.Cu")
		(net "PHY_IOC_TO_SCC_45_DP")
	)
	(segment
		(start 151.094186 -57.968388)
		(end 149.09292 -59.26836)
		(width 0.12446)
		(layer "F.Cu")
		(net "PHY_IOC_TO_SCC_45_DP")
	)
	(segment
		(start 153.237184 -39.901368)
		(end 152.136094 -45.074332)
		(width 0.12446)
		(layer "F.Cu")
		(net "PHY_IOC_TO_SCC_45_DP")
	)
	(segment
		(start 145.004282 -59.760612)
		(end 144.630902 -59.760612)
		(width 0.12446)
		(layer "F.Cu")
		(net "PHY_IOC_TO_SCC_45_DP")
	)
	(segment
		(start 153.08199 -52.034948)
		(end 153.00452 -52.399946)
		(width 0.12446)
		(layer "F.Cu")
		(net "PHY_IOC_TO_SCC_45_DP")
	)
	(segment
		(start 152.815036 -53.291994)
		(end 152.737312 -53.657246)
		(width 0.12446)
		(layer "F.Cu")
		(net "PHY_IOC_TO_SCC_45_DP")
	)
	(segment
		(start 152.136094 -45.074332)
		(end 153.349198 -50.777648)
		(width 0.12446)
		(layer "F.Cu")
		(net "PHY_IOC_TO_SCC_45_DP")
	)
	(segment
		(start 153.6192 -40.05961)
		(end 152.551638 -45.074332)
		(width 0.12446)
		(layer "F.Cu")
		(net "PHY_IOC_TO_SCC_45_DN")
	)
	(segment
		(start 143.312388 -60.436252)
		(end 143.223488 -60.525152)
		(width 0.12446)
		(layer "F.Cu")
		(net "PHY_IOC_TO_SCC_45_DN")
	)
	(segment
		(start 152.551638 -45.074332)
		(end 153.764742 -50.777648)
		(width 0.12446)
		(layer "F.Cu")
		(net "PHY_IOC_TO_SCC_45_DN")
	)
	(segment
		(start 149.251162 -59.650376)
		(end 147.43811 -60.03544)
		(width 0.12446)
		(layer "F.Cu")
		(net "PHY_IOC_TO_SCC_45_DN")
	)
	(segment
		(start 143.223488 -60.525152)
		(end 142.85722 -60.525152)
		(width 0.12446)
		(layer "F.Cu")
		(net "PHY_IOC_TO_SCC_45_DN")
	)
	(segment
		(start 153.764742 -50.777648)
		(end 152.556972 -56.462422)
		(width 0.12446)
		(layer "F.Cu")
		(net "PHY_IOC_TO_SCC_45_DN")
	)
	(segment
		(start 161.634424 -35.7124)
		(end 160.972754 -36.142168)
		(width 0.12446)
		(layer "F.Cu")
		(net "PHY_IOC_TO_SCC_45_DN")
	)
	(segment
		(start 147.43811 -60.03544)
		(end 145.804128 -60.436252)
		(width 0.12446)
		(layer "F.Cu")
		(net "PHY_IOC_TO_SCC_45_DN")
	)
	(segment
		(start 163.504118 -36.006278)
		(end 162.813238 -36.006278)
		(width 0.12446)
		(layer "F.Cu")
		(net "PHY_IOC_TO_SCC_45_DN")
	)
	(segment
		(start 145.804128 -60.436252)
		(end 143.312388 -60.436252)
		(width 0.12446)
		(layer "F.Cu")
		(net "PHY_IOC_TO_SCC_45_DN")
	)
	(segment
		(start 151.388064 -58.262266)
		(end 149.251162 -59.650376)
		(width 0.12446)
		(layer "F.Cu")
		(net "PHY_IOC_TO_SCC_45_DN")
	)
	(segment
		(start 164.199824 -35.599878)
		(end 163.504118 -36.006278)
		(width 0.12446)
		(layer "F.Cu")
		(net "PHY_IOC_TO_SCC_45_DN")
	)
	(segment
		(start 156.56814 -37.07892)
		(end 154.816048 -38.21684)
		(width 0.12446)
		(layer "F.Cu")
		(net "PHY_IOC_TO_SCC_45_DN")
	)
	(segment
		(start 152.556972 -56.462422)
		(end 151.388064 -58.262266)
		(width 0.12446)
		(layer "F.Cu")
		(net "PHY_IOC_TO_SCC_45_DN")
	)
	(segment
		(start 160.972754 -36.142168)
		(end 156.56814 -37.07892)
		(width 0.12446)
		(layer "F.Cu")
		(net "PHY_IOC_TO_SCC_45_DN")
	)
	(segment
		(start 162.51936 -35.7124)
		(end 161.634424 -35.7124)
		(width 0.12446)
		(layer "F.Cu")
		(net "PHY_IOC_TO_SCC_45_DN")
	)
	(segment
		(start 154.816048 -38.21684)
		(end 153.6192 -40.05961)
		(width 0.12446)
		(layer "F.Cu")
		(net "PHY_IOC_TO_SCC_45_DN")
	)
	(segment
		(start 162.813238 -36.006278)
		(end 162.51936 -35.7124)
		(width 0.12446)
		(layer "F.Cu")
		(net "PHY_IOC_TO_SCC_45_DN")
	)
	(segment
		(start 151.00808 -47.043848)
		(end 150.930356 -46.678596)
		(width 0.12446)
		(layer "F.Cu")
		(net "PHY_IOC_TO_SCC_44_DP")
	)
	(segment
		(start 151.940006 -50.130456)
		(end 151.59482 -48.508158)
		(width 0.12446)
		(layer "F.Cu")
		(net "PHY_IOC_TO_SCC_44_DP")
	)
	(segment
		(start 147.509738 -57.8104)
		(end 148.23694 -57.655714)
		(width 0.12446)
		(layer "F.Cu")
		(net "PHY_IOC_TO_SCC_44_DP")
	)
	(segment
		(start 151.197818 -47.935642)
		(end 151.405082 -47.616364)
		(width 0.12446)
		(layer "F.Cu")
		(net "PHY_IOC_TO_SCC_44_DP")
	)
	(segment
		(start 143.27251 -57.7215)
		(end 143.638778 -57.7215)
		(width 0.12446)
		(layer "F.Cu")
		(net "PHY_IOC_TO_SCC_44_DP")
	)
	(segment
		(start 151.48687 -40.930322)
		(end 151.564594 -40.565324)
		(width 0.12446)
		(layer "F.Cu")
		(net "PHY_IOC_TO_SCC_44_DP")
	)
	(segment
		(start 143.638778 -57.7215)
		(end 143.727678 -57.8104)
		(width 0.12446)
		(layer "F.Cu")
		(net "PHY_IOC_TO_SCC_44_DP")
	)
	(segment
		(start 150.872952 -45.114464)
		(end 151.42718 -42.5069)
		(width 0.12446)
		(layer "F.Cu")
		(net "PHY_IOC_TO_SCC_44_DP")
	)
	(segment
		(start 162.948366 -34.5186)
		(end 163.229798 -34.800032)
		(width 0.12446)
		(layer "F.Cu")
		(net "PHY_IOC_TO_SCC_44_DP")
	)
	(segment
		(start 151.883872 -40.357806)
		(end 152.075642 -39.455598)
		(width 0.12446)
		(layer "F.Cu")
		(net "PHY_IOC_TO_SCC_44_DP")
	)
	(segment
		(start 148.23694 -57.65546)
		(end 148.964142 -57.501282)
		(width 0.12446)
		(layer "F.Cu")
		(net "PHY_IOC_TO_SCC_44_DP")
	)
	(segment
		(start 151.405082 -47.616364)
		(end 151.327358 -47.251112)
		(width 0.12446)
		(layer "F.Cu")
		(net "PHY_IOC_TO_SCC_44_DP")
	)
	(segment
		(start 151.327358 -47.251112)
		(end 151.00808 -47.043848)
		(width 0.12446)
		(layer "F.Cu")
		(net "PHY_IOC_TO_SCC_44_DP")
	)
	(segment
		(start 143.727678 -57.8104)
		(end 147.509738 -57.8104)
		(width 0.12446)
		(layer "F.Cu")
		(net "PHY_IOC_TO_SCC_44_DP")
	)
	(segment
		(start 148.964142 -57.501282)
		(end 150.250652 -56.665622)
		(width 0.12446)
		(layer "F.Cu")
		(net "PHY_IOC_TO_SCC_44_DP")
	)
	(segment
		(start 150.930356 -46.678596)
		(end 151.13762 -46.359318)
		(width 0.12446)
		(layer "F.Cu")
		(net "PHY_IOC_TO_SCC_44_DP")
	)
	(segment
		(start 151.13762 -46.359318)
		(end 150.872952 -45.114464)
		(width 0.12446)
		(layer "F.Cu")
		(net "PHY_IOC_TO_SCC_44_DP")
	)
	(segment
		(start 151.616664 -41.615106)
		(end 151.694388 -41.249854)
		(width 0.12446)
		(layer "F.Cu")
		(net "PHY_IOC_TO_SCC_44_DP")
	)
	(segment
		(start 150.696676 -55.978806)
		(end 151.940006 -50.130456)
		(width 0.12446)
		(layer "F.Cu")
		(net "PHY_IOC_TO_SCC_44_DP")
	)
	(segment
		(start 151.219916 -42.187622)
		(end 151.297386 -41.82237)
		(width 0.12446)
		(layer "F.Cu")
		(net "PHY_IOC_TO_SCC_44_DP")
	)
	(segment
		(start 151.297386 -41.82237)
		(end 151.616664 -41.615106)
		(width 0.12446)
		(layer "F.Cu")
		(net "PHY_IOC_TO_SCC_44_DP")
	)
	(segment
		(start 150.250652 -56.665622)
		(end 150.696676 -55.978806)
		(width 0.12446)
		(layer "F.Cu")
		(net "PHY_IOC_TO_SCC_44_DP")
	)
	(segment
		(start 153.647394 -37.03574)
		(end 155.957016 -35.536124)
		(width 0.12446)
		(layer "F.Cu")
		(net "PHY_IOC_TO_SCC_44_DP")
	)
	(segment
		(start 155.957016 -35.536124)
		(end 160.744916 -34.5186)
		(width 0.12446)
		(layer "F.Cu")
		(net "PHY_IOC_TO_SCC_44_DP")
	)
	(segment
		(start 151.59482 -48.508158)
		(end 151.275542 -48.300894)
		(width 0.12446)
		(layer "F.Cu")
		(net "PHY_IOC_TO_SCC_44_DP")
	)
	(segment
		(start 151.42718 -42.5069)
		(end 151.219916 -42.187622)
		(width 0.12446)
		(layer "F.Cu")
		(net "PHY_IOC_TO_SCC_44_DP")
	)
	(segment
		(start 163.229798 -34.800032)
		(end 163.399978 -34.800032)
		(width 0.12446)
		(layer "F.Cu")
		(net "PHY_IOC_TO_SCC_44_DP")
	)
	(segment
		(start 160.744916 -34.5186)
		(end 162.948366 -34.5186)
		(width 0.12446)
		(layer "F.Cu")
		(net "PHY_IOC_TO_SCC_44_DP")
	)
	(segment
		(start 152.075642 -39.455598)
		(end 153.647394 -37.03574)
		(width 0.12446)
		(layer "F.Cu")
		(net "PHY_IOC_TO_SCC_44_DP")
	)
	(segment
		(start 151.564594 -40.565324)
		(end 151.883872 -40.357806)
		(width 0.12446)
		(layer "F.Cu")
		(net "PHY_IOC_TO_SCC_44_DP")
	)
	(segment
		(start 151.275542 -48.300894)
		(end 151.197818 -47.935642)
		(width 0.12446)
		(layer "F.Cu")
		(net "PHY_IOC_TO_SCC_44_DP")
	)
	(segment
		(start 151.694388 -41.249854)
		(end 151.48687 -40.930322)
		(width 0.12446)
		(layer "F.Cu")
		(net "PHY_IOC_TO_SCC_44_DP")
	)
	(segment
		(start 148.23694 -57.655714)
		(end 148.23694 -57.65546)
		(width 0.12446)
		(layer "F.Cu")
		(net "PHY_IOC_TO_SCC_44_DP")
	)
	(segment
		(start 152.457658 -39.61384)
		(end 151.288496 -45.114464)
		(width 0.12446)
		(layer "F.Cu")
		(net "PHY_IOC_TO_SCC_44_DN")
	)
	(segment
		(start 151.288496 -45.114464)
		(end 152.35555 -50.130456)
		(width 0.12446)
		(layer "F.Cu")
		(net "PHY_IOC_TO_SCC_44_DN")
	)
	(segment
		(start 164.199824 -34.800032)
		(end 163.399978 -35.206432)
		(width 0.12446)
		(layer "F.Cu")
		(net "PHY_IOC_TO_SCC_44_DN")
	)
	(segment
		(start 156.115258 -35.91814)
		(end 153.941272 -37.329618)
		(width 0.12446)
		(layer "F.Cu")
		(net "PHY_IOC_TO_SCC_44_DN")
	)
	(segment
		(start 149.12213 -57.883298)
		(end 147.552664 -58.2168)
		(width 0.12446)
		(layer "F.Cu")
		(net "PHY_IOC_TO_SCC_44_DN")
	)
	(segment
		(start 143.638778 -58.3057)
		(end 143.27251 -58.3057)
		(width 0.12446)
		(layer "F.Cu")
		(net "PHY_IOC_TO_SCC_44_DN")
	)
	(segment
		(start 160.787842 -34.925)
		(end 156.115258 -35.91814)
		(width 0.12446)
		(layer "F.Cu")
		(net "PHY_IOC_TO_SCC_44_DN")
	)
	(segment
		(start 163.061396 -35.206432)
		(end 162.779964 -34.925)
		(width 0.12446)
		(layer "F.Cu")
		(net "PHY_IOC_TO_SCC_44_DN")
	)
	(segment
		(start 143.727678 -58.2168)
		(end 143.638778 -58.3057)
		(width 0.12446)
		(layer "F.Cu")
		(net "PHY_IOC_TO_SCC_44_DN")
	)
	(segment
		(start 153.941272 -37.329618)
		(end 152.457658 -39.61384)
		(width 0.12446)
		(layer "F.Cu")
		(net "PHY_IOC_TO_SCC_44_DN")
	)
	(segment
		(start 152.35555 -50.130456)
		(end 151.078692 -56.137048)
		(width 0.12446)
		(layer "F.Cu")
		(net "PHY_IOC_TO_SCC_44_DN")
	)
	(segment
		(start 151.078692 -56.137048)
		(end 150.54453 -56.9595)
		(width 0.12446)
		(layer "F.Cu")
		(net "PHY_IOC_TO_SCC_44_DN")
	)
	(segment
		(start 162.779964 -34.925)
		(end 160.787842 -34.925)
		(width 0.12446)
		(layer "F.Cu")
		(net "PHY_IOC_TO_SCC_44_DN")
	)
	(segment
		(start 150.54453 -56.9595)
		(end 149.12213 -57.883298)
		(width 0.12446)
		(layer "F.Cu")
		(net "PHY_IOC_TO_SCC_44_DN")
	)
	(segment
		(start 163.399978 -35.206432)
		(end 163.061396 -35.206432)
		(width 0.12446)
		(layer "F.Cu")
		(net "PHY_IOC_TO_SCC_44_DN")
	)
	(segment
		(start 147.552664 -58.2168)
		(end 143.727678 -58.2168)
		(width 0.12446)
		(layer "F.Cu")
		(net "PHY_IOC_TO_SCC_44_DN")
	)
	(segment
		(start 157.447996 -31.382208)
		(end 157.447742 -31.381954)
		(width 0.12446)
		(layer "F.Cu")
		(net "PHY_IOC_TO_SCC_43_DP")
	)
	(segment
		(start 162.265868 -33.199832)
		(end 159.269938 -32.565848)
		(width 0.12446)
		(layer "F.Cu")
		(net "PHY_IOC_TO_SCC_43_DP")
	)
	(segment
		(start 157.447742 -31.381954)
		(end 154.777694 -27.271472)
		(width 0.12446)
		(layer "F.Cu")
		(net "PHY_IOC_TO_SCC_43_DP")
	)
	(segment
		(start 133.62178 -42.346626)
		(end 133.41858 -42.659808)
		(width 0.12446)
		(layer "F.Cu")
		(net "PHY_IOC_TO_SCC_43_DP")
	)
	(segment
		(start 133.41858 -42.659808)
		(end 133.497574 -43.032426)
		(width 0.12446)
		(layer "F.Cu")
		(net "PHY_IOC_TO_SCC_43_DP")
	)
	(segment
		(start 146.635216 -27.010868)
		(end 141.903704 -30.08376)
		(width 0.12446)
		(layer "F.Cu")
		(net "PHY_IOC_TO_SCC_43_DP")
	)
	(segment
		(start 133.25983 -43.398694)
		(end 133.25983 -43.968416)
		(width 0.12446)
		(layer "F.Cu")
		(net "PHY_IOC_TO_SCC_43_DP")
	)
	(segment
		(start 141.903704 -30.08376)
		(end 133.994144 -42.267378)
		(width 0.12446)
		(layer "F.Cu")
		(net "PHY_IOC_TO_SCC_43_DP")
	)
	(segment
		(start 159.269938 -32.565848)
		(end 157.447996 -31.382208)
		(width 0.12446)
		(layer "F.Cu")
		(net "PHY_IOC_TO_SCC_43_DP")
	)
	(segment
		(start 133.14553 -44.082716)
		(end 133.14553 -44.423584)
		(width 0.12446)
		(layer "F.Cu")
		(net "PHY_IOC_TO_SCC_43_DP")
	)
	(segment
		(start 147.80641 -26.464006)
		(end 147.212558 -26.741374)
		(width 0.12446)
		(layer "F.Cu")
		(net "PHY_IOC_TO_SCC_43_DP")
	)
	(segment
		(start 147.212558 -26.741374)
		(end 146.635216 -27.010868)
		(width 0.12446)
		(layer "F.Cu")
		(net "PHY_IOC_TO_SCC_43_DP")
	)
	(segment
		(start 133.994144 -42.267378)
		(end 133.62178 -42.346626)
		(width 0.12446)
		(layer "F.Cu")
		(net "PHY_IOC_TO_SCC_43_DP")
	)
	(segment
		(start 154.777694 -27.271472)
		(end 152.682448 -25.91181)
		(width 0.12446)
		(layer "F.Cu")
		(net "PHY_IOC_TO_SCC_43_DP")
	)
	(segment
		(start 163.399978 -33.199832)
		(end 162.265868 -33.199832)
		(width 0.12446)
		(layer "F.Cu")
		(net "PHY_IOC_TO_SCC_43_DP")
	)
	(segment
		(start 151.543512 -25.66924)
		(end 147.80641 -26.464006)
		(width 0.12446)
		(layer "F.Cu")
		(net "PHY_IOC_TO_SCC_43_DP")
	)
	(segment
		(start 133.497574 -43.032426)
		(end 133.25983 -43.398694)
		(width 0.12446)
		(layer "F.Cu")
		(net "PHY_IOC_TO_SCC_43_DP")
	)
	(segment
		(start 152.682448 -25.91181)
		(end 151.543512 -25.66924)
		(width 0.12446)
		(layer "F.Cu")
		(net "PHY_IOC_TO_SCC_43_DP")
	)
	(segment
		(start 133.25983 -43.968416)
		(end 133.14553 -44.082716)
		(width 0.12446)
		(layer "F.Cu")
		(net "PHY_IOC_TO_SCC_43_DP")
	)
	(segment
		(start 157.153356 -31.675832)
		(end 157.15361 -31.675578)
		(width 0.12446)
		(layer "F.Cu")
		(net "PHY_IOC_TO_SCC_43_DN")
	)
	(segment
		(start 147.936458 -26.852118)
		(end 146.832828 -27.36723)
		(width 0.12446)
		(layer "F.Cu")
		(net "PHY_IOC_TO_SCC_43_DN")
	)
	(segment
		(start 152.524206 -26.293826)
		(end 151.543512 -26.084784)
		(width 0.12446)
		(layer "F.Cu")
		(net "PHY_IOC_TO_SCC_43_DN")
	)
	(segment
		(start 133.66623 -43.968416)
		(end 133.72973 -44.031916)
		(width 0.12446)
		(layer "F.Cu")
		(net "PHY_IOC_TO_SCC_43_DN")
	)
	(segment
		(start 163.474146 -33.606232)
		(end 162.223196 -33.606232)
		(width 0.12446)
		(layer "F.Cu")
		(net "PHY_IOC_TO_SCC_43_DN")
	)
	(segment
		(start 151.543512 -26.084784)
		(end 147.936458 -26.852118)
		(width 0.12446)
		(layer "F.Cu")
		(net "PHY_IOC_TO_SCC_43_DN")
	)
	(segment
		(start 162.223196 -33.606232)
		(end 159.11195 -32.947864)
		(width 0.12446)
		(layer "F.Cu")
		(net "PHY_IOC_TO_SCC_43_DN")
	)
	(segment
		(start 164.199824 -33.199832)
		(end 163.474146 -33.606232)
		(width 0.12446)
		(layer "F.Cu")
		(net "PHY_IOC_TO_SCC_43_DN")
	)
	(segment
		(start 159.11195 -32.947864)
		(end 157.153356 -31.675832)
		(width 0.12446)
		(layer "F.Cu")
		(net "PHY_IOC_TO_SCC_43_DN")
	)
	(segment
		(start 133.72973 -44.031916)
		(end 133.72973 -44.423584)
		(width 0.12446)
		(layer "F.Cu")
		(net "PHY_IOC_TO_SCC_43_DN")
	)
	(segment
		(start 154.483816 -27.565604)
		(end 152.524206 -26.293826)
		(width 0.12446)
		(layer "F.Cu")
		(net "PHY_IOC_TO_SCC_43_DN")
	)
	(segment
		(start 146.832828 -27.36723)
		(end 142.197582 -30.377638)
		(width 0.12446)
		(layer "F.Cu")
		(net "PHY_IOC_TO_SCC_43_DN")
	)
	(segment
		(start 133.66623 -43.51909)
		(end 133.66623 -43.968416)
		(width 0.12446)
		(layer "F.Cu")
		(net "PHY_IOC_TO_SCC_43_DN")
	)
	(segment
		(start 157.15361 -31.675578)
		(end 154.483816 -27.565604)
		(width 0.12446)
		(layer "F.Cu")
		(net "PHY_IOC_TO_SCC_43_DN")
	)
	(segment
		(start 142.197582 -30.377638)
		(end 133.66623 -43.51909)
		(width 0.12446)
		(layer "F.Cu")
		(net "PHY_IOC_TO_SCC_43_DN")
	)
	(segment
		(start 134.427214 -39.256462)
		(end 132.799074 -40.31361)
		(width 0.12446)
		(layer "F.Cu")
		(net "PHY_IOC_TO_SCC_42_DP")
	)
	(segment
		(start 134.86003 -38.095174)
		(end 134.649972 -38.419024)
		(width 0.12446)
		(layer "F.Cu")
		(net "PHY_IOC_TO_SCC_42_DP")
	)
	(segment
		(start 132.799074 -40.31361)
		(end 130.694938 -43.553634)
		(width 0.12446)
		(layer "F.Cu")
		(net "PHY_IOC_TO_SCC_42_DP")
	)
	(segment
		(start 153.132282 -24.742394)
		(end 151.57831 -24.411686)
		(width 0.12446)
		(layer "F.Cu")
		(net "PHY_IOC_TO_SCC_42_DP")
	)
	(segment
		(start 130.694938 -43.553634)
		(end 130.694938 -43.97629)
		(width 0.12446)
		(layer "F.Cu")
		(net "PHY_IOC_TO_SCC_42_DP")
	)
	(segment
		(start 130.57378 -44.097448)
		(end 130.57378 -44.438316)
		(width 0.12446)
		(layer "F.Cu")
		(net "PHY_IOC_TO_SCC_42_DP")
	)
	(segment
		(start 161.955734 -32.20339)
		(end 161.678112 -32.144462)
		(width 0.12446)
		(layer "F.Cu")
		(net "PHY_IOC_TO_SCC_42_DP")
	)
	(segment
		(start 151.57831 -24.411686)
		(end 146.725386 -25.442926)
		(width 0.12446)
		(layer "F.Cu")
		(net "PHY_IOC_TO_SCC_42_DP")
	)
	(segment
		(start 140.965682 -29.184346)
		(end 138.07567 -33.636458)
		(width 0.12446)
		(layer "F.Cu")
		(net "PHY_IOC_TO_SCC_42_DP")
	)
	(segment
		(start 130.694938 -43.97629)
		(end 130.57378 -44.097448)
		(width 0.12446)
		(layer "F.Cu")
		(net "PHY_IOC_TO_SCC_42_DP")
	)
	(segment
		(start 158.255208 -30.042612)
		(end 156.03855 -26.62936)
		(width 0.12446)
		(layer "F.Cu")
		(net "PHY_IOC_TO_SCC_42_DP")
	)
	(segment
		(start 163.399978 -32.399986)
		(end 162.880802 -32.399986)
		(width 0.12446)
		(layer "F.Cu")
		(net "PHY_IOC_TO_SCC_42_DP")
	)
	(segment
		(start 143.850106 -27.310842)
		(end 140.965682 -29.184346)
		(width 0.12446)
		(layer "F.Cu")
		(net "PHY_IOC_TO_SCC_42_DP")
	)
	(segment
		(start 145.255996 -26.397458)
		(end 143.850106 -27.310842)
		(width 0.12446)
		(layer "F.Cu")
		(net "PHY_IOC_TO_SCC_42_DP")
	)
	(segment
		(start 138.07567 -33.636458)
		(end 135.232394 -38.015926)
		(width 0.12446)
		(layer "F.Cu")
		(net "PHY_IOC_TO_SCC_42_DP")
	)
	(segment
		(start 162.880802 -32.399986)
		(end 162.510724 -32.321246)
		(width 0.12446)
		(layer "F.Cu")
		(net "PHY_IOC_TO_SCC_42_DP")
	)
	(segment
		(start 161.678112 -32.144462)
		(end 161.400998 -32.085788)
		(width 0.12446)
		(layer "F.Cu")
		(net "PHY_IOC_TO_SCC_42_DP")
	)
	(segment
		(start 134.649972 -38.419024)
		(end 134.72922 -38.791388)
		(width 0.12446)
		(layer "F.Cu")
		(net "PHY_IOC_TO_SCC_42_DP")
	)
	(segment
		(start 134.72922 -38.791388)
		(end 134.427214 -39.256462)
		(width 0.12446)
		(layer "F.Cu")
		(net "PHY_IOC_TO_SCC_42_DP")
	)
	(segment
		(start 161.400998 -32.085788)
		(end 158.255208 -30.042612)
		(width 0.12446)
		(layer "F.Cu")
		(net "PHY_IOC_TO_SCC_42_DP")
	)
	(segment
		(start 162.510724 -32.321246)
		(end 161.955734 -32.20339)
		(width 0.12446)
		(layer "F.Cu")
		(net "PHY_IOC_TO_SCC_42_DP")
	)
	(segment
		(start 146.725386 -25.442926)
		(end 145.255996 -26.397458)
		(width 0.12446)
		(layer "F.Cu")
		(net "PHY_IOC_TO_SCC_42_DP")
	)
	(segment
		(start 135.232394 -38.015926)
		(end 134.86003 -38.095174)
		(width 0.12446)
		(layer "F.Cu")
		(net "PHY_IOC_TO_SCC_42_DP")
	)
	(segment
		(start 156.03855 -26.62936)
		(end 153.132282 -24.742394)
		(width 0.12446)
		(layer "F.Cu")
		(net "PHY_IOC_TO_SCC_42_DP")
	)
	(segment
		(start 131.101338 -43.990006)
		(end 131.15798 -44.046648)
		(width 0.12446)
		(layer "F.Cu")
		(net "PHY_IOC_TO_SCC_42_DN")
	)
	(segment
		(start 163.46424 -32.806386)
		(end 162.837876 -32.806386)
		(width 0.12446)
		(layer "F.Cu")
		(net "PHY_IOC_TO_SCC_42_DN")
	)
	(segment
		(start 155.744672 -26.923238)
		(end 152.97404 -25.12441)
		(width 0.12446)
		(layer "F.Cu")
		(net "PHY_IOC_TO_SCC_42_DN")
	)
	(segment
		(start 131.101338 -43.67403)
		(end 131.101338 -43.990006)
		(width 0.12446)
		(layer "F.Cu")
		(net "PHY_IOC_TO_SCC_42_DN")
	)
	(segment
		(start 151.57831 -24.82723)
		(end 146.883628 -25.824942)
		(width 0.12446)
		(layer "F.Cu")
		(net "PHY_IOC_TO_SCC_42_DN")
	)
	(segment
		(start 146.883628 -25.824942)
		(end 141.259814 -29.478224)
		(width 0.12446)
		(layer "F.Cu")
		(net "PHY_IOC_TO_SCC_42_DN")
	)
	(segment
		(start 133.092952 -40.607488)
		(end 131.101338 -43.67403)
		(width 0.12446)
		(layer "F.Cu")
		(net "PHY_IOC_TO_SCC_42_DN")
	)
	(segment
		(start 152.97404 -25.12441)
		(end 151.57831 -24.82723)
		(width 0.12446)
		(layer "F.Cu")
		(net "PHY_IOC_TO_SCC_42_DN")
	)
	(segment
		(start 134.721092 -39.55034)
		(end 133.092952 -40.607488)
		(width 0.12446)
		(layer "F.Cu")
		(net "PHY_IOC_TO_SCC_42_DN")
	)
	(segment
		(start 162.837876 -32.806386)
		(end 161.24301 -32.467804)
		(width 0.12446)
		(layer "F.Cu")
		(net "PHY_IOC_TO_SCC_42_DN")
	)
	(segment
		(start 141.259814 -29.478224)
		(end 134.721092 -39.55034)
		(width 0.12446)
		(layer "F.Cu")
		(net "PHY_IOC_TO_SCC_42_DN")
	)
	(segment
		(start 157.96133 -30.33649)
		(end 155.744672 -26.923238)
		(width 0.12446)
		(layer "F.Cu")
		(net "PHY_IOC_TO_SCC_42_DN")
	)
	(segment
		(start 131.15798 -44.046648)
		(end 131.15798 -44.438316)
		(width 0.12446)
		(layer "F.Cu")
		(net "PHY_IOC_TO_SCC_42_DN")
	)
	(segment
		(start 161.24301 -32.467804)
		(end 157.96133 -30.33649)
		(width 0.12446)
		(layer "F.Cu")
		(net "PHY_IOC_TO_SCC_42_DN")
	)
	(segment
		(start 164.199824 -32.399986)
		(end 163.46424 -32.806386)
		(width 0.12446)
		(layer "F.Cu")
		(net "PHY_IOC_TO_SCC_42_DN")
	)
	(segment
		(start 130.29311 -40.15994)
		(end 130.213862 -40.532304)
		(width 0.12446)
		(layer "F.Cu")
		(net "PHY_IOC_TO_SCC_41_DP")
	)
	(segment
		(start 151.608282 -23.146766)
		(end 146.238976 -24.28875)
		(width 0.12446)
		(layer "F.Cu")
		(net "PHY_IOC_TO_SCC_41_DP")
	)
	(segment
		(start 136.151874 -33.799272)
		(end 132.922264 -38.773862)
		(width 0.12446)
		(layer "F.Cu")
		(net "PHY_IOC_TO_SCC_41_DP")
	)
	(segment
		(start 128.00203 -44.11218)
		(end 128.00203 -44.453048)
		(width 0.12446)
		(layer "F.Cu")
		(net "PHY_IOC_TO_SCC_41_DP")
	)
	(segment
		(start 157.770322 -26.299922)
		(end 153.553922 -23.560024)
		(width 0.12446)
		(layer "F.Cu")
		(net "PHY_IOC_TO_SCC_41_DP")
	)
	(segment
		(start 132.922264 -38.773862)
		(end 130.978656 -40.035734)
		(width 0.12446)
		(layer "F.Cu")
		(net "PHY_IOC_TO_SCC_41_DP")
	)
	(segment
		(start 130.013964 -40.662098)
		(end 128.097026 -43.614594)
		(width 0.12446)
		(layer "F.Cu")
		(net "PHY_IOC_TO_SCC_41_DP")
	)
	(segment
		(start 163.398962 -30.801056)
		(end 161.912046 -30.801056)
		(width 0.12446)
		(layer "F.Cu")
		(net "PHY_IOC_TO_SCC_41_DP")
	)
	(segment
		(start 146.238976 -24.28875)
		(end 142.861792 -26.481532)
		(width 0.12446)
		(layer "F.Cu")
		(net "PHY_IOC_TO_SCC_41_DP")
	)
	(segment
		(start 130.978656 -40.035734)
		(end 130.606292 -39.95674)
		(width 0.12446)
		(layer "F.Cu")
		(net "PHY_IOC_TO_SCC_41_DP")
	)
	(segment
		(start 139.475464 -28.679902)
		(end 136.151874 -33.799272)
		(width 0.12446)
		(layer "F.Cu")
		(net "PHY_IOC_TO_SCC_41_DP")
	)
	(segment
		(start 159.804354 -29.433012)
		(end 157.770322 -26.299922)
		(width 0.12446)
		(layer "F.Cu")
		(net "PHY_IOC_TO_SCC_41_DP")
	)
	(segment
		(start 128.097026 -43.614594)
		(end 128.097026 -44.017184)
		(width 0.12446)
		(layer "F.Cu")
		(net "PHY_IOC_TO_SCC_41_DP")
	)
	(segment
		(start 142.861792 -26.481532)
		(end 139.475464 -28.679902)
		(width 0.12446)
		(layer "F.Cu")
		(net "PHY_IOC_TO_SCC_41_DP")
	)
	(segment
		(start 130.606292 -39.95674)
		(end 130.29311 -40.15994)
		(width 0.12446)
		(layer "F.Cu")
		(net "PHY_IOC_TO_SCC_41_DP")
	)
	(segment
		(start 128.097026 -44.017184)
		(end 128.00203 -44.11218)
		(width 0.12446)
		(layer "F.Cu")
		(net "PHY_IOC_TO_SCC_41_DP")
	)
	(segment
		(start 130.213862 -40.532304)
		(end 130.013964 -40.662098)
		(width 0.12446)
		(layer "F.Cu")
		(net "PHY_IOC_TO_SCC_41_DP")
	)
	(segment
		(start 163.399978 -30.80004)
		(end 163.398962 -30.801056)
		(width 0.12446)
		(layer "F.Cu")
		(net "PHY_IOC_TO_SCC_41_DP")
	)
	(segment
		(start 160.8582 -30.11678)
		(end 159.804354 -29.433012)
		(width 0.12446)
		(layer "F.Cu")
		(net "PHY_IOC_TO_SCC_41_DP")
	)
	(segment
		(start 161.912046 -30.800802)
		(end 160.8582 -30.11678)
		(width 0.12446)
		(layer "F.Cu")
		(net "PHY_IOC_TO_SCC_41_DP")
	)
	(segment
		(start 153.553922 -23.560024)
		(end 151.608282 -23.146766)
		(width 0.12446)
		(layer "F.Cu")
		(net "PHY_IOC_TO_SCC_41_DP")
	)
	(segment
		(start 161.912046 -30.801056)
		(end 161.912046 -30.800802)
		(width 0.12446)
		(layer "F.Cu")
		(net "PHY_IOC_TO_SCC_41_DP")
	)
	(segment
		(start 128.503426 -43.978576)
		(end 128.58623 -44.06138)
		(width 0.12446)
		(layer "F.Cu")
		(net "PHY_IOC_TO_SCC_41_DN")
	)
	(segment
		(start 161.79165 -31.207456)
		(end 159.510476 -29.72689)
		(width 0.12446)
		(layer "F.Cu")
		(net "PHY_IOC_TO_SCC_41_DN")
	)
	(segment
		(start 164.199824 -30.80004)
		(end 163.484052 -31.207456)
		(width 0.12446)
		(layer "F.Cu")
		(net "PHY_IOC_TO_SCC_41_DN")
	)
	(segment
		(start 153.39568 -23.94204)
		(end 151.608282 -23.56231)
		(width 0.12446)
		(layer "F.Cu")
		(net "PHY_IOC_TO_SCC_41_DN")
	)
	(segment
		(start 159.510476 -29.72689)
		(end 157.47619 -26.5938)
		(width 0.12446)
		(layer "F.Cu")
		(net "PHY_IOC_TO_SCC_41_DN")
	)
	(segment
		(start 139.769342 -28.97378)
		(end 133.216142 -39.06774)
		(width 0.12446)
		(layer "F.Cu")
		(net "PHY_IOC_TO_SCC_41_DN")
	)
	(segment
		(start 128.58623 -44.06138)
		(end 128.58623 -44.453048)
		(width 0.12446)
		(layer "F.Cu")
		(net "PHY_IOC_TO_SCC_41_DN")
	)
	(segment
		(start 130.576574 -40.781478)
		(end 130.576574 -40.781732)
		(width 0.12446)
		(layer "F.Cu")
		(net "PHY_IOC_TO_SCC_41_DN")
	)
	(segment
		(start 157.47619 -26.5938)
		(end 153.39568 -23.94204)
		(width 0.12446)
		(layer "F.Cu")
		(net "PHY_IOC_TO_SCC_41_DN")
	)
	(segment
		(start 146.397218 -24.670766)
		(end 139.769342 -28.97378)
		(width 0.12446)
		(layer "F.Cu")
		(net "PHY_IOC_TO_SCC_41_DN")
	)
	(segment
		(start 128.503426 -43.73499)
		(end 128.503426 -43.978576)
		(width 0.12446)
		(layer "F.Cu")
		(net "PHY_IOC_TO_SCC_41_DN")
	)
	(segment
		(start 163.484052 -31.207456)
		(end 161.79165 -31.207456)
		(width 0.12446)
		(layer "F.Cu")
		(net "PHY_IOC_TO_SCC_41_DN")
	)
	(segment
		(start 130.576574 -40.781732)
		(end 130.307842 -40.955976)
		(width 0.12446)
		(layer "F.Cu")
		(net "PHY_IOC_TO_SCC_41_DN")
	)
	(segment
		(start 130.307842 -40.955976)
		(end 128.503426 -43.73499)
		(width 0.12446)
		(layer "F.Cu")
		(net "PHY_IOC_TO_SCC_41_DN")
	)
	(segment
		(start 133.216142 -39.06774)
		(end 130.576574 -40.781478)
		(width 0.12446)
		(layer "F.Cu")
		(net "PHY_IOC_TO_SCC_41_DN")
	)
	(segment
		(start 151.608282 -23.56231)
		(end 146.397218 -24.670766)
		(width 0.12446)
		(layer "F.Cu")
		(net "PHY_IOC_TO_SCC_41_DN")
	)
	(segment
		(start 157.66161 -24.760682)
		(end 158.033974 -24.681688)
		(width 0.12446)
		(layer "F.Cu")
		(net "PHY_IOC_TO_SCC_40_DP")
	)
	(segment
		(start 160.888426 -28.368498)
		(end 163.399978 -29.999686)
		(width 0.12446)
		(layer "F.Cu")
		(net "PHY_IOC_TO_SCC_40_DP")
	)
	(segment
		(start 127.954024 -40.127428)
		(end 130.300476 -38.603682)
		(width 0.12446)
		(layer "F.Cu")
		(net "PHY_IOC_TO_SCC_40_DP")
	)
	(segment
		(start 151.59228 -21.896324)
		(end 154.057096 -22.419564)
		(width 0.12446)
		(layer "F.Cu")
		(net "PHY_IOC_TO_SCC_40_DP")
	)
	(segment
		(start 158.426404 -25.257506)
		(end 159.190436 -25.753822)
		(width 0.12446)
		(layer "F.Cu")
		(net "PHY_IOC_TO_SCC_40_DP")
	)
	(segment
		(start 143.929354 -24.318468)
		(end 145.744438 -23.139146)
		(width 0.12446)
		(layer "F.Cu")
		(net "PHY_IOC_TO_SCC_40_DP")
	)
	(segment
		(start 132.502402 -37.173916)
		(end 135.55218 -32.476948)
		(width 0.12446)
		(layer "F.Cu")
		(net "PHY_IOC_TO_SCC_40_DP")
	)
	(segment
		(start 135.55218 -32.476948)
		(end 138.602212 -27.779726)
		(width 0.12446)
		(layer "F.Cu")
		(net "PHY_IOC_TO_SCC_40_DP")
	)
	(segment
		(start 138.602212 -27.779726)
		(end 142.17777 -25.456642)
		(width 0.12446)
		(layer "F.Cu")
		(net "PHY_IOC_TO_SCC_40_DP")
	)
	(segment
		(start 125.526546 -44.101512)
		(end 125.65634 -43.971718)
		(width 0.12446)
		(layer "F.Cu")
		(net "PHY_IOC_TO_SCC_40_DP")
	)
	(segment
		(start 125.65634 -43.668696)
		(end 127.954024 -40.127428)
		(width 0.12446)
		(layer "F.Cu")
		(net "PHY_IOC_TO_SCC_40_DP")
	)
	(segment
		(start 159.190436 -25.753822)
		(end 160.888426 -28.368498)
		(width 0.12446)
		(layer "F.Cu")
		(net "PHY_IOC_TO_SCC_40_DP")
	)
	(segment
		(start 163.399978 -29.999686)
		(end 163.399978 -29.99994)
		(width 0.12446)
		(layer "F.Cu")
		(net "PHY_IOC_TO_SCC_40_DP")
	)
	(segment
		(start 158.347156 -24.885142)
		(end 158.426404 -25.257506)
		(width 0.12446)
		(layer "F.Cu")
		(net "PHY_IOC_TO_SCC_40_DP")
	)
	(segment
		(start 125.65634 -43.971718)
		(end 125.65634 -43.668696)
		(width 0.12446)
		(layer "F.Cu")
		(net "PHY_IOC_TO_SCC_40_DP")
	)
	(segment
		(start 154.057096 -22.419564)
		(end 157.66161 -24.760682)
		(width 0.12446)
		(layer "F.Cu")
		(net "PHY_IOC_TO_SCC_40_DP")
	)
	(segment
		(start 145.744438 -23.139146)
		(end 151.59228 -21.896324)
		(width 0.12446)
		(layer "F.Cu")
		(net "PHY_IOC_TO_SCC_40_DP")
	)
	(segment
		(start 142.17777 -25.456642)
		(end 143.929354 -24.318468)
		(width 0.12446)
		(layer "F.Cu")
		(net "PHY_IOC_TO_SCC_40_DP")
	)
	(segment
		(start 130.300476 -38.603682)
		(end 132.502402 -37.173916)
		(width 0.12446)
		(layer "F.Cu")
		(net "PHY_IOC_TO_SCC_40_DP")
	)
	(segment
		(start 125.526546 -44.46778)
		(end 125.526546 -44.101512)
		(width 0.12446)
		(layer "F.Cu")
		(net "PHY_IOC_TO_SCC_40_DP")
	)
	(segment
		(start 158.033974 -24.681688)
		(end 158.347156 -24.885142)
		(width 0.12446)
		(layer "F.Cu")
		(net "PHY_IOC_TO_SCC_40_DP")
	)
	(segment
		(start 138.89609 -28.073604)
		(end 132.79628 -37.467794)
		(width 0.12446)
		(layer "F.Cu")
		(net "PHY_IOC_TO_SCC_40_DN")
	)
	(segment
		(start 160.594548 -28.662376)
		(end 158.896558 -26.0477)
		(width 0.12446)
		(layer "F.Cu")
		(net "PHY_IOC_TO_SCC_40_DN")
	)
	(segment
		(start 126.06274 -43.789092)
		(end 126.06274 -44.038774)
		(width 0.12446)
		(layer "F.Cu")
		(net "PHY_IOC_TO_SCC_40_DN")
	)
	(segment
		(start 126.110746 -44.08678)
		(end 126.110746 -44.46778)
		(width 0.12446)
		(layer "F.Cu")
		(net "PHY_IOC_TO_SCC_40_DN")
	)
	(segment
		(start 153.898854 -22.80158)
		(end 151.59228 -22.311868)
		(width 0.12446)
		(layer "F.Cu")
		(net "PHY_IOC_TO_SCC_40_DN")
	)
	(segment
		(start 158.896558 -26.0477)
		(end 153.898854 -22.80158)
		(width 0.12446)
		(layer "F.Cu")
		(net "PHY_IOC_TO_SCC_40_DN")
	)
	(segment
		(start 164.199824 -29.99994)
		(end 163.49345 -30.409134)
		(width 0.12446)
		(layer "F.Cu")
		(net "PHY_IOC_TO_SCC_40_DN")
	)
	(segment
		(start 128.248156 -40.421306)
		(end 126.06274 -43.789092)
		(width 0.12446)
		(layer "F.Cu")
		(net "PHY_IOC_TO_SCC_40_DN")
	)
	(segment
		(start 145.90268 -23.521162)
		(end 138.89609 -28.073604)
		(width 0.12446)
		(layer "F.Cu")
		(net "PHY_IOC_TO_SCC_40_DN")
	)
	(segment
		(start 126.06274 -44.038774)
		(end 126.110746 -44.08678)
		(width 0.12446)
		(layer "F.Cu")
		(net "PHY_IOC_TO_SCC_40_DN")
	)
	(segment
		(start 163.49345 -30.409134)
		(end 163.283646 -30.409134)
		(width 0.12446)
		(layer "F.Cu")
		(net "PHY_IOC_TO_SCC_40_DN")
	)
	(segment
		(start 128.247902 -40.421306)
		(end 128.248156 -40.421306)
		(width 0.12446)
		(layer "F.Cu")
		(net "PHY_IOC_TO_SCC_40_DN")
	)
	(segment
		(start 151.59228 -22.311868)
		(end 145.90268 -23.521162)
		(width 0.12446)
		(layer "F.Cu")
		(net "PHY_IOC_TO_SCC_40_DN")
	)
	(segment
		(start 132.79628 -37.467794)
		(end 128.247902 -40.421306)
		(width 0.12446)
		(layer "F.Cu")
		(net "PHY_IOC_TO_SCC_40_DN")
	)
	(segment
		(start 163.283646 -30.409134)
		(end 160.594548 -28.662376)
		(width 0.12446)
		(layer "F.Cu")
		(net "PHY_IOC_TO_SCC_40_DN")
	)
	(segment
		(start 126.500128 -72.500236)
		(end 127 -73.000108)
		(width 0.104902)
		(layer "F.Cu")
		(net "PHY_DPB_TO_SCC_C_7_DP")
	)
	(via
		(at 127 -73.000108)
		(size 0.4572)
		(drill 0.2032)
		(layers "F.Cu" "B.Cu")
		(net "PHY_DPB_TO_SCC_C_7_DP")
	)
	(segment
		(start 133.859524 -73.75652)
		(end 133.580124 -73.47712)
		(width 0.12446)
		(layer "B.Cu")
		(net "PHY_DPB_TO_SCC_C_7_DP")
	)
	(segment
		(start 136.755632 -74.5998)
		(end 136.656826 -74.500994)
		(width 0.12446)
		(layer "B.Cu")
		(net "PHY_DPB_TO_SCC_C_7_DP")
	)
	(segment
		(start 126.595124 -72.749918)
		(end 126.595124 -72.900032)
		(width 0.0889)
		(layer "B.Cu")
		(net "PHY_DPB_TO_SCC_C_7_DP")
	)
	(segment
		(start 133.580124 -73.47712)
		(end 133.100318 -73.47712)
		(width 0.12446)
		(layer "B.Cu")
		(net "PHY_DPB_TO_SCC_C_7_DP")
	)
	(segment
		(start 131.169918 -72.595232)
		(end 126.74981 -72.595232)
		(width 0.0889)
		(layer "B.Cu")
		(net "PHY_DPB_TO_SCC_C_7_DP")
	)
	(segment
		(start 134.512304 -73.47712)
		(end 134.232904 -73.75652)
		(width 0.12446)
		(layer "B.Cu")
		(net "PHY_DPB_TO_SCC_C_7_DP")
	)
	(segment
		(start 132.338064 -72.714866)
		(end 131.31165 -72.714866)
		(width 0.12446)
		(layer "B.Cu")
		(net "PHY_DPB_TO_SCC_C_7_DP")
	)
	(segment
		(start 136.656826 -74.500994)
		(end 135.881872 -74.500994)
		(width 0.12446)
		(layer "B.Cu")
		(net "PHY_DPB_TO_SCC_C_7_DP")
	)
	(segment
		(start 134.232904 -73.75652)
		(end 133.859524 -73.75652)
		(width 0.12446)
		(layer "B.Cu")
		(net "PHY_DPB_TO_SCC_C_7_DP")
	)
	(segment
		(start 131.31165 -72.714866)
		(end 131.289552 -72.714866)
		(width 0.0889)
		(layer "B.Cu")
		(net "PHY_DPB_TO_SCC_C_7_DP")
	)
	(segment
		(start 135.881872 -74.500994)
		(end 134.857998 -73.47712)
		(width 0.12446)
		(layer "B.Cu")
		(net "PHY_DPB_TO_SCC_C_7_DP")
	)
	(segment
		(start 137.1346 -74.5998)
		(end 136.755632 -74.5998)
		(width 0.12446)
		(layer "B.Cu")
		(net "PHY_DPB_TO_SCC_C_7_DP")
	)
	(segment
		(start 134.857998 -73.47712)
		(end 134.512304 -73.47712)
		(width 0.12446)
		(layer "B.Cu")
		(net "PHY_DPB_TO_SCC_C_7_DP")
	)
	(segment
		(start 133.100318 -73.47712)
		(end 132.338064 -72.714866)
		(width 0.12446)
		(layer "B.Cu")
		(net "PHY_DPB_TO_SCC_C_7_DP")
	)
	(segment
		(start 126.6952 -73.000108)
		(end 127 -73.000108)
		(width 0.0889)
		(layer "B.Cu")
		(net "PHY_DPB_TO_SCC_C_7_DP")
	)
	(segment
		(start 131.289552 -72.714866)
		(end 131.169918 -72.595232)
		(width 0.0889)
		(layer "B.Cu")
		(net "PHY_DPB_TO_SCC_C_7_DP")
	)
	(arc
		(start 126.74981 -72.595232)
		(mid 126.64043 -72.640538)
		(end 126.595124 -72.749918)
		(width 0.0889)
		(layer "B.Cu")
		(net "PHY_DPB_TO_SCC_C_7_DP")
	)
	(arc
		(start 126.595124 -72.900032)
		(mid 126.624436 -72.970796)
		(end 126.6952 -73.000108)
		(width 0.0889)
		(layer "B.Cu")
		(net "PHY_DPB_TO_SCC_C_7_DP")
	)
	(segment
		(start 125.50013 -72.500236)
		(end 126.000002 -73.000108)
		(width 0.104902)
		(layer "F.Cu")
		(net "PHY_DPB_TO_SCC_C_7_DN")
	)
	(via
		(at 126.000002 -73.000108)
		(size 0.4572)
		(drill 0.2032)
		(layers "F.Cu" "B.Cu")
		(net "PHY_DPB_TO_SCC_C_7_DN")
	)
	(segment
		(start 132.506466 -72.308466)
		(end 131.31165 -72.308466)
		(width 0.12446)
		(layer "B.Cu")
		(net "PHY_DPB_TO_SCC_C_7_DN")
	)
	(segment
		(start 137.1346 -74.041)
		(end 136.755632 -74.041)
		(width 0.12446)
		(layer "B.Cu")
		(net "PHY_DPB_TO_SCC_C_7_DN")
	)
	(segment
		(start 131.289552 -72.308466)
		(end 131.193286 -72.404732)
		(width 0.0889)
		(layer "B.Cu")
		(net "PHY_DPB_TO_SCC_C_7_DN")
	)
	(segment
		(start 131.31165 -72.308466)
		(end 131.289552 -72.308466)
		(width 0.0889)
		(layer "B.Cu")
		(net "PHY_DPB_TO_SCC_C_7_DN")
	)
	(segment
		(start 131.193286 -72.404732)
		(end 126.74981 -72.404732)
		(width 0.0889)
		(layer "B.Cu")
		(net "PHY_DPB_TO_SCC_C_7_DN")
	)
	(segment
		(start 126.404624 -72.749918)
		(end 126.404624 -72.900286)
		(width 0.0889)
		(layer "B.Cu")
		(net "PHY_DPB_TO_SCC_C_7_DN")
	)
	(segment
		(start 136.755632 -74.041)
		(end 136.702038 -74.094594)
		(width 0.12446)
		(layer "B.Cu")
		(net "PHY_DPB_TO_SCC_C_7_DN")
	)
	(segment
		(start 133.26872 -73.07072)
		(end 132.506466 -72.308466)
		(width 0.12446)
		(layer "B.Cu")
		(net "PHY_DPB_TO_SCC_C_7_DN")
	)
	(segment
		(start 136.050274 -74.094594)
		(end 135.0264 -73.07072)
		(width 0.12446)
		(layer "B.Cu")
		(net "PHY_DPB_TO_SCC_C_7_DN")
	)
	(segment
		(start 136.702038 -74.094594)
		(end 136.050274 -74.094594)
		(width 0.12446)
		(layer "B.Cu")
		(net "PHY_DPB_TO_SCC_C_7_DN")
	)
	(segment
		(start 126.304802 -73.000108)
		(end 126.000002 -73.000108)
		(width 0.0889)
		(layer "B.Cu")
		(net "PHY_DPB_TO_SCC_C_7_DN")
	)
	(segment
		(start 135.0264 -73.07072)
		(end 133.26872 -73.07072)
		(width 0.12446)
		(layer "B.Cu")
		(net "PHY_DPB_TO_SCC_C_7_DN")
	)
	(arc
		(start 126.404624 -72.900286)
		(mid 126.375387 -72.970871)
		(end 126.304802 -73.000108)
		(width 0.0889)
		(layer "B.Cu")
		(net "PHY_DPB_TO_SCC_C_7_DN")
	)
	(arc
		(start 126.74981 -72.404732)
		(mid 126.505727 -72.505835)
		(end 126.404624 -72.749918)
		(width 0.0889)
		(layer "B.Cu")
		(net "PHY_DPB_TO_SCC_C_7_DN")
	)
	(segment
		(start 126.500128 -71.500238)
		(end 127 -72.00011)
		(width 0.104902)
		(layer "F.Cu")
		(net "PHY_DPB_TO_SCC_C_6_DP")
	)
	(via
		(at 127 -72.00011)
		(size 0.4572)
		(drill 0.2032)
		(layers "F.Cu" "B.Cu")
		(net "PHY_DPB_TO_SCC_C_6_DP")
	)
	(segment
		(start 134.366 -71.937626)
		(end 134.0866 -72.217026)
		(width 0.12446)
		(layer "B.Cu")
		(net "PHY_DPB_TO_SCC_C_6_DP")
	)
	(segment
		(start 136.806432 -72.9996)
		(end 136.70661 -72.899778)
		(width 0.12446)
		(layer "B.Cu")
		(net "PHY_DPB_TO_SCC_C_6_DP")
	)
	(segment
		(start 131.30911 -71.736712)
		(end 131.287012 -71.736712)
		(width 0.0889)
		(layer "B.Cu")
		(net "PHY_DPB_TO_SCC_C_6_DP")
	)
	(segment
		(start 135.041894 -71.937626)
		(end 134.366 -71.937626)
		(width 0.12446)
		(layer "B.Cu")
		(net "PHY_DPB_TO_SCC_C_6_DP")
	)
	(segment
		(start 133.43382 -71.937626)
		(end 132.809234 -71.937626)
		(width 0.12446)
		(layer "B.Cu")
		(net "PHY_DPB_TO_SCC_C_6_DP")
	)
	(segment
		(start 137.1854 -72.9996)
		(end 136.806432 -72.9996)
		(width 0.12446)
		(layer "B.Cu")
		(net "PHY_DPB_TO_SCC_C_6_DP")
	)
	(segment
		(start 136.70661 -72.899778)
		(end 136.004046 -72.899778)
		(width 0.12446)
		(layer "B.Cu")
		(net "PHY_DPB_TO_SCC_C_6_DP")
	)
	(segment
		(start 133.71322 -72.217026)
		(end 133.43382 -71.937626)
		(width 0.12446)
		(layer "B.Cu")
		(net "PHY_DPB_TO_SCC_C_6_DP")
	)
	(segment
		(start 134.0866 -72.217026)
		(end 133.71322 -72.217026)
		(width 0.12446)
		(layer "B.Cu")
		(net "PHY_DPB_TO_SCC_C_6_DP")
	)
	(segment
		(start 132.60832 -71.736712)
		(end 131.30911 -71.736712)
		(width 0.12446)
		(layer "B.Cu")
		(net "PHY_DPB_TO_SCC_C_6_DP")
	)
	(segment
		(start 126.6952 -72.00011)
		(end 127 -72.00011)
		(width 0.0889)
		(layer "B.Cu")
		(net "PHY_DPB_TO_SCC_C_6_DP")
	)
	(segment
		(start 131.287012 -71.736712)
		(end 131.147566 -71.597266)
		(width 0.0889)
		(layer "B.Cu")
		(net "PHY_DPB_TO_SCC_C_6_DP")
	)
	(segment
		(start 126.595124 -71.74992)
		(end 126.595124 -71.900034)
		(width 0.0889)
		(layer "B.Cu")
		(net "PHY_DPB_TO_SCC_C_6_DP")
	)
	(segment
		(start 131.147566 -71.597266)
		(end 126.747778 -71.597266)
		(width 0.0889)
		(layer "B.Cu")
		(net "PHY_DPB_TO_SCC_C_6_DP")
	)
	(segment
		(start 136.004046 -72.899778)
		(end 135.041894 -71.937626)
		(width 0.12446)
		(layer "B.Cu")
		(net "PHY_DPB_TO_SCC_C_6_DP")
	)
	(segment
		(start 132.809234 -71.937626)
		(end 132.60832 -71.736712)
		(width 0.12446)
		(layer "B.Cu")
		(net "PHY_DPB_TO_SCC_C_6_DP")
	)
	(arc
		(start 126.747778 -71.597266)
		(mid 126.639835 -71.641977)
		(end 126.595124 -71.74992)
		(width 0.0889)
		(layer "B.Cu")
		(net "PHY_DPB_TO_SCC_C_6_DP")
	)
	(arc
		(start 126.595124 -71.900034)
		(mid 126.624436 -71.970798)
		(end 126.6952 -72.00011)
		(width 0.0889)
		(layer "B.Cu")
		(net "PHY_DPB_TO_SCC_C_6_DP")
	)
	(segment
		(start 125.50013 -71.500238)
		(end 126.000002 -72.00011)
		(width 0.104902)
		(layer "F.Cu")
		(net "PHY_DPB_TO_SCC_C_6_DN")
	)
	(via
		(at 126.000002 -72.00011)
		(size 0.4572)
		(drill 0.2032)
		(layers "F.Cu" "B.Cu")
		(net "PHY_DPB_TO_SCC_C_6_DN")
	)
	(segment
		(start 131.287012 -71.330312)
		(end 131.210558 -71.406766)
		(width 0.0889)
		(layer "B.Cu")
		(net "PHY_DPB_TO_SCC_C_6_DN")
	)
	(segment
		(start 135.210296 -71.531226)
		(end 132.977636 -71.531226)
		(width 0.12446)
		(layer "B.Cu")
		(net "PHY_DPB_TO_SCC_C_6_DN")
	)
	(segment
		(start 126.404624 -71.74992)
		(end 126.404624 -71.900288)
		(width 0.0889)
		(layer "B.Cu")
		(net "PHY_DPB_TO_SCC_C_6_DN")
	)
	(segment
		(start 136.172448 -72.493378)
		(end 135.210296 -71.531226)
		(width 0.12446)
		(layer "B.Cu")
		(net "PHY_DPB_TO_SCC_C_6_DN")
	)
	(segment
		(start 126.304802 -72.00011)
		(end 126.000002 -72.00011)
		(width 0.0889)
		(layer "B.Cu")
		(net "PHY_DPB_TO_SCC_C_6_DN")
	)
	(segment
		(start 131.30911 -71.330312)
		(end 131.287012 -71.330312)
		(width 0.0889)
		(layer "B.Cu")
		(net "PHY_DPB_TO_SCC_C_6_DN")
	)
	(segment
		(start 136.753854 -72.493378)
		(end 136.172448 -72.493378)
		(width 0.12446)
		(layer "B.Cu")
		(net "PHY_DPB_TO_SCC_C_6_DN")
	)
	(segment
		(start 136.806432 -72.4408)
		(end 136.753854 -72.493378)
		(width 0.12446)
		(layer "B.Cu")
		(net "PHY_DPB_TO_SCC_C_6_DN")
	)
	(segment
		(start 137.1854 -72.4408)
		(end 136.806432 -72.4408)
		(width 0.12446)
		(layer "B.Cu")
		(net "PHY_DPB_TO_SCC_C_6_DN")
	)
	(segment
		(start 131.210558 -71.406766)
		(end 126.747778 -71.406766)
		(width 0.0889)
		(layer "B.Cu")
		(net "PHY_DPB_TO_SCC_C_6_DN")
	)
	(segment
		(start 132.977636 -71.531226)
		(end 132.776722 -71.330312)
		(width 0.12446)
		(layer "B.Cu")
		(net "PHY_DPB_TO_SCC_C_6_DN")
	)
	(segment
		(start 132.776722 -71.330312)
		(end 131.30911 -71.330312)
		(width 0.12446)
		(layer "B.Cu")
		(net "PHY_DPB_TO_SCC_C_6_DN")
	)
	(arc
		(start 126.404624 -71.900288)
		(mid 126.375387 -71.970873)
		(end 126.304802 -72.00011)
		(width 0.0889)
		(layer "B.Cu")
		(net "PHY_DPB_TO_SCC_C_6_DN")
	)
	(arc
		(start 126.747778 -71.406766)
		(mid 126.505131 -71.507273)
		(end 126.404624 -71.74992)
		(width 0.0889)
		(layer "B.Cu")
		(net "PHY_DPB_TO_SCC_C_6_DN")
	)
	(segment
		(start 126.500128 -70.50024)
		(end 127 -71.000112)
		(width 0.104902)
		(layer "F.Cu")
		(net "PHY_DPB_TO_SCC_C_5_DP")
	)
	(via
		(at 127 -71.000112)
		(size 0.4572)
		(drill 0.2032)
		(layers "F.Cu" "B.Cu")
		(net "PHY_DPB_TO_SCC_C_5_DP")
	)
	(segment
		(start 131.759198 -70.704456)
		(end 131.7371 -70.704456)
		(width 0.0889)
		(layer "B.Cu")
		(net "PHY_DPB_TO_SCC_C_5_DP")
	)
	(segment
		(start 132.132578 -70.704456)
		(end 131.759198 -70.704456)
		(width 0.12446)
		(layer "B.Cu")
		(net "PHY_DPB_TO_SCC_C_5_DP")
	)
	(segment
		(start 131.62915 -70.596506)
		(end 126.74854 -70.596506)
		(width 0.0889)
		(layer "B.Cu")
		(net "PHY_DPB_TO_SCC_C_5_DP")
	)
	(segment
		(start 131.7371 -70.704456)
		(end 131.62915 -70.596506)
		(width 0.0889)
		(layer "B.Cu")
		(net "PHY_DPB_TO_SCC_C_5_DP")
	)
	(segment
		(start 132.785358 -70.983856)
		(end 132.411978 -70.983856)
		(width 0.12446)
		(layer "B.Cu")
		(net "PHY_DPB_TO_SCC_C_5_DP")
	)
	(segment
		(start 136.850882 -71.4502)
		(end 136.753346 -71.352664)
		(width 0.12446)
		(layer "B.Cu")
		(net "PHY_DPB_TO_SCC_C_5_DP")
	)
	(segment
		(start 135.543544 -70.704456)
		(end 133.064758 -70.704456)
		(width 0.12446)
		(layer "B.Cu")
		(net "PHY_DPB_TO_SCC_C_5_DP")
	)
	(segment
		(start 136.191752 -71.352664)
		(end 135.543544 -70.704456)
		(width 0.12446)
		(layer "B.Cu")
		(net "PHY_DPB_TO_SCC_C_5_DP")
	)
	(segment
		(start 132.411978 -70.983856)
		(end 132.132578 -70.704456)
		(width 0.12446)
		(layer "B.Cu")
		(net "PHY_DPB_TO_SCC_C_5_DP")
	)
	(segment
		(start 126.6952 -71.000112)
		(end 127 -71.000112)
		(width 0.0889)
		(layer "B.Cu")
		(net "PHY_DPB_TO_SCC_C_5_DP")
	)
	(segment
		(start 137.1854 -71.4502)
		(end 136.850882 -71.4502)
		(width 0.12446)
		(layer "B.Cu")
		(net "PHY_DPB_TO_SCC_C_5_DP")
	)
	(segment
		(start 126.595124 -70.749922)
		(end 126.595124 -70.900036)
		(width 0.0889)
		(layer "B.Cu")
		(net "PHY_DPB_TO_SCC_C_5_DP")
	)
	(segment
		(start 133.064758 -70.704456)
		(end 132.785358 -70.983856)
		(width 0.12446)
		(layer "B.Cu")
		(net "PHY_DPB_TO_SCC_C_5_DP")
	)
	(segment
		(start 136.753346 -71.352664)
		(end 136.191752 -71.352664)
		(width 0.12446)
		(layer "B.Cu")
		(net "PHY_DPB_TO_SCC_C_5_DP")
	)
	(arc
		(start 126.74854 -70.596506)
		(mid 126.640059 -70.641441)
		(end 126.595124 -70.749922)
		(width 0.0889)
		(layer "B.Cu")
		(net "PHY_DPB_TO_SCC_C_5_DP")
	)
	(arc
		(start 126.595124 -70.900036)
		(mid 126.624436 -70.9708)
		(end 126.6952 -71.000112)
		(width 0.0889)
		(layer "B.Cu")
		(net "PHY_DPB_TO_SCC_C_5_DP")
	)
	(segment
		(start 125.50013 -70.50024)
		(end 126.000002 -71.000112)
		(width 0.104902)
		(layer "F.Cu")
		(net "PHY_DPB_TO_SCC_C_5_DN")
	)
	(via
		(at 126.000002 -71.000112)
		(size 0.4572)
		(drill 0.2032)
		(layers "F.Cu" "B.Cu")
		(net "PHY_DPB_TO_SCC_C_5_DN")
	)
	(segment
		(start 136.806432 -70.8914)
		(end 136.751568 -70.946264)
		(width 0.12446)
		(layer "B.Cu")
		(net "PHY_DPB_TO_SCC_C_5_DN")
	)
	(segment
		(start 131.7371 -70.298056)
		(end 131.62915 -70.406006)
		(width 0.0889)
		(layer "B.Cu")
		(net "PHY_DPB_TO_SCC_C_5_DN")
	)
	(segment
		(start 136.751568 -70.946264)
		(end 136.360154 -70.946264)
		(width 0.12446)
		(layer "B.Cu")
		(net "PHY_DPB_TO_SCC_C_5_DN")
	)
	(segment
		(start 126.304802 -71.000112)
		(end 126.000002 -71.000112)
		(width 0.0889)
		(layer "B.Cu")
		(net "PHY_DPB_TO_SCC_C_5_DN")
	)
	(segment
		(start 137.1854 -70.8914)
		(end 136.806432 -70.8914)
		(width 0.12446)
		(layer "B.Cu")
		(net "PHY_DPB_TO_SCC_C_5_DN")
	)
	(segment
		(start 136.360154 -70.946264)
		(end 135.711946 -70.298056)
		(width 0.12446)
		(layer "B.Cu")
		(net "PHY_DPB_TO_SCC_C_5_DN")
	)
	(segment
		(start 131.759198 -70.298056)
		(end 131.7371 -70.298056)
		(width 0.0889)
		(layer "B.Cu")
		(net "PHY_DPB_TO_SCC_C_5_DN")
	)
	(segment
		(start 131.62915 -70.406006)
		(end 126.74854 -70.406006)
		(width 0.0889)
		(layer "B.Cu")
		(net "PHY_DPB_TO_SCC_C_5_DN")
	)
	(segment
		(start 126.404624 -70.749922)
		(end 126.404624 -70.90029)
		(width 0.0889)
		(layer "B.Cu")
		(net "PHY_DPB_TO_SCC_C_5_DN")
	)
	(segment
		(start 135.711946 -70.298056)
		(end 131.759198 -70.298056)
		(width 0.12446)
		(layer "B.Cu")
		(net "PHY_DPB_TO_SCC_C_5_DN")
	)
	(arc
		(start 126.404624 -70.90029)
		(mid 126.375387 -70.970875)
		(end 126.304802 -71.000112)
		(width 0.0889)
		(layer "B.Cu")
		(net "PHY_DPB_TO_SCC_C_5_DN")
	)
	(arc
		(start 126.74854 -70.406006)
		(mid 126.505355 -70.506737)
		(end 126.404624 -70.749922)
		(width 0.0889)
		(layer "B.Cu")
		(net "PHY_DPB_TO_SCC_C_5_DN")
	)
	(segment
		(start 126.500128 -69.500242)
		(end 127 -70.000114)
		(width 0.104902)
		(layer "F.Cu")
		(net "PHY_DPB_TO_SCC_C_4_DP")
	)
	(via
		(at 127 -70.000114)
		(size 0.4572)
		(drill 0.2032)
		(layers "F.Cu" "B.Cu")
		(net "PHY_DPB_TO_SCC_C_4_DP")
	)
	(segment
		(start 132.276088 -69.474334)
		(end 132.024628 -69.474334)
		(width 0.12446)
		(layer "B.Cu")
		(net "PHY_DPB_TO_SCC_C_4_DP")
	)
	(segment
		(start 132.024628 -69.474334)
		(end 131.785106 -69.713856)
		(width 0.12446)
		(layer "B.Cu")
		(net "PHY_DPB_TO_SCC_C_4_DP")
	)
	(segment
		(start 132.928868 -69.753734)
		(end 132.555488 -69.753734)
		(width 0.12446)
		(layer "B.Cu")
		(net "PHY_DPB_TO_SCC_C_4_DP")
	)
	(segment
		(start 136.042146 -69.474334)
		(end 133.208268 -69.474334)
		(width 0.12446)
		(layer "B.Cu")
		(net "PHY_DPB_TO_SCC_C_4_DP")
	)
	(segment
		(start 131.285488 -69.594222)
		(end 126.750826 -69.594222)
		(width 0.0889)
		(layer "B.Cu")
		(net "PHY_DPB_TO_SCC_C_4_DP")
	)
	(segment
		(start 136.70153 -69.795898)
		(end 136.36371 -69.795898)
		(width 0.12446)
		(layer "B.Cu")
		(net "PHY_DPB_TO_SCC_C_4_DP")
	)
	(segment
		(start 131.405122 -69.713856)
		(end 131.285488 -69.594222)
		(width 0.0889)
		(layer "B.Cu")
		(net "PHY_DPB_TO_SCC_C_4_DP")
	)
	(segment
		(start 132.555488 -69.753734)
		(end 132.276088 -69.474334)
		(width 0.12446)
		(layer "B.Cu")
		(net "PHY_DPB_TO_SCC_C_4_DP")
	)
	(segment
		(start 136.806432 -69.9008)
		(end 136.70153 -69.795898)
		(width 0.12446)
		(layer "B.Cu")
		(net "PHY_DPB_TO_SCC_C_4_DP")
	)
	(segment
		(start 126.595124 -69.749924)
		(end 126.595124 -69.900038)
		(width 0.0889)
		(layer "B.Cu")
		(net "PHY_DPB_TO_SCC_C_4_DP")
	)
	(segment
		(start 133.208268 -69.474334)
		(end 132.928868 -69.753734)
		(width 0.12446)
		(layer "B.Cu")
		(net "PHY_DPB_TO_SCC_C_4_DP")
	)
	(segment
		(start 126.6952 -70.000114)
		(end 127 -70.000114)
		(width 0.0889)
		(layer "B.Cu")
		(net "PHY_DPB_TO_SCC_C_4_DP")
	)
	(segment
		(start 137.1854 -69.9008)
		(end 136.806432 -69.9008)
		(width 0.12446)
		(layer "B.Cu")
		(net "PHY_DPB_TO_SCC_C_4_DP")
	)
	(segment
		(start 131.785106 -69.713856)
		(end 131.42722 -69.713856)
		(width 0.12446)
		(layer "B.Cu")
		(net "PHY_DPB_TO_SCC_C_4_DP")
	)
	(segment
		(start 131.42722 -69.713856)
		(end 131.405122 -69.713856)
		(width 0.0889)
		(layer "B.Cu")
		(net "PHY_DPB_TO_SCC_C_4_DP")
	)
	(segment
		(start 136.36371 -69.795898)
		(end 136.042146 -69.474334)
		(width 0.12446)
		(layer "B.Cu")
		(net "PHY_DPB_TO_SCC_C_4_DP")
	)
	(arc
		(start 126.595124 -69.900038)
		(mid 126.624436 -69.970802)
		(end 126.6952 -70.000114)
		(width 0.0889)
		(layer "B.Cu")
		(net "PHY_DPB_TO_SCC_C_4_DP")
	)
	(arc
		(start 126.750826 -69.594222)
		(mid 126.640728 -69.639826)
		(end 126.595124 -69.749924)
		(width 0.0889)
		(layer "B.Cu")
		(net "PHY_DPB_TO_SCC_C_4_DP")
	)
	(segment
		(start 125.50013 -69.500242)
		(end 126.000002 -70.000114)
		(width 0.104902)
		(layer "F.Cu")
		(net "PHY_DPB_TO_SCC_C_4_DN")
	)
	(via
		(at 126.000002 -70.000114)
		(size 0.4572)
		(drill 0.2032)
		(layers "F.Cu" "B.Cu")
		(net "PHY_DPB_TO_SCC_C_4_DN")
	)
	(segment
		(start 136.532112 -69.389498)
		(end 136.210548 -69.067934)
		(width 0.12446)
		(layer "B.Cu")
		(net "PHY_DPB_TO_SCC_C_4_DN")
	)
	(segment
		(start 131.42722 -69.307456)
		(end 131.405122 -69.307456)
		(width 0.0889)
		(layer "B.Cu")
		(net "PHY_DPB_TO_SCC_C_4_DN")
	)
	(segment
		(start 131.405122 -69.307456)
		(end 131.308856 -69.403722)
		(width 0.0889)
		(layer "B.Cu")
		(net "PHY_DPB_TO_SCC_C_4_DN")
	)
	(segment
		(start 137.1854 -69.342)
		(end 136.806432 -69.342)
		(width 0.12446)
		(layer "B.Cu")
		(net "PHY_DPB_TO_SCC_C_4_DN")
	)
	(segment
		(start 131.616704 -69.307456)
		(end 131.42722 -69.307456)
		(width 0.12446)
		(layer "B.Cu")
		(net "PHY_DPB_TO_SCC_C_4_DN")
	)
	(segment
		(start 136.806432 -69.342)
		(end 136.758934 -69.389498)
		(width 0.12446)
		(layer "B.Cu")
		(net "PHY_DPB_TO_SCC_C_4_DN")
	)
	(segment
		(start 136.210548 -69.067934)
		(end 131.856226 -69.067934)
		(width 0.12446)
		(layer "B.Cu")
		(net "PHY_DPB_TO_SCC_C_4_DN")
	)
	(segment
		(start 126.304802 -70.000114)
		(end 126.000002 -70.000114)
		(width 0.0889)
		(layer "B.Cu")
		(net "PHY_DPB_TO_SCC_C_4_DN")
	)
	(segment
		(start 131.856226 -69.067934)
		(end 131.616704 -69.307456)
		(width 0.12446)
		(layer "B.Cu")
		(net "PHY_DPB_TO_SCC_C_4_DN")
	)
	(segment
		(start 131.308856 -69.403722)
		(end 126.750826 -69.403722)
		(width 0.0889)
		(layer "B.Cu")
		(net "PHY_DPB_TO_SCC_C_4_DN")
	)
	(segment
		(start 136.758934 -69.389498)
		(end 136.532112 -69.389498)
		(width 0.12446)
		(layer "B.Cu")
		(net "PHY_DPB_TO_SCC_C_4_DN")
	)
	(segment
		(start 126.404624 -69.749924)
		(end 126.404624 -69.900292)
		(width 0.0889)
		(layer "B.Cu")
		(net "PHY_DPB_TO_SCC_C_4_DN")
	)
	(arc
		(start 126.404624 -69.900292)
		(mid 126.375387 -69.970877)
		(end 126.304802 -70.000114)
		(width 0.0889)
		(layer "B.Cu")
		(net "PHY_DPB_TO_SCC_C_4_DN")
	)
	(arc
		(start 126.750826 -69.403722)
		(mid 126.506024 -69.505122)
		(end 126.404624 -69.749924)
		(width 0.0889)
		(layer "B.Cu")
		(net "PHY_DPB_TO_SCC_C_4_DN")
	)
	(segment
		(start 123.500134 -55.500016)
		(end 124.000006 -55.000144)
		(width 0.104902)
		(layer "F.Cu")
		(net "PHY_DPB_TO_SCC_C_39_DP")
	)
	(via
		(at 124.000006 -55.000144)
		(size 0.4572)
		(drill 0.2032)
		(layers "F.Cu" "B.Cu")
		(net "PHY_DPB_TO_SCC_C_39_DP")
	)
	(segment
		(start 127.330454 -40.725344)
		(end 127.330454 -40.080946)
		(width 0.12446)
		(layer "B.Cu")
		(net "PHY_DPB_TO_SCC_C_39_DP")
	)
	(segment
		(start 124.259086 -50.344324)
		(end 124.27458 -50.32883)
		(width 0.0889)
		(layer "B.Cu")
		(net "PHY_DPB_TO_SCC_C_39_DP")
	)
	(segment
		(start 124.000006 -55.000144)
		(end 124.000006 -55.31612)
		(width 0.0889)
		(layer "B.Cu")
		(net "PHY_DPB_TO_SCC_C_39_DP")
	)
	(segment
		(start 124.026676 -50.344324)
		(end 124.259086 -50.344324)
		(width 0.0889)
		(layer "B.Cu")
		(net "PHY_DPB_TO_SCC_C_39_DP")
	)
	(segment
		(start 124.27458 -50.32883)
		(end 124.820172 -49.783746)
		(width 0.12446)
		(layer "B.Cu")
		(net "PHY_DPB_TO_SCC_C_39_DP")
	)
	(segment
		(start 123.593606 -55.237126)
		(end 123.593606 -50.777394)
		(width 0.0889)
		(layer "B.Cu")
		(net "PHY_DPB_TO_SCC_C_39_DP")
	)
	(segment
		(start 124.820172 -49.783746)
		(end 125.690122 -48.443388)
		(width 0.12446)
		(layer "B.Cu")
		(net "PHY_DPB_TO_SCC_C_39_DP")
	)
	(segment
		(start 123.911106 -55.40502)
		(end 123.761246 -55.40502)
		(width 0.0889)
		(layer "B.Cu")
		(net "PHY_DPB_TO_SCC_C_39_DP")
	)
	(segment
		(start 123.593606 -50.777394)
		(end 124.026676 -50.344324)
		(width 0.0889)
		(layer "B.Cu")
		(net "PHY_DPB_TO_SCC_C_39_DP")
	)
	(segment
		(start 127.330454 -40.080946)
		(end 127.4572 -39.9542)
		(width 0.12446)
		(layer "B.Cu")
		(net "PHY_DPB_TO_SCC_C_39_DP")
	)
	(segment
		(start 125.690122 -48.443388)
		(end 127.330454 -40.725344)
		(width 0.12446)
		(layer "B.Cu")
		(net "PHY_DPB_TO_SCC_C_39_DP")
	)
	(segment
		(start 127.4572 -39.9542)
		(end 127.4572 -39.751)
		(width 0.12446)
		(layer "B.Cu")
		(net "PHY_DPB_TO_SCC_C_39_DP")
	)
	(arc
		(start 123.761246 -55.40502)
		(mid 123.69719 -55.392278)
		(end 123.642882 -55.355998)
		(width 0.0889)
		(layer "B.Cu")
		(net "PHY_DPB_TO_SCC_C_39_DP")
	)
	(arc
		(start 123.642882 -55.355998)
		(mid 123.60644 -55.301459)
		(end 123.593606 -55.237126)
		(width 0.0889)
		(layer "B.Cu")
		(net "PHY_DPB_TO_SCC_C_39_DP")
	)
	(arc
		(start 124.000006 -55.31612)
		(mid 123.973968 -55.378982)
		(end 123.911106 -55.40502)
		(width 0.0889)
		(layer "B.Cu")
		(net "PHY_DPB_TO_SCC_C_39_DP")
	)
	(segment
		(start 123.500134 -56.500014)
		(end 124.000006 -56.000142)
		(width 0.104902)
		(layer "F.Cu")
		(net "PHY_DPB_TO_SCC_C_39_DN")
	)
	(via
		(at 124.000006 -56.000142)
		(size 0.4572)
		(drill 0.2032)
		(layers "F.Cu" "B.Cu")
		(net "PHY_DPB_TO_SCC_C_39_DN")
	)
	(segment
		(start 124.502672 -49.52619)
		(end 125.308106 -48.285146)
		(width 0.12446)
		(layer "B.Cu")
		(net "PHY_DPB_TO_SCC_C_39_DN")
	)
	(segment
		(start 123.403106 -55.237634)
		(end 123.403106 -50.6984)
		(width 0.0889)
		(layer "B.Cu")
		(net "PHY_DPB_TO_SCC_C_39_DN")
	)
	(segment
		(start 123.403106 -50.6984)
		(end 123.971558 -50.129948)
		(width 0.0889)
		(layer "B.Cu")
		(net "PHY_DPB_TO_SCC_C_39_DN")
	)
	(segment
		(start 123.987306 -50.041302)
		(end 124.502672 -49.52619)
		(width 0.12446)
		(layer "B.Cu")
		(net "PHY_DPB_TO_SCC_C_39_DN")
	)
	(segment
		(start 123.971558 -50.129948)
		(end 123.971558 -50.05705)
		(width 0.0889)
		(layer "B.Cu")
		(net "PHY_DPB_TO_SCC_C_39_DN")
	)
	(segment
		(start 123.971558 -50.05705)
		(end 123.987306 -50.041302)
		(width 0.0889)
		(layer "B.Cu")
		(net "PHY_DPB_TO_SCC_C_39_DN")
	)
	(segment
		(start 124.000006 -56.000142)
		(end 124.000006 -55.68442)
		(width 0.0889)
		(layer "B.Cu")
		(net "PHY_DPB_TO_SCC_C_39_DN")
	)
	(segment
		(start 125.308106 -48.285146)
		(end 126.924054 -40.682418)
		(width 0.12446)
		(layer "B.Cu")
		(net "PHY_DPB_TO_SCC_C_39_DN")
	)
	(segment
		(start 126.873 -39.9796)
		(end 126.873 -39.751)
		(width 0.12446)
		(layer "B.Cu")
		(net "PHY_DPB_TO_SCC_C_39_DN")
	)
	(segment
		(start 126.924054 -40.682418)
		(end 126.924054 -40.030654)
		(width 0.12446)
		(layer "B.Cu")
		(net "PHY_DPB_TO_SCC_C_39_DN")
	)
	(segment
		(start 126.924054 -40.030654)
		(end 126.873 -39.9796)
		(width 0.12446)
		(layer "B.Cu")
		(net "PHY_DPB_TO_SCC_C_39_DN")
	)
	(segment
		(start 123.911106 -55.59552)
		(end 123.761246 -55.59552)
		(width 0.0889)
		(layer "B.Cu")
		(net "PHY_DPB_TO_SCC_C_39_DN")
	)
	(arc
		(start 124.000006 -55.68442)
		(mid 123.973968 -55.621558)
		(end 123.911106 -55.59552)
		(width 0.0889)
		(layer "B.Cu")
		(net "PHY_DPB_TO_SCC_C_39_DN")
	)
	(arc
		(start 123.761246 -55.59552)
		(mid 123.624221 -55.568376)
		(end 123.508008 -55.490872)
		(width 0.0889)
		(layer "B.Cu")
		(net "PHY_DPB_TO_SCC_C_39_DN")
	)
	(arc
		(start 123.508008 -55.490872)
		(mid 123.430375 -55.374685)
		(end 123.403106 -55.237634)
		(width 0.0889)
		(layer "B.Cu")
		(net "PHY_DPB_TO_SCC_C_39_DN")
	)
	(segment
		(start 122.500136 -55.500016)
		(end 123.000008 -55.000144)
		(width 0.104902)
		(layer "F.Cu")
		(net "PHY_DPB_TO_SCC_C_38_DP")
	)
	(via
		(at 123.000008 -55.000144)
		(size 0.4572)
		(drill 0.2032)
		(layers "F.Cu" "B.Cu")
		(net "PHY_DPB_TO_SCC_C_38_DP")
	)
	(segment
		(start 122.703082 -50.365914)
		(end 122.703082 -50.217324)
		(width 0.12446)
		(layer "B.Cu")
		(net "PHY_DPB_TO_SCC_C_38_DP")
	)
	(segment
		(start 123.83262 -45.767752)
		(end 124.49175 -42.66692)
		(width 0.12446)
		(layer "B.Cu")
		(net "PHY_DPB_TO_SCC_C_38_DP")
	)
	(segment
		(start 122.595132 -55.240682)
		(end 122.595132 -50.495962)
		(width 0.0889)
		(layer "B.Cu")
		(net "PHY_DPB_TO_SCC_C_38_DP")
	)
	(segment
		(start 124.16663 -48.007016)
		(end 123.83262 -47.673006)
		(width 0.12446)
		(layer "B.Cu")
		(net "PHY_DPB_TO_SCC_C_38_DP")
	)
	(segment
		(start 122.595132 -50.495962)
		(end 122.703082 -50.388012)
		(width 0.0889)
		(layer "B.Cu")
		(net "PHY_DPB_TO_SCC_C_38_DP")
	)
	(segment
		(start 123.83262 -48.714406)
		(end 124.16663 -48.380396)
		(width 0.12446)
		(layer "B.Cu")
		(net "PHY_DPB_TO_SCC_C_38_DP")
	)
	(segment
		(start 125.476 -40.0812)
		(end 125.5776 -39.9796)
		(width 0.12446)
		(layer "B.Cu")
		(net "PHY_DPB_TO_SCC_C_38_DP")
	)
	(segment
		(start 123.83262 -47.673006)
		(end 123.83262 -45.767752)
		(width 0.12446)
		(layer "B.Cu")
		(net "PHY_DPB_TO_SCC_C_38_DP")
	)
	(segment
		(start 125.5776 -39.9796)
		(end 125.5776 -39.751)
		(width 0.12446)
		(layer "B.Cu")
		(net "PHY_DPB_TO_SCC_C_38_DP")
	)
	(segment
		(start 124.16663 -48.380396)
		(end 124.16663 -48.007016)
		(width 0.12446)
		(layer "B.Cu")
		(net "PHY_DPB_TO_SCC_C_38_DP")
	)
	(segment
		(start 123.83262 -49.087786)
		(end 123.83262 -48.714406)
		(width 0.12446)
		(layer "B.Cu")
		(net "PHY_DPB_TO_SCC_C_38_DP")
	)
	(segment
		(start 122.911108 -55.40502)
		(end 122.761248 -55.40502)
		(width 0.0889)
		(layer "B.Cu")
		(net "PHY_DPB_TO_SCC_C_38_DP")
	)
	(segment
		(start 122.703082 -50.217324)
		(end 123.83262 -49.087786)
		(width 0.12446)
		(layer "B.Cu")
		(net "PHY_DPB_TO_SCC_C_38_DP")
	)
	(segment
		(start 125.476 -41.151302)
		(end 125.476 -40.0812)
		(width 0.12446)
		(layer "B.Cu")
		(net "PHY_DPB_TO_SCC_C_38_DP")
	)
	(segment
		(start 124.49175 -42.66692)
		(end 125.476 -41.151302)
		(width 0.12446)
		(layer "B.Cu")
		(net "PHY_DPB_TO_SCC_C_38_DP")
	)
	(segment
		(start 122.703082 -50.388012)
		(end 122.703082 -50.365914)
		(width 0.0889)
		(layer "B.Cu")
		(net "PHY_DPB_TO_SCC_C_38_DP")
	)
	(segment
		(start 123.000008 -55.000144)
		(end 123.000008 -55.31612)
		(width 0.0889)
		(layer "B.Cu")
		(net "PHY_DPB_TO_SCC_C_38_DP")
	)
	(arc
		(start 122.761248 -55.40502)
		(mid 122.697192 -55.392278)
		(end 122.642884 -55.355998)
		(width 0.0889)
		(layer "B.Cu")
		(net "PHY_DPB_TO_SCC_C_38_DP")
	)
	(arc
		(start 122.642884 -55.355998)
		(mid 122.607532 -55.303091)
		(end 122.595132 -55.240682)
		(width 0.0889)
		(layer "B.Cu")
		(net "PHY_DPB_TO_SCC_C_38_DP")
	)
	(arc
		(start 123.000008 -55.31612)
		(mid 122.97397 -55.378982)
		(end 122.911108 -55.40502)
		(width 0.0889)
		(layer "B.Cu")
		(net "PHY_DPB_TO_SCC_C_38_DP")
	)
	(segment
		(start 122.500136 -56.500014)
		(end 123.000008 -56.000142)
		(width 0.104902)
		(layer "F.Cu")
		(net "PHY_DPB_TO_SCC_C_38_DN")
	)
	(via
		(at 123.000008 -56.000142)
		(size 0.4572)
		(drill 0.2032)
		(layers "F.Cu" "B.Cu")
		(net "PHY_DPB_TO_SCC_C_38_DN")
	)
	(segment
		(start 124.9934 -40.005)
		(end 124.9934 -39.751)
		(width 0.12446)
		(layer "B.Cu")
		(net "PHY_DPB_TO_SCC_C_38_DN")
	)
	(segment
		(start 124.109734 -42.508678)
		(end 125.0696 -41.030906)
		(width 0.12446)
		(layer "B.Cu")
		(net "PHY_DPB_TO_SCC_C_38_DN")
	)
	(segment
		(start 125.0696 -40.0812)
		(end 124.9934 -40.005)
		(width 0.12446)
		(layer "B.Cu")
		(net "PHY_DPB_TO_SCC_C_38_DN")
	)
	(segment
		(start 122.296682 -50.388012)
		(end 122.296682 -50.365914)
		(width 0.0889)
		(layer "B.Cu")
		(net "PHY_DPB_TO_SCC_C_38_DN")
	)
	(segment
		(start 122.404632 -50.495962)
		(end 122.296682 -50.388012)
		(width 0.0889)
		(layer "B.Cu")
		(net "PHY_DPB_TO_SCC_C_38_DN")
	)
	(segment
		(start 123.000008 -56.000142)
		(end 123.000008 -55.68442)
		(width 0.0889)
		(layer "B.Cu")
		(net "PHY_DPB_TO_SCC_C_38_DN")
	)
	(segment
		(start 122.296682 -50.365914)
		(end 122.296682 -50.048922)
		(width 0.12446)
		(layer "B.Cu")
		(net "PHY_DPB_TO_SCC_C_38_DN")
	)
	(segment
		(start 123.42622 -48.919384)
		(end 123.42622 -45.724572)
		(width 0.12446)
		(layer "B.Cu")
		(net "PHY_DPB_TO_SCC_C_38_DN")
	)
	(segment
		(start 123.42622 -45.724572)
		(end 124.109734 -42.508678)
		(width 0.12446)
		(layer "B.Cu")
		(net "PHY_DPB_TO_SCC_C_38_DN")
	)
	(segment
		(start 122.911108 -55.59552)
		(end 122.761248 -55.59552)
		(width 0.0889)
		(layer "B.Cu")
		(net "PHY_DPB_TO_SCC_C_38_DN")
	)
	(segment
		(start 122.296682 -50.048922)
		(end 123.42622 -48.919384)
		(width 0.12446)
		(layer "B.Cu")
		(net "PHY_DPB_TO_SCC_C_38_DN")
	)
	(segment
		(start 122.404632 -55.24119)
		(end 122.404632 -50.495962)
		(width 0.0889)
		(layer "B.Cu")
		(net "PHY_DPB_TO_SCC_C_38_DN")
	)
	(segment
		(start 125.0696 -41.030906)
		(end 125.0696 -40.0812)
		(width 0.12446)
		(layer "B.Cu")
		(net "PHY_DPB_TO_SCC_C_38_DN")
	)
	(arc
		(start 122.761248 -55.59552)
		(mid 122.624223 -55.568376)
		(end 122.50801 -55.490872)
		(width 0.0889)
		(layer "B.Cu")
		(net "PHY_DPB_TO_SCC_C_38_DN")
	)
	(arc
		(start 123.000008 -55.68442)
		(mid 122.97397 -55.621558)
		(end 122.911108 -55.59552)
		(width 0.0889)
		(layer "B.Cu")
		(net "PHY_DPB_TO_SCC_C_38_DN")
	)
	(arc
		(start 122.50801 -55.490872)
		(mid 122.43152 -55.376303)
		(end 122.404632 -55.24119)
		(width 0.0889)
		(layer "B.Cu")
		(net "PHY_DPB_TO_SCC_C_38_DN")
	)
	(segment
		(start 121.500138 -55.500016)
		(end 122.00001 -55.000144)
		(width 0.104902)
		(layer "F.Cu")
		(net "PHY_DPB_TO_SCC_C_37_DP")
	)
	(via
		(at 122.00001 -55.000144)
		(size 0.4572)
		(drill 0.2032)
		(layers "F.Cu" "B.Cu")
		(net "PHY_DPB_TO_SCC_C_37_DP")
	)
	(segment
		(start 123.7234 -40.300656)
		(end 123.7234 -40.0304)
		(width 0.12446)
		(layer "B.Cu")
		(net "PHY_DPB_TO_SCC_C_37_DP")
	)
	(segment
		(start 122.949716 -48.069246)
		(end 122.603514 -47.723044)
		(width 0.12446)
		(layer "B.Cu")
		(net "PHY_DPB_TO_SCC_C_37_DP")
	)
	(segment
		(start 121.703846 -50.061876)
		(end 122.603514 -49.162208)
		(width 0.12446)
		(layer "B.Cu")
		(net "PHY_DPB_TO_SCC_C_37_DP")
	)
	(segment
		(start 121.703846 -50.365914)
		(end 121.703846 -50.061876)
		(width 0.12446)
		(layer "B.Cu")
		(net "PHY_DPB_TO_SCC_C_37_DP")
	)
	(segment
		(start 121.595896 -55.24246)
		(end 121.595896 -50.495962)
		(width 0.0889)
		(layer "B.Cu")
		(net "PHY_DPB_TO_SCC_C_37_DP")
	)
	(segment
		(start 121.595896 -50.495962)
		(end 121.703846 -50.388012)
		(width 0.0889)
		(layer "B.Cu")
		(net "PHY_DPB_TO_SCC_C_37_DP")
	)
	(segment
		(start 123.7996 -39.9542)
		(end 123.7996 -39.751)
		(width 0.12446)
		(layer "B.Cu")
		(net "PHY_DPB_TO_SCC_C_37_DP")
	)
	(segment
		(start 122.949716 -48.442626)
		(end 122.949716 -48.069246)
		(width 0.12446)
		(layer "B.Cu")
		(net "PHY_DPB_TO_SCC_C_37_DP")
	)
	(segment
		(start 122.603514 -49.162208)
		(end 122.603514 -48.788828)
		(width 0.12446)
		(layer "B.Cu")
		(net "PHY_DPB_TO_SCC_C_37_DP")
	)
	(segment
		(start 121.91111 -55.40502)
		(end 121.76125 -55.40502)
		(width 0.0889)
		(layer "B.Cu")
		(net "PHY_DPB_TO_SCC_C_37_DP")
	)
	(segment
		(start 122.603514 -48.788828)
		(end 122.949716 -48.442626)
		(width 0.12446)
		(layer "B.Cu")
		(net "PHY_DPB_TO_SCC_C_37_DP")
	)
	(segment
		(start 122.603514 -45.569632)
		(end 123.7234 -40.300656)
		(width 0.12446)
		(layer "B.Cu")
		(net "PHY_DPB_TO_SCC_C_37_DP")
	)
	(segment
		(start 122.00001 -55.000144)
		(end 122.00001 -55.31612)
		(width 0.0889)
		(layer "B.Cu")
		(net "PHY_DPB_TO_SCC_C_37_DP")
	)
	(segment
		(start 123.7234 -40.0304)
		(end 123.7996 -39.9542)
		(width 0.12446)
		(layer "B.Cu")
		(net "PHY_DPB_TO_SCC_C_37_DP")
	)
	(segment
		(start 121.703846 -50.388012)
		(end 121.703846 -50.365914)
		(width 0.0889)
		(layer "B.Cu")
		(net "PHY_DPB_TO_SCC_C_37_DP")
	)
	(segment
		(start 122.603514 -47.723044)
		(end 122.603514 -45.569632)
		(width 0.12446)
		(layer "B.Cu")
		(net "PHY_DPB_TO_SCC_C_37_DP")
	)
	(arc
		(start 121.76125 -55.40502)
		(mid 121.697194 -55.392278)
		(end 121.642886 -55.355998)
		(width 0.0889)
		(layer "B.Cu")
		(net "PHY_DPB_TO_SCC_C_37_DP")
	)
	(arc
		(start 122.00001 -55.31612)
		(mid 121.973972 -55.378982)
		(end 121.91111 -55.40502)
		(width 0.0889)
		(layer "B.Cu")
		(net "PHY_DPB_TO_SCC_C_37_DP")
	)
	(arc
		(start 121.642886 -55.355998)
		(mid 121.608079 -55.303906)
		(end 121.595896 -55.24246)
		(width 0.0889)
		(layer "B.Cu")
		(net "PHY_DPB_TO_SCC_C_37_DP")
	)
	(segment
		(start 121.500138 -56.500014)
		(end 122.00001 -56.000142)
		(width 0.104902)
		(layer "F.Cu")
		(net "PHY_DPB_TO_SCC_C_37_DN")
	)
	(via
		(at 122.00001 -56.000142)
		(size 0.4572)
		(drill 0.2032)
		(layers "F.Cu" "B.Cu")
		(net "PHY_DPB_TO_SCC_C_37_DN")
	)
	(segment
		(start 121.297446 -49.893474)
		(end 122.197114 -48.993806)
		(width 0.12446)
		(layer "B.Cu")
		(net "PHY_DPB_TO_SCC_C_37_DN")
	)
	(segment
		(start 123.317 -40.25773)
		(end 123.317 -40.0558)
		(width 0.12446)
		(layer "B.Cu")
		(net "PHY_DPB_TO_SCC_C_37_DN")
	)
	(segment
		(start 122.197114 -48.993806)
		(end 122.197114 -45.526706)
		(width 0.12446)
		(layer "B.Cu")
		(net "PHY_DPB_TO_SCC_C_37_DN")
	)
	(segment
		(start 121.405396 -50.495962)
		(end 121.297446 -50.388012)
		(width 0.0889)
		(layer "B.Cu")
		(net "PHY_DPB_TO_SCC_C_37_DN")
	)
	(segment
		(start 122.197114 -45.526706)
		(end 123.038616 -41.5671)
		(width 0.12446)
		(layer "B.Cu")
		(net "PHY_DPB_TO_SCC_C_37_DN")
	)
	(segment
		(start 121.297446 -50.388012)
		(end 121.297446 -50.365914)
		(width 0.0889)
		(layer "B.Cu")
		(net "PHY_DPB_TO_SCC_C_37_DN")
	)
	(segment
		(start 123.317 -40.0558)
		(end 123.2154 -39.9542)
		(width 0.12446)
		(layer "B.Cu")
		(net "PHY_DPB_TO_SCC_C_37_DN")
	)
	(segment
		(start 123.2154 -39.9542)
		(end 123.2154 -39.751)
		(width 0.12446)
		(layer "B.Cu")
		(net "PHY_DPB_TO_SCC_C_37_DN")
	)
	(segment
		(start 122.00001 -56.000142)
		(end 122.00001 -55.68442)
		(width 0.0889)
		(layer "B.Cu")
		(net "PHY_DPB_TO_SCC_C_37_DN")
	)
	(segment
		(start 121.405396 -55.243222)
		(end 121.405396 -50.495962)
		(width 0.0889)
		(layer "B.Cu")
		(net "PHY_DPB_TO_SCC_C_37_DN")
	)
	(segment
		(start 123.038616 -41.5671)
		(end 123.317 -40.25773)
		(width 0.12446)
		(layer "B.Cu")
		(net "PHY_DPB_TO_SCC_C_37_DN")
	)
	(segment
		(start 121.297446 -50.365914)
		(end 121.297446 -49.893474)
		(width 0.12446)
		(layer "B.Cu")
		(net "PHY_DPB_TO_SCC_C_37_DN")
	)
	(segment
		(start 121.91111 -55.59552)
		(end 121.76125 -55.59552)
		(width 0.0889)
		(layer "B.Cu")
		(net "PHY_DPB_TO_SCC_C_37_DN")
	)
	(arc
		(start 121.76125 -55.59552)
		(mid 121.624225 -55.568376)
		(end 121.508012 -55.490872)
		(width 0.0889)
		(layer "B.Cu")
		(net "PHY_DPB_TO_SCC_C_37_DN")
	)
	(arc
		(start 122.00001 -55.68442)
		(mid 121.973972 -55.621558)
		(end 121.91111 -55.59552)
		(width 0.0889)
		(layer "B.Cu")
		(net "PHY_DPB_TO_SCC_C_37_DN")
	)
	(arc
		(start 121.508012 -55.490872)
		(mid 121.432092 -55.377249)
		(end 121.405396 -55.243222)
		(width 0.0889)
		(layer "B.Cu")
		(net "PHY_DPB_TO_SCC_C_37_DN")
	)
	(segment
		(start 120.50014 -55.500016)
		(end 121.000012 -55.000144)
		(width 0.104902)
		(layer "F.Cu")
		(net "PHY_DPB_TO_SCC_C_36_DP")
	)
	(via
		(at 121.000012 -55.000144)
		(size 0.4572)
		(drill 0.2032)
		(layers "F.Cu" "B.Cu")
		(net "PHY_DPB_TO_SCC_C_36_DP")
	)
	(segment
		(start 120.59666 -50.495962)
		(end 120.70461 -50.388012)
		(width 0.0889)
		(layer "B.Cu")
		(net "PHY_DPB_TO_SCC_C_36_DP")
	)
	(segment
		(start 121.38025 -44.597828)
		(end 121.92 -41.793668)
		(width 0.12446)
		(layer "B.Cu")
		(net "PHY_DPB_TO_SCC_C_36_DP")
	)
	(segment
		(start 122.0216 -40.005)
		(end 122.0216 -39.751)
		(width 0.12446)
		(layer "B.Cu")
		(net "PHY_DPB_TO_SCC_C_36_DP")
	)
	(segment
		(start 120.70461 -49.82337)
		(end 121.38025 -49.14773)
		(width 0.12446)
		(layer "B.Cu")
		(net "PHY_DPB_TO_SCC_C_36_DP")
	)
	(segment
		(start 121.000012 -55.000144)
		(end 121.000012 -55.31612)
		(width 0.0889)
		(layer "B.Cu")
		(net "PHY_DPB_TO_SCC_C_36_DP")
	)
	(segment
		(start 121.92 -40.1066)
		(end 122.0216 -40.005)
		(width 0.12446)
		(layer "B.Cu")
		(net "PHY_DPB_TO_SCC_C_36_DP")
	)
	(segment
		(start 120.59666 -55.244492)
		(end 120.59666 -50.495962)
		(width 0.0889)
		(layer "B.Cu")
		(net "PHY_DPB_TO_SCC_C_36_DP")
	)
	(segment
		(start 122.203464 -40.734996)
		(end 121.92 -40.451532)
		(width 0.12446)
		(layer "B.Cu")
		(net "PHY_DPB_TO_SCC_C_36_DP")
	)
	(segment
		(start 120.911112 -55.40502)
		(end 120.761252 -55.40502)
		(width 0.0889)
		(layer "B.Cu")
		(net "PHY_DPB_TO_SCC_C_36_DP")
	)
	(segment
		(start 121.38025 -49.14773)
		(end 121.38025 -44.597828)
		(width 0.12446)
		(layer "B.Cu")
		(net "PHY_DPB_TO_SCC_C_36_DP")
	)
	(segment
		(start 121.92 -41.793668)
		(end 121.92 -41.39184)
		(width 0.12446)
		(layer "B.Cu")
		(net "PHY_DPB_TO_SCC_C_36_DP")
	)
	(segment
		(start 120.70461 -50.365914)
		(end 120.70461 -49.82337)
		(width 0.12446)
		(layer "B.Cu")
		(net "PHY_DPB_TO_SCC_C_36_DP")
	)
	(segment
		(start 121.92 -41.39184)
		(end 122.203464 -41.108376)
		(width 0.12446)
		(layer "B.Cu")
		(net "PHY_DPB_TO_SCC_C_36_DP")
	)
	(segment
		(start 122.203464 -41.108376)
		(end 122.203464 -40.734996)
		(width 0.12446)
		(layer "B.Cu")
		(net "PHY_DPB_TO_SCC_C_36_DP")
	)
	(segment
		(start 121.92 -40.451532)
		(end 121.92 -40.1066)
		(width 0.12446)
		(layer "B.Cu")
		(net "PHY_DPB_TO_SCC_C_36_DP")
	)
	(segment
		(start 120.70461 -50.388012)
		(end 120.70461 -50.365914)
		(width 0.0889)
		(layer "B.Cu")
		(net "PHY_DPB_TO_SCC_C_36_DP")
	)
	(arc
		(start 121.000012 -55.31612)
		(mid 120.973974 -55.378982)
		(end 120.911112 -55.40502)
		(width 0.0889)
		(layer "B.Cu")
		(net "PHY_DPB_TO_SCC_C_36_DP")
	)
	(arc
		(start 120.642888 -55.355998)
		(mid 120.608704 -55.304839)
		(end 120.59666 -55.244492)
		(width 0.0889)
		(layer "B.Cu")
		(net "PHY_DPB_TO_SCC_C_36_DP")
	)
	(arc
		(start 120.761252 -55.40502)
		(mid 120.697196 -55.392278)
		(end 120.642888 -55.355998)
		(width 0.0889)
		(layer "B.Cu")
		(net "PHY_DPB_TO_SCC_C_36_DP")
	)
	(segment
		(start 120.50014 -56.500014)
		(end 121.000012 -56.000142)
		(width 0.104902)
		(layer "F.Cu")
		(net "PHY_DPB_TO_SCC_C_36_DN")
	)
	(via
		(at 121.000012 -56.000142)
		(size 0.4572)
		(drill 0.2032)
		(layers "F.Cu" "B.Cu")
		(net "PHY_DPB_TO_SCC_C_36_DN")
	)
	(segment
		(start 121.4374 -39.9796)
		(end 121.4374 -39.751)
		(width 0.12446)
		(layer "B.Cu")
		(net "PHY_DPB_TO_SCC_C_36_DN")
	)
	(segment
		(start 121.5136 -41.754806)
		(end 121.5136 -40.0558)
		(width 0.12446)
		(layer "B.Cu")
		(net "PHY_DPB_TO_SCC_C_36_DN")
	)
	(segment
		(start 121.000012 -56.000142)
		(end 121.000012 -55.68442)
		(width 0.0889)
		(layer "B.Cu")
		(net "PHY_DPB_TO_SCC_C_36_DN")
	)
	(segment
		(start 120.97385 -44.558966)
		(end 121.5136 -41.754806)
		(width 0.12446)
		(layer "B.Cu")
		(net "PHY_DPB_TO_SCC_C_36_DN")
	)
	(segment
		(start 120.29821 -50.388012)
		(end 120.29821 -50.365914)
		(width 0.0889)
		(layer "B.Cu")
		(net "PHY_DPB_TO_SCC_C_36_DN")
	)
	(segment
		(start 121.5136 -40.0558)
		(end 121.4374 -39.9796)
		(width 0.12446)
		(layer "B.Cu")
		(net "PHY_DPB_TO_SCC_C_36_DN")
	)
	(segment
		(start 120.29821 -50.365914)
		(end 120.29821 -49.654968)
		(width 0.12446)
		(layer "B.Cu")
		(net "PHY_DPB_TO_SCC_C_36_DN")
	)
	(segment
		(start 120.40616 -55.245)
		(end 120.40616 -50.495962)
		(width 0.0889)
		(layer "B.Cu")
		(net "PHY_DPB_TO_SCC_C_36_DN")
	)
	(segment
		(start 120.29821 -49.654968)
		(end 120.97385 -48.979328)
		(width 0.12446)
		(layer "B.Cu")
		(net "PHY_DPB_TO_SCC_C_36_DN")
	)
	(segment
		(start 120.40616 -50.495962)
		(end 120.29821 -50.388012)
		(width 0.0889)
		(layer "B.Cu")
		(net "PHY_DPB_TO_SCC_C_36_DN")
	)
	(segment
		(start 120.911112 -55.59552)
		(end 120.761252 -55.59552)
		(width 0.0889)
		(layer "B.Cu")
		(net "PHY_DPB_TO_SCC_C_36_DN")
	)
	(segment
		(start 120.97385 -48.979328)
		(end 120.97385 -44.558966)
		(width 0.12446)
		(layer "B.Cu")
		(net "PHY_DPB_TO_SCC_C_36_DN")
	)
	(arc
		(start 120.761252 -55.59552)
		(mid 120.624227 -55.568376)
		(end 120.508014 -55.490872)
		(width 0.0889)
		(layer "B.Cu")
		(net "PHY_DPB_TO_SCC_C_36_DN")
	)
	(arc
		(start 120.508014 -55.490872)
		(mid 120.432639 -55.378065)
		(end 120.40616 -55.245)
		(width 0.0889)
		(layer "B.Cu")
		(net "PHY_DPB_TO_SCC_C_36_DN")
	)
	(arc
		(start 121.000012 -55.68442)
		(mid 120.973974 -55.621558)
		(end 120.911112 -55.59552)
		(width 0.0889)
		(layer "B.Cu")
		(net "PHY_DPB_TO_SCC_C_36_DN")
	)
	(segment
		(start 119.500142 -55.500016)
		(end 120.000014 -55.000144)
		(width 0.104902)
		(layer "F.Cu")
		(net "PHY_DPB_TO_SCC_C_35_DP")
	)
	(via
		(at 120.000014 -55.000144)
		(size 0.4572)
		(drill 0.2032)
		(layers "F.Cu" "B.Cu")
		(net "PHY_DPB_TO_SCC_C_35_DP")
	)
	(segment
		(start 120.329706 -47.986442)
		(end 119.9896 -47.646336)
		(width 0.12446)
		(layer "B.Cu")
		(net "PHY_DPB_TO_SCC_C_35_DP")
	)
	(segment
		(start 119.701564 -49.439068)
		(end 119.9896 -49.151032)
		(width 0.12446)
		(layer "B.Cu")
		(net "PHY_DPB_TO_SCC_C_35_DP")
	)
	(segment
		(start 119.9896 -47.646336)
		(end 119.9896 -44.9834)
		(width 0.12446)
		(layer "B.Cu")
		(net "PHY_DPB_TO_SCC_C_35_DP")
	)
	(segment
		(start 119.593614 -55.237126)
		(end 119.593614 -50.610262)
		(width 0.0889)
		(layer "B.Cu")
		(net "PHY_DPB_TO_SCC_C_35_DP")
	)
	(segment
		(start 120.000014 -55.000144)
		(end 120.000014 -55.31612)
		(width 0.0889)
		(layer "B.Cu")
		(net "PHY_DPB_TO_SCC_C_35_DP")
	)
	(segment
		(start 119.9896 -49.151032)
		(end 119.9896 -48.699928)
		(width 0.12446)
		(layer "B.Cu")
		(net "PHY_DPB_TO_SCC_C_35_DP")
	)
	(segment
		(start 120.329706 -48.359822)
		(end 120.329706 -47.986442)
		(width 0.12446)
		(layer "B.Cu")
		(net "PHY_DPB_TO_SCC_C_35_DP")
	)
	(segment
		(start 119.701564 -50.480214)
		(end 119.701564 -49.439068)
		(width 0.12446)
		(layer "B.Cu")
		(net "PHY_DPB_TO_SCC_C_35_DP")
	)
	(segment
		(start 120.0658 -44.9072)
		(end 120.0658 -44.5008)
		(width 0.12446)
		(layer "B.Cu")
		(net "PHY_DPB_TO_SCC_C_35_DP")
	)
	(segment
		(start 119.9896 -44.9834)
		(end 120.0658 -44.9072)
		(width 0.12446)
		(layer "B.Cu")
		(net "PHY_DPB_TO_SCC_C_35_DP")
	)
	(segment
		(start 119.911114 -55.40502)
		(end 119.761254 -55.40502)
		(width 0.0889)
		(layer "B.Cu")
		(net "PHY_DPB_TO_SCC_C_35_DP")
	)
	(segment
		(start 119.593614 -50.610262)
		(end 119.701564 -50.502312)
		(width 0.0889)
		(layer "B.Cu")
		(net "PHY_DPB_TO_SCC_C_35_DP")
	)
	(segment
		(start 119.701564 -50.502312)
		(end 119.701564 -50.480214)
		(width 0.0889)
		(layer "B.Cu")
		(net "PHY_DPB_TO_SCC_C_35_DP")
	)
	(segment
		(start 119.9896 -48.699928)
		(end 120.329706 -48.359822)
		(width 0.12446)
		(layer "B.Cu")
		(net "PHY_DPB_TO_SCC_C_35_DP")
	)
	(arc
		(start 120.000014 -55.31612)
		(mid 119.973976 -55.378982)
		(end 119.911114 -55.40502)
		(width 0.0889)
		(layer "B.Cu")
		(net "PHY_DPB_TO_SCC_C_35_DP")
	)
	(arc
		(start 119.64289 -55.355998)
		(mid 119.606448 -55.301459)
		(end 119.593614 -55.237126)
		(width 0.0889)
		(layer "B.Cu")
		(net "PHY_DPB_TO_SCC_C_35_DP")
	)
	(arc
		(start 119.761254 -55.40502)
		(mid 119.697198 -55.392278)
		(end 119.64289 -55.355998)
		(width 0.0889)
		(layer "B.Cu")
		(net "PHY_DPB_TO_SCC_C_35_DP")
	)
	(segment
		(start 119.500142 -56.500014)
		(end 120.000014 -56.000142)
		(width 0.104902)
		(layer "F.Cu")
		(net "PHY_DPB_TO_SCC_C_35_DN")
	)
	(via
		(at 120.000014 -56.000142)
		(size 0.4572)
		(drill 0.2032)
		(layers "F.Cu" "B.Cu")
		(net "PHY_DPB_TO_SCC_C_35_DN")
	)
	(segment
		(start 120.000014 -55.68442)
		(end 120.000014 -56.000142)
		(width 0.0889)
		(layer "B.Cu")
		(net "PHY_DPB_TO_SCC_C_35_DN")
	)
	(segment
		(start 119.403114 -50.610262)
		(end 119.403114 -55.237634)
		(width 0.0889)
		(layer "B.Cu")
		(net "PHY_DPB_TO_SCC_C_35_DN")
	)
	(segment
		(start 119.5832 -48.98263)
		(end 119.295164 -49.270666)
		(width 0.12446)
		(layer "B.Cu")
		(net "PHY_DPB_TO_SCC_C_35_DN")
	)
	(segment
		(start 119.5832 -44.995592)
		(end 119.5832 -48.98263)
		(width 0.12446)
		(layer "B.Cu")
		(net "PHY_DPB_TO_SCC_C_35_DN")
	)
	(segment
		(start 119.295164 -50.502312)
		(end 119.403114 -50.610262)
		(width 0.0889)
		(layer "B.Cu")
		(net "PHY_DPB_TO_SCC_C_35_DN")
	)
	(segment
		(start 119.507 -44.919392)
		(end 119.5832 -44.995592)
		(width 0.12446)
		(layer "B.Cu")
		(net "PHY_DPB_TO_SCC_C_35_DN")
	)
	(segment
		(start 119.295164 -50.480214)
		(end 119.295164 -50.502312)
		(width 0.0889)
		(layer "B.Cu")
		(net "PHY_DPB_TO_SCC_C_35_DN")
	)
	(segment
		(start 119.507 -44.5008)
		(end 119.507 -44.919392)
		(width 0.12446)
		(layer "B.Cu")
		(net "PHY_DPB_TO_SCC_C_35_DN")
	)
	(segment
		(start 119.761254 -55.59552)
		(end 119.911114 -55.59552)
		(width 0.0889)
		(layer "B.Cu")
		(net "PHY_DPB_TO_SCC_C_35_DN")
	)
	(segment
		(start 119.295164 -49.270666)
		(end 119.295164 -50.480214)
		(width 0.12446)
		(layer "B.Cu")
		(net "PHY_DPB_TO_SCC_C_35_DN")
	)
	(arc
		(start 119.911114 -55.59552)
		(mid 119.973976 -55.621558)
		(end 120.000014 -55.68442)
		(width 0.0889)
		(layer "B.Cu")
		(net "PHY_DPB_TO_SCC_C_35_DN")
	)
	(arc
		(start 119.508016 -55.490872)
		(mid 119.624232 -55.568369)
		(end 119.761254 -55.59552)
		(width 0.0889)
		(layer "B.Cu")
		(net "PHY_DPB_TO_SCC_C_35_DN")
	)
	(arc
		(start 119.403114 -55.237634)
		(mid 119.430376 -55.374688)
		(end 119.508016 -55.490872)
		(width 0.0889)
		(layer "B.Cu")
		(net "PHY_DPB_TO_SCC_C_35_DN")
	)
	(segment
		(start 118.500144 -55.500016)
		(end 119.000016 -55.000144)
		(width 0.104902)
		(layer "F.Cu")
		(net "PHY_DPB_TO_SCC_C_34_DP")
	)
	(via
		(at 119.000016 -55.000144)
		(size 0.4572)
		(drill 0.2032)
		(layers "F.Cu" "B.Cu")
		(net "PHY_DPB_TO_SCC_C_34_DP")
	)
	(segment
		(start 119.034306 -48.643794)
		(end 119.034306 -48.270414)
		(width 0.12446)
		(layer "B.Cu")
		(net "PHY_DPB_TO_SCC_C_34_DP")
	)
	(segment
		(start 118.911116 -55.40502)
		(end 118.761256 -55.40502)
		(width 0.0889)
		(layer "B.Cu")
		(net "PHY_DPB_TO_SCC_C_34_DP")
	)
	(segment
		(start 119.000016 -55.000144)
		(end 119.000016 -55.31612)
		(width 0.0889)
		(layer "B.Cu")
		(net "PHY_DPB_TO_SCC_C_34_DP")
	)
	(segment
		(start 118.702836 -48.975264)
		(end 119.034306 -48.643794)
		(width 0.12446)
		(layer "B.Cu")
		(net "PHY_DPB_TO_SCC_C_34_DP")
	)
	(segment
		(start 118.4656 -45.84192)
		(end 118.4656 -44.828968)
		(width 0.12446)
		(layer "B.Cu")
		(net "PHY_DPB_TO_SCC_C_34_DP")
	)
	(segment
		(start 118.594886 -55.240174)
		(end 118.594886 -50.495962)
		(width 0.0889)
		(layer "B.Cu")
		(net "PHY_DPB_TO_SCC_C_34_DP")
	)
	(segment
		(start 118.4656 -44.828968)
		(end 118.5418 -44.752768)
		(width 0.12446)
		(layer "B.Cu")
		(net "PHY_DPB_TO_SCC_C_34_DP")
	)
	(segment
		(start 118.702836 -50.365914)
		(end 118.702836 -48.975264)
		(width 0.12446)
		(layer "B.Cu")
		(net "PHY_DPB_TO_SCC_C_34_DP")
	)
	(segment
		(start 119.034306 -48.270414)
		(end 118.702836 -47.938944)
		(width 0.12446)
		(layer "B.Cu")
		(net "PHY_DPB_TO_SCC_C_34_DP")
	)
	(segment
		(start 118.5418 -44.752768)
		(end 118.5418 -44.5008)
		(width 0.12446)
		(layer "B.Cu")
		(net "PHY_DPB_TO_SCC_C_34_DP")
	)
	(segment
		(start 118.702836 -46.079156)
		(end 118.4656 -45.84192)
		(width 0.12446)
		(layer "B.Cu")
		(net "PHY_DPB_TO_SCC_C_34_DP")
	)
	(segment
		(start 118.702836 -50.388012)
		(end 118.702836 -50.365914)
		(width 0.0889)
		(layer "B.Cu")
		(net "PHY_DPB_TO_SCC_C_34_DP")
	)
	(segment
		(start 118.702836 -47.938944)
		(end 118.702836 -46.079156)
		(width 0.12446)
		(layer "B.Cu")
		(net "PHY_DPB_TO_SCC_C_34_DP")
	)
	(segment
		(start 118.594886 -50.495962)
		(end 118.702836 -50.388012)
		(width 0.0889)
		(layer "B.Cu")
		(net "PHY_DPB_TO_SCC_C_34_DP")
	)
	(arc
		(start 118.642892 -55.355998)
		(mid 118.607385 -55.302857)
		(end 118.594886 -55.240174)
		(width 0.0889)
		(layer "B.Cu")
		(net "PHY_DPB_TO_SCC_C_34_DP")
	)
	(arc
		(start 118.761256 -55.40502)
		(mid 118.6972 -55.392278)
		(end 118.642892 -55.355998)
		(width 0.0889)
		(layer "B.Cu")
		(net "PHY_DPB_TO_SCC_C_34_DP")
	)
	(arc
		(start 119.000016 -55.31612)
		(mid 118.973978 -55.378982)
		(end 118.911116 -55.40502)
		(width 0.0889)
		(layer "B.Cu")
		(net "PHY_DPB_TO_SCC_C_34_DP")
	)
	(segment
		(start 118.500144 -56.500014)
		(end 119.000016 -56.000142)
		(width 0.104902)
		(layer "F.Cu")
		(net "PHY_DPB_TO_SCC_C_34_DN")
	)
	(via
		(at 119.000016 -56.000142)
		(size 0.4572)
		(drill 0.2032)
		(layers "F.Cu" "B.Cu")
		(net "PHY_DPB_TO_SCC_C_34_DN")
	)
	(segment
		(start 118.0592 -46.010322)
		(end 118.0592 -44.828968)
		(width 0.12446)
		(layer "B.Cu")
		(net "PHY_DPB_TO_SCC_C_34_DN")
	)
	(segment
		(start 118.0592 -44.828968)
		(end 117.983 -44.752768)
		(width 0.12446)
		(layer "B.Cu")
		(net "PHY_DPB_TO_SCC_C_34_DN")
	)
	(segment
		(start 117.983 -44.752768)
		(end 117.983 -44.5008)
		(width 0.12446)
		(layer "B.Cu")
		(net "PHY_DPB_TO_SCC_C_34_DN")
	)
	(segment
		(start 118.404386 -55.240682)
		(end 118.404386 -50.495962)
		(width 0.0889)
		(layer "B.Cu")
		(net "PHY_DPB_TO_SCC_C_34_DN")
	)
	(segment
		(start 118.911116 -55.59552)
		(end 118.761256 -55.59552)
		(width 0.0889)
		(layer "B.Cu")
		(net "PHY_DPB_TO_SCC_C_34_DN")
	)
	(segment
		(start 118.296436 -50.388012)
		(end 118.296436 -50.365914)
		(width 0.0889)
		(layer "B.Cu")
		(net "PHY_DPB_TO_SCC_C_34_DN")
	)
	(segment
		(start 119.000016 -56.000142)
		(end 119.000016 -55.68442)
		(width 0.0889)
		(layer "B.Cu")
		(net "PHY_DPB_TO_SCC_C_34_DN")
	)
	(segment
		(start 118.296436 -50.365914)
		(end 118.296436 -46.247558)
		(width 0.12446)
		(layer "B.Cu")
		(net "PHY_DPB_TO_SCC_C_34_DN")
	)
	(segment
		(start 118.296436 -46.247558)
		(end 118.0592 -46.010322)
		(width 0.12446)
		(layer "B.Cu")
		(net "PHY_DPB_TO_SCC_C_34_DN")
	)
	(segment
		(start 118.404386 -50.495962)
		(end 118.296436 -50.388012)
		(width 0.0889)
		(layer "B.Cu")
		(net "PHY_DPB_TO_SCC_C_34_DN")
	)
	(arc
		(start 119.000016 -55.68442)
		(mid 118.973978 -55.621558)
		(end 118.911116 -55.59552)
		(width 0.0889)
		(layer "B.Cu")
		(net "PHY_DPB_TO_SCC_C_34_DN")
	)
	(arc
		(start 118.508018 -55.490872)
		(mid 118.431319 -55.376084)
		(end 118.404386 -55.240682)
		(width 0.0889)
		(layer "B.Cu")
		(net "PHY_DPB_TO_SCC_C_34_DN")
	)
	(arc
		(start 118.761256 -55.59552)
		(mid 118.624231 -55.568376)
		(end 118.508018 -55.490872)
		(width 0.0889)
		(layer "B.Cu")
		(net "PHY_DPB_TO_SCC_C_34_DN")
	)
	(segment
		(start 117.500146 -55.500016)
		(end 118.000018 -55.000144)
		(width 0.104902)
		(layer "F.Cu")
		(net "PHY_DPB_TO_SCC_C_33_DP")
	)
	(via
		(at 118.000018 -55.000144)
		(size 0.4572)
		(drill 0.2032)
		(layers "F.Cu" "B.Cu")
		(net "PHY_DPB_TO_SCC_C_33_DP")
	)
	(segment
		(start 118.000018 -55.000144)
		(end 118.000018 -55.31612)
		(width 0.0889)
		(layer "B.Cu")
		(net "PHY_DPB_TO_SCC_C_33_DP")
	)
	(segment
		(start 117.475 -46.877478)
		(end 116.936012 -46.33849)
		(width 0.12446)
		(layer "B.Cu")
		(net "PHY_DPB_TO_SCC_C_33_DP")
	)
	(segment
		(start 117.793008 -49.002696)
		(end 117.793008 -48.629316)
		(width 0.12446)
		(layer "B.Cu")
		(net "PHY_DPB_TO_SCC_C_33_DP")
	)
	(segment
		(start 117.793008 -48.629316)
		(end 117.475 -48.311308)
		(width 0.12446)
		(layer "B.Cu")
		(net "PHY_DPB_TO_SCC_C_33_DP")
	)
	(segment
		(start 117.714776 -50.36185)
		(end 117.714776 -49.93386)
		(width 0.12446)
		(layer "B.Cu")
		(net "PHY_DPB_TO_SCC_C_33_DP")
	)
	(segment
		(start 117.714776 -50.383948)
		(end 117.714776 -50.36185)
		(width 0.0889)
		(layer "B.Cu")
		(net "PHY_DPB_TO_SCC_C_33_DP")
	)
	(segment
		(start 117.594888 -50.503836)
		(end 117.714776 -50.383948)
		(width 0.0889)
		(layer "B.Cu")
		(net "PHY_DPB_TO_SCC_C_33_DP")
	)
	(segment
		(start 116.936012 -46.33849)
		(end 116.936012 -44.961556)
		(width 0.12446)
		(layer "B.Cu")
		(net "PHY_DPB_TO_SCC_C_33_DP")
	)
	(segment
		(start 117.0178 -44.879768)
		(end 117.0178 -44.5008)
		(width 0.12446)
		(layer "B.Cu")
		(net "PHY_DPB_TO_SCC_C_33_DP")
	)
	(segment
		(start 117.714776 -49.93386)
		(end 117.475 -49.694084)
		(width 0.12446)
		(layer "B.Cu")
		(net "PHY_DPB_TO_SCC_C_33_DP")
	)
	(segment
		(start 117.475 -48.311308)
		(end 117.475 -46.877478)
		(width 0.12446)
		(layer "B.Cu")
		(net "PHY_DPB_TO_SCC_C_33_DP")
	)
	(segment
		(start 117.475 -49.694084)
		(end 117.475 -49.320704)
		(width 0.12446)
		(layer "B.Cu")
		(net "PHY_DPB_TO_SCC_C_33_DP")
	)
	(segment
		(start 117.594888 -55.240174)
		(end 117.594888 -50.503836)
		(width 0.0889)
		(layer "B.Cu")
		(net "PHY_DPB_TO_SCC_C_33_DP")
	)
	(segment
		(start 117.475 -49.320704)
		(end 117.793008 -49.002696)
		(width 0.12446)
		(layer "B.Cu")
		(net "PHY_DPB_TO_SCC_C_33_DP")
	)
	(segment
		(start 117.911118 -55.40502)
		(end 117.761258 -55.40502)
		(width 0.0889)
		(layer "B.Cu")
		(net "PHY_DPB_TO_SCC_C_33_DP")
	)
	(segment
		(start 116.936012 -44.961556)
		(end 117.0178 -44.879768)
		(width 0.12446)
		(layer "B.Cu")
		(net "PHY_DPB_TO_SCC_C_33_DP")
	)
	(arc
		(start 117.761258 -55.40502)
		(mid 117.697202 -55.392278)
		(end 117.642894 -55.355998)
		(width 0.0889)
		(layer "B.Cu")
		(net "PHY_DPB_TO_SCC_C_33_DP")
	)
	(arc
		(start 117.642894 -55.355998)
		(mid 117.607387 -55.302857)
		(end 117.594888 -55.240174)
		(width 0.0889)
		(layer "B.Cu")
		(net "PHY_DPB_TO_SCC_C_33_DP")
	)
	(arc
		(start 118.000018 -55.31612)
		(mid 117.97398 -55.378982)
		(end 117.911118 -55.40502)
		(width 0.0889)
		(layer "B.Cu")
		(net "PHY_DPB_TO_SCC_C_33_DP")
	)
	(segment
		(start 117.500146 -56.500014)
		(end 118.000018 -56.000142)
		(width 0.104902)
		(layer "F.Cu")
		(net "PHY_DPB_TO_SCC_C_33_DN")
	)
	(via
		(at 118.000018 -56.000142)
		(size 0.4572)
		(drill 0.2032)
		(layers "F.Cu" "B.Cu")
		(net "PHY_DPB_TO_SCC_C_33_DN")
	)
	(segment
		(start 116.459 -44.879768)
		(end 116.459 -44.5008)
		(width 0.12446)
		(layer "B.Cu")
		(net "PHY_DPB_TO_SCC_C_33_DN")
	)
	(segment
		(start 116.529612 -44.95038)
		(end 116.459 -44.879768)
		(width 0.12446)
		(layer "B.Cu")
		(net "PHY_DPB_TO_SCC_C_33_DN")
	)
	(segment
		(start 117.308376 -50.102262)
		(end 117.0686 -49.862486)
		(width 0.12446)
		(layer "B.Cu")
		(net "PHY_DPB_TO_SCC_C_33_DN")
	)
	(segment
		(start 117.308376 -50.36185)
		(end 117.308376 -50.102262)
		(width 0.12446)
		(layer "B.Cu")
		(net "PHY_DPB_TO_SCC_C_33_DN")
	)
	(segment
		(start 116.529612 -46.506892)
		(end 116.529612 -44.95038)
		(width 0.12446)
		(layer "B.Cu")
		(net "PHY_DPB_TO_SCC_C_33_DN")
	)
	(segment
		(start 117.308376 -50.383948)
		(end 117.308376 -50.36185)
		(width 0.0889)
		(layer "B.Cu")
		(net "PHY_DPB_TO_SCC_C_33_DN")
	)
	(segment
		(start 117.404388 -50.47996)
		(end 117.308376 -50.383948)
		(width 0.0889)
		(layer "B.Cu")
		(net "PHY_DPB_TO_SCC_C_33_DN")
	)
	(segment
		(start 117.404388 -55.240682)
		(end 117.404388 -50.47996)
		(width 0.0889)
		(layer "B.Cu")
		(net "PHY_DPB_TO_SCC_C_33_DN")
	)
	(segment
		(start 117.0686 -47.04588)
		(end 116.529612 -46.506892)
		(width 0.12446)
		(layer "B.Cu")
		(net "PHY_DPB_TO_SCC_C_33_DN")
	)
	(segment
		(start 117.0686 -49.862486)
		(end 117.0686 -47.04588)
		(width 0.12446)
		(layer "B.Cu")
		(net "PHY_DPB_TO_SCC_C_33_DN")
	)
	(segment
		(start 118.000018 -56.000142)
		(end 118.000018 -55.68442)
		(width 0.0889)
		(layer "B.Cu")
		(net "PHY_DPB_TO_SCC_C_33_DN")
	)
	(segment
		(start 117.911118 -55.59552)
		(end 117.761258 -55.59552)
		(width 0.0889)
		(layer "B.Cu")
		(net "PHY_DPB_TO_SCC_C_33_DN")
	)
	(arc
		(start 117.761258 -55.59552)
		(mid 117.624233 -55.568376)
		(end 117.50802 -55.490872)
		(width 0.0889)
		(layer "B.Cu")
		(net "PHY_DPB_TO_SCC_C_33_DN")
	)
	(arc
		(start 117.50802 -55.490872)
		(mid 117.431321 -55.376084)
		(end 117.404388 -55.240682)
		(width 0.0889)
		(layer "B.Cu")
		(net "PHY_DPB_TO_SCC_C_33_DN")
	)
	(arc
		(start 118.000018 -55.68442)
		(mid 117.97398 -55.621558)
		(end 117.911118 -55.59552)
		(width 0.0889)
		(layer "B.Cu")
		(net "PHY_DPB_TO_SCC_C_33_DN")
	)
	(segment
		(start 116.500148 -55.500016)
		(end 117.00002 -55.000144)
		(width 0.104902)
		(layer "F.Cu")
		(net "PHY_DPB_TO_SCC_C_32_DP")
	)
	(via
		(at 117.00002 -55.000144)
		(size 0.4572)
		(drill 0.2032)
		(layers "F.Cu" "B.Cu")
		(net "PHY_DPB_TO_SCC_C_32_DP")
	)
	(segment
		(start 115.4176 -46.047406)
		(end 115.68684 -45.778166)
		(width 0.12446)
		(layer "B.Cu")
		(net "PHY_DPB_TO_SCC_C_32_DP")
	)
	(segment
		(start 115.4176 -44.8056)
		(end 115.4938 -44.7294)
		(width 0.12446)
		(layer "B.Cu")
		(net "PHY_DPB_TO_SCC_C_32_DP")
	)
	(segment
		(start 115.4938 -44.7294)
		(end 115.4938 -44.5008)
		(width 0.12446)
		(layer "B.Cu")
		(net "PHY_DPB_TO_SCC_C_32_DP")
	)
	(segment
		(start 115.68684 -45.778166)
		(end 115.68684 -45.404786)
		(width 0.12446)
		(layer "B.Cu")
		(net "PHY_DPB_TO_SCC_C_32_DP")
	)
	(segment
		(start 116.726462 -50.497486)
		(end 116.726462 -50.163984)
		(width 0.12446)
		(layer "B.Cu")
		(net "PHY_DPB_TO_SCC_C_32_DP")
	)
	(segment
		(start 116.59489 -55.240174)
		(end 116.59489 -50.651156)
		(width 0.0889)
		(layer "B.Cu")
		(net "PHY_DPB_TO_SCC_C_32_DP")
	)
	(segment
		(start 116.235988 -49.67351)
		(end 116.235988 -47.363126)
		(width 0.12446)
		(layer "B.Cu")
		(net "PHY_DPB_TO_SCC_C_32_DP")
	)
	(segment
		(start 115.4176 -45.135546)
		(end 115.4176 -44.8056)
		(width 0.12446)
		(layer "B.Cu")
		(net "PHY_DPB_TO_SCC_C_32_DP")
	)
	(segment
		(start 116.726462 -50.519584)
		(end 116.726462 -50.497486)
		(width 0.0889)
		(layer "B.Cu")
		(net "PHY_DPB_TO_SCC_C_32_DP")
	)
	(segment
		(start 116.235988 -47.363126)
		(end 115.4176 -46.544738)
		(width 0.12446)
		(layer "B.Cu")
		(net "PHY_DPB_TO_SCC_C_32_DP")
	)
	(segment
		(start 116.59489 -50.651156)
		(end 116.726462 -50.519584)
		(width 0.0889)
		(layer "B.Cu")
		(net "PHY_DPB_TO_SCC_C_32_DP")
	)
	(segment
		(start 115.4176 -46.544738)
		(end 115.4176 -46.047406)
		(width 0.12446)
		(layer "B.Cu")
		(net "PHY_DPB_TO_SCC_C_32_DP")
	)
	(segment
		(start 117.00002 -55.000144)
		(end 117.00002 -55.31612)
		(width 0.0889)
		(layer "B.Cu")
		(net "PHY_DPB_TO_SCC_C_32_DP")
	)
	(segment
		(start 115.68684 -45.404786)
		(end 115.4176 -45.135546)
		(width 0.12446)
		(layer "B.Cu")
		(net "PHY_DPB_TO_SCC_C_32_DP")
	)
	(segment
		(start 116.91112 -55.40502)
		(end 116.76126 -55.40502)
		(width 0.0889)
		(layer "B.Cu")
		(net "PHY_DPB_TO_SCC_C_32_DP")
	)
	(segment
		(start 116.726462 -50.163984)
		(end 116.235988 -49.67351)
		(width 0.12446)
		(layer "B.Cu")
		(net "PHY_DPB_TO_SCC_C_32_DP")
	)
	(arc
		(start 116.76126 -55.40502)
		(mid 116.697204 -55.392278)
		(end 116.642896 -55.355998)
		(width 0.0889)
		(layer "B.Cu")
		(net "PHY_DPB_TO_SCC_C_32_DP")
	)
	(arc
		(start 117.00002 -55.31612)
		(mid 116.973982 -55.378982)
		(end 116.91112 -55.40502)
		(width 0.0889)
		(layer "B.Cu")
		(net "PHY_DPB_TO_SCC_C_32_DP")
	)
	(arc
		(start 116.642896 -55.355998)
		(mid 116.607389 -55.302857)
		(end 116.59489 -55.240174)
		(width 0.0889)
		(layer "B.Cu")
		(net "PHY_DPB_TO_SCC_C_32_DP")
	)
	(segment
		(start 116.500148 -56.500014)
		(end 117.00002 -56.000142)
		(width 0.104902)
		(layer "F.Cu")
		(net "PHY_DPB_TO_SCC_C_32_DN")
	)
	(via
		(at 117.00002 -56.000142)
		(size 0.4572)
		(drill 0.2032)
		(layers "F.Cu" "B.Cu")
		(net "PHY_DPB_TO_SCC_C_32_DN")
	)
	(segment
		(start 114.935 -44.704)
		(end 114.935 -44.5008)
		(width 0.12446)
		(layer "B.Cu")
		(net "PHY_DPB_TO_SCC_C_32_DN")
	)
	(segment
		(start 116.320062 -50.497486)
		(end 116.320062 -50.332386)
		(width 0.12446)
		(layer "B.Cu")
		(net "PHY_DPB_TO_SCC_C_32_DN")
	)
	(segment
		(start 116.320062 -50.332386)
		(end 115.829588 -49.841912)
		(width 0.12446)
		(layer "B.Cu")
		(net "PHY_DPB_TO_SCC_C_32_DN")
	)
	(segment
		(start 115.829588 -49.841912)
		(end 115.829588 -47.531528)
		(width 0.12446)
		(layer "B.Cu")
		(net "PHY_DPB_TO_SCC_C_32_DN")
	)
	(segment
		(start 116.320062 -50.519584)
		(end 116.320062 -50.497486)
		(width 0.0889)
		(layer "B.Cu")
		(net "PHY_DPB_TO_SCC_C_32_DN")
	)
	(segment
		(start 116.91112 -55.59552)
		(end 116.76126 -55.59552)
		(width 0.0889)
		(layer "B.Cu")
		(net "PHY_DPB_TO_SCC_C_32_DN")
	)
	(segment
		(start 115.0112 -44.7802)
		(end 114.935 -44.704)
		(width 0.12446)
		(layer "B.Cu")
		(net "PHY_DPB_TO_SCC_C_32_DN")
	)
	(segment
		(start 116.40439 -55.240682)
		(end 116.40439 -50.603912)
		(width 0.0889)
		(layer "B.Cu")
		(net "PHY_DPB_TO_SCC_C_32_DN")
	)
	(segment
		(start 116.40439 -50.603912)
		(end 116.320062 -50.519584)
		(width 0.0889)
		(layer "B.Cu")
		(net "PHY_DPB_TO_SCC_C_32_DN")
	)
	(segment
		(start 115.829588 -47.531528)
		(end 115.0112 -46.71314)
		(width 0.12446)
		(layer "B.Cu")
		(net "PHY_DPB_TO_SCC_C_32_DN")
	)
	(segment
		(start 115.0112 -46.71314)
		(end 115.0112 -44.7802)
		(width 0.12446)
		(layer "B.Cu")
		(net "PHY_DPB_TO_SCC_C_32_DN")
	)
	(segment
		(start 117.00002 -56.000142)
		(end 117.00002 -55.68442)
		(width 0.0889)
		(layer "B.Cu")
		(net "PHY_DPB_TO_SCC_C_32_DN")
	)
	(arc
		(start 116.508022 -55.490872)
		(mid 116.431323 -55.376084)
		(end 116.40439 -55.240682)
		(width 0.0889)
		(layer "B.Cu")
		(net "PHY_DPB_TO_SCC_C_32_DN")
	)
	(arc
		(start 116.76126 -55.59552)
		(mid 116.624235 -55.568376)
		(end 116.508022 -55.490872)
		(width 0.0889)
		(layer "B.Cu")
		(net "PHY_DPB_TO_SCC_C_32_DN")
	)
	(arc
		(start 117.00002 -55.68442)
		(mid 116.973982 -55.621558)
		(end 116.91112 -55.59552)
		(width 0.0889)
		(layer "B.Cu")
		(net "PHY_DPB_TO_SCC_C_32_DN")
	)
	(segment
		(start 126.500128 -64.499998)
		(end 127 -64.000126)
		(width 0.104902)
		(layer "F.Cu")
		(net "PHY_DPB_TO_SCC_C_31_DP")
	)
	(via
		(at 127 -64.000126)
		(size 0.4572)
		(drill 0.2032)
		(layers "F.Cu" "B.Cu")
		(net "PHY_DPB_TO_SCC_C_31_DP")
	)
	(segment
		(start 134.184898 -61.470794)
		(end 132.020564 -63.635128)
		(width 0.12446)
		(layer "B.Cu")
		(net "PHY_DPB_TO_SCC_C_31_DP")
	)
	(segment
		(start 131.544314 -63.635128)
		(end 131.503674 -63.594488)
		(width 0.0889)
		(layer "B.Cu")
		(net "PHY_DPB_TO_SCC_C_31_DP")
	)
	(segment
		(start 126.6952 -64.000126)
		(end 127 -64.000126)
		(width 0.0889)
		(layer "B.Cu")
		(net "PHY_DPB_TO_SCC_C_31_DP")
	)
	(segment
		(start 131.566412 -63.635128)
		(end 131.544314 -63.635128)
		(width 0.0889)
		(layer "B.Cu")
		(net "PHY_DPB_TO_SCC_C_31_DP")
	)
	(segment
		(start 134.184898 -59.18708)
		(end 134.184898 -61.470794)
		(width 0.12446)
		(layer "B.Cu")
		(net "PHY_DPB_TO_SCC_C_31_DP")
	)
	(segment
		(start 126.595124 -63.749936)
		(end 126.595124 -63.90005)
		(width 0.0889)
		(layer "B.Cu")
		(net "PHY_DPB_TO_SCC_C_31_DP")
	)
	(segment
		(start 132.020564 -63.635128)
		(end 131.566412 -63.635128)
		(width 0.12446)
		(layer "B.Cu")
		(net "PHY_DPB_TO_SCC_C_31_DP")
	)
	(segment
		(start 135.405622 -57.966356)
		(end 134.184898 -59.18708)
		(width 0.12446)
		(layer "B.Cu")
		(net "PHY_DPB_TO_SCC_C_31_DP")
	)
	(segment
		(start 131.503674 -63.594488)
		(end 126.750572 -63.594488)
		(width 0.0889)
		(layer "B.Cu")
		(net "PHY_DPB_TO_SCC_C_31_DP")
	)
	(segment
		(start 135.405622 -56.659018)
		(end 135.405622 -57.966356)
		(width 0.12446)
		(layer "B.Cu")
		(net "PHY_DPB_TO_SCC_C_31_DP")
	)
	(arc
		(start 126.595124 -63.90005)
		(mid 126.624436 -63.970814)
		(end 126.6952 -64.000126)
		(width 0.0889)
		(layer "B.Cu")
		(net "PHY_DPB_TO_SCC_C_31_DP")
	)
	(arc
		(start 126.750572 -63.594488)
		(mid 126.640654 -63.640018)
		(end 126.595124 -63.749936)
		(width 0.0889)
		(layer "B.Cu")
		(net "PHY_DPB_TO_SCC_C_31_DP")
	)
	(segment
		(start 125.50013 -64.499998)
		(end 126.000002 -64.000126)
		(width 0.104902)
		(layer "F.Cu")
		(net "PHY_DPB_TO_SCC_C_31_DN")
	)
	(via
		(at 126.000002 -64.000126)
		(size 0.4572)
		(drill 0.2032)
		(layers "F.Cu" "B.Cu")
		(net "PHY_DPB_TO_SCC_C_31_DN")
	)
	(segment
		(start 131.852162 -63.228728)
		(end 131.566412 -63.228728)
		(width 0.12446)
		(layer "B.Cu")
		(net "PHY_DPB_TO_SCC_C_31_DN")
	)
	(segment
		(start 131.566412 -63.228728)
		(end 131.544314 -63.228728)
		(width 0.0889)
		(layer "B.Cu")
		(net "PHY_DPB_TO_SCC_C_31_DN")
	)
	(segment
		(start 134.999222 -57.797954)
		(end 133.778498 -59.018678)
		(width 0.12446)
		(layer "B.Cu")
		(net "PHY_DPB_TO_SCC_C_31_DN")
	)
	(segment
		(start 133.778498 -61.302392)
		(end 131.852162 -63.228728)
		(width 0.12446)
		(layer "B.Cu")
		(net "PHY_DPB_TO_SCC_C_31_DN")
	)
	(segment
		(start 133.778498 -60.929012)
		(end 133.778498 -61.302392)
		(width 0.12446)
		(layer "B.Cu")
		(net "PHY_DPB_TO_SCC_C_31_DN")
	)
	(segment
		(start 134.999222 -56.914542)
		(end 134.999222 -57.797954)
		(width 0.12446)
		(layer "B.Cu")
		(net "PHY_DPB_TO_SCC_C_31_DN")
	)
	(segment
		(start 131.544314 -63.228728)
		(end 131.369054 -63.403988)
		(width 0.0889)
		(layer "B.Cu")
		(net "PHY_DPB_TO_SCC_C_31_DN")
	)
	(segment
		(start 134.846822 -56.659018)
		(end 134.846822 -56.762142)
		(width 0.12446)
		(layer "B.Cu")
		(net "PHY_DPB_TO_SCC_C_31_DN")
	)
	(segment
		(start 126.304802 -64.000126)
		(end 126.000002 -64.000126)
		(width 0.0889)
		(layer "B.Cu")
		(net "PHY_DPB_TO_SCC_C_31_DN")
	)
	(segment
		(start 133.509258 -60.659772)
		(end 133.778498 -60.929012)
		(width 0.12446)
		(layer "B.Cu")
		(net "PHY_DPB_TO_SCC_C_31_DN")
	)
	(segment
		(start 133.778498 -59.018678)
		(end 133.778498 -60.017152)
		(width 0.12446)
		(layer "B.Cu")
		(net "PHY_DPB_TO_SCC_C_31_DN")
	)
	(segment
		(start 126.404624 -63.749936)
		(end 126.404624 -63.900304)
		(width 0.0889)
		(layer "B.Cu")
		(net "PHY_DPB_TO_SCC_C_31_DN")
	)
	(segment
		(start 134.846822 -56.762142)
		(end 134.999222 -56.914542)
		(width 0.12446)
		(layer "B.Cu")
		(net "PHY_DPB_TO_SCC_C_31_DN")
	)
	(segment
		(start 131.369054 -63.403988)
		(end 126.750572 -63.403988)
		(width 0.0889)
		(layer "B.Cu")
		(net "PHY_DPB_TO_SCC_C_31_DN")
	)
	(segment
		(start 133.778498 -60.017152)
		(end 133.509258 -60.286392)
		(width 0.12446)
		(layer "B.Cu")
		(net "PHY_DPB_TO_SCC_C_31_DN")
	)
	(segment
		(start 133.509258 -60.286392)
		(end 133.509258 -60.659772)
		(width 0.12446)
		(layer "B.Cu")
		(net "PHY_DPB_TO_SCC_C_31_DN")
	)
	(arc
		(start 126.750572 -63.403988)
		(mid 126.50595 -63.505314)
		(end 126.404624 -63.749936)
		(width 0.0889)
		(layer "B.Cu")
		(net "PHY_DPB_TO_SCC_C_31_DN")
	)
	(arc
		(start 126.404624 -63.900304)
		(mid 126.375387 -63.970889)
		(end 126.304802 -64.000126)
		(width 0.0889)
		(layer "B.Cu")
		(net "PHY_DPB_TO_SCC_C_31_DN")
	)
	(segment
		(start 126.500128 -63.5)
		(end 127 -63.000128)
		(width 0.104902)
		(layer "F.Cu")
		(net "PHY_DPB_TO_SCC_C_30_DP")
	)
	(via
		(at 127 -63.000128)
		(size 0.4572)
		(drill 0.2032)
		(layers "F.Cu" "B.Cu")
		(net "PHY_DPB_TO_SCC_C_30_DP")
	)
	(segment
		(start 133.60781 -57.741058)
		(end 134.460996 -53.727604)
		(width 0.12446)
		(layer "B.Cu")
		(net "PHY_DPB_TO_SCC_C_30_DP")
	)
	(segment
		(start 131.99237 -62.454028)
		(end 133.010402 -61.435996)
		(width 0.12446)
		(layer "B.Cu")
		(net "PHY_DPB_TO_SCC_C_30_DP")
	)
	(segment
		(start 133.010402 -61.435996)
		(end 133.010402 -58.659268)
		(width 0.12446)
		(layer "B.Cu")
		(net "PHY_DPB_TO_SCC_C_30_DP")
	)
	(segment
		(start 134.267956 -47.97806)
		(end 133.739128 -45.4914)
		(width 0.12446)
		(layer "B.Cu")
		(net "PHY_DPB_TO_SCC_C_30_DP")
	)
	(segment
		(start 133.8326 -45.105828)
		(end 133.8326 -44.6786)
		(width 0.12446)
		(layer "B.Cu")
		(net "PHY_DPB_TO_SCC_C_30_DP")
	)
	(segment
		(start 133.753352 -50.39868)
		(end 134.267956 -47.97806)
		(width 0.12446)
		(layer "B.Cu")
		(net "PHY_DPB_TO_SCC_C_30_DP")
	)
	(segment
		(start 133.010402 -58.659268)
		(end 133.60781 -57.741058)
		(width 0.12446)
		(layer "B.Cu")
		(net "PHY_DPB_TO_SCC_C_30_DP")
	)
	(segment
		(start 133.739128 -45.1993)
		(end 133.8326 -45.105828)
		(width 0.12446)
		(layer "B.Cu")
		(net "PHY_DPB_TO_SCC_C_30_DP")
	)
	(segment
		(start 131.700016 -62.593474)
		(end 131.823968 -62.469522)
		(width 0.0889)
		(layer "B.Cu")
		(net "PHY_DPB_TO_SCC_C_30_DP")
	)
	(segment
		(start 126.595124 -62.900052)
		(end 126.595124 -62.749938)
		(width 0.0889)
		(layer "B.Cu")
		(net "PHY_DPB_TO_SCC_C_30_DP")
	)
	(segment
		(start 134.460996 -53.727604)
		(end 133.753352 -50.39868)
		(width 0.12446)
		(layer "B.Cu")
		(net "PHY_DPB_TO_SCC_C_30_DP")
	)
	(segment
		(start 131.823968 -62.469522)
		(end 131.976876 -62.469522)
		(width 0.0889)
		(layer "B.Cu")
		(net "PHY_DPB_TO_SCC_C_30_DP")
	)
	(segment
		(start 127 -63.000128)
		(end 126.6952 -63.000128)
		(width 0.0889)
		(layer "B.Cu")
		(net "PHY_DPB_TO_SCC_C_30_DP")
	)
	(segment
		(start 126.751588 -62.593474)
		(end 131.700016 -62.593474)
		(width 0.0889)
		(layer "B.Cu")
		(net "PHY_DPB_TO_SCC_C_30_DP")
	)
	(segment
		(start 131.976876 -62.469522)
		(end 131.99237 -62.454028)
		(width 0.0889)
		(layer "B.Cu")
		(net "PHY_DPB_TO_SCC_C_30_DP")
	)
	(segment
		(start 133.739128 -45.4914)
		(end 133.739128 -45.1993)
		(width 0.12446)
		(layer "B.Cu")
		(net "PHY_DPB_TO_SCC_C_30_DP")
	)
	(arc
		(start 126.6952 -63.000128)
		(mid 126.624436 -62.970816)
		(end 126.595124 -62.900052)
		(width 0.0889)
		(layer "B.Cu")
		(net "PHY_DPB_TO_SCC_C_30_DP")
	)
	(arc
		(start 126.595124 -62.749938)
		(mid 126.640951 -62.639301)
		(end 126.751588 -62.593474)
		(width 0.0889)
		(layer "B.Cu")
		(net "PHY_DPB_TO_SCC_C_30_DP")
	)
	(segment
		(start 125.50013 -63.5)
		(end 126.000002 -63.000128)
		(width 0.104902)
		(layer "F.Cu")
		(net "PHY_DPB_TO_SCC_C_30_DN")
	)
	(via
		(at 126.000002 -63.000128)
		(size 0.4572)
		(drill 0.2032)
		(layers "F.Cu" "B.Cu")
		(net "PHY_DPB_TO_SCC_C_30_DN")
	)
	(segment
		(start 126.751588 -62.402974)
		(end 131.621022 -62.402974)
		(width 0.0889)
		(layer "B.Cu")
		(net "PHY_DPB_TO_SCC_C_30_DN")
	)
	(segment
		(start 126.404624 -62.900306)
		(end 126.404624 -62.749938)
		(width 0.0889)
		(layer "B.Cu")
		(net "PHY_DPB_TO_SCC_C_30_DN")
	)
	(segment
		(start 126.000002 -63.000128)
		(end 126.304802 -63.000128)
		(width 0.0889)
		(layer "B.Cu")
		(net "PHY_DPB_TO_SCC_C_30_DN")
	)
	(segment
		(start 133.332728 -45.534326)
		(end 133.332728 -45.131228)
		(width 0.12446)
		(layer "B.Cu")
		(net "PHY_DPB_TO_SCC_C_30_DN")
	)
	(segment
		(start 133.608064 -49.126902)
		(end 133.4008 -48.807624)
		(width 0.12446)
		(layer "B.Cu")
		(net "PHY_DPB_TO_SCC_C_30_DN")
	)
	(segment
		(start 131.621022 -62.402974)
		(end 131.689348 -62.334648)
		(width 0.0889)
		(layer "B.Cu")
		(net "PHY_DPB_TO_SCC_C_30_DN")
	)
	(segment
		(start 133.4008 -48.807624)
		(end 133.47827 -48.442372)
		(width 0.12446)
		(layer "B.Cu")
		(net "PHY_DPB_TO_SCC_C_30_DN")
	)
	(segment
		(start 133.47827 -48.442372)
		(end 133.797548 -48.235108)
		(width 0.12446)
		(layer "B.Cu")
		(net "PHY_DPB_TO_SCC_C_30_DN")
	)
	(segment
		(start 133.332728 -45.131228)
		(end 133.2738 -45.0723)
		(width 0.12446)
		(layer "B.Cu")
		(net "PHY_DPB_TO_SCC_C_30_DN")
	)
	(segment
		(start 133.852412 -47.97806)
		(end 133.332728 -45.534326)
		(width 0.12446)
		(layer "B.Cu")
		(net "PHY_DPB_TO_SCC_C_30_DN")
	)
	(segment
		(start 132.604002 -58.538618)
		(end 133.225794 -57.582562)
		(width 0.12446)
		(layer "B.Cu")
		(net "PHY_DPB_TO_SCC_C_30_DN")
	)
	(segment
		(start 133.337808 -50.39868)
		(end 133.608064 -49.126902)
		(width 0.12446)
		(layer "B.Cu")
		(net "PHY_DPB_TO_SCC_C_30_DN")
	)
	(segment
		(start 133.225794 -57.582562)
		(end 134.045452 -53.727604)
		(width 0.12446)
		(layer "B.Cu")
		(net "PHY_DPB_TO_SCC_C_30_DN")
	)
	(segment
		(start 131.704842 -62.166754)
		(end 132.604002 -61.267594)
		(width 0.12446)
		(layer "B.Cu")
		(net "PHY_DPB_TO_SCC_C_30_DN")
	)
	(segment
		(start 133.797548 -48.235108)
		(end 133.852412 -47.97806)
		(width 0.12446)
		(layer "B.Cu")
		(net "PHY_DPB_TO_SCC_C_30_DN")
	)
	(segment
		(start 132.604002 -61.267594)
		(end 132.604002 -58.538618)
		(width 0.12446)
		(layer "B.Cu")
		(net "PHY_DPB_TO_SCC_C_30_DN")
	)
	(segment
		(start 134.045452 -53.727604)
		(end 133.337808 -50.39868)
		(width 0.12446)
		(layer "B.Cu")
		(net "PHY_DPB_TO_SCC_C_30_DN")
	)
	(segment
		(start 133.2738 -45.0723)
		(end 133.2738 -44.6786)
		(width 0.12446)
		(layer "B.Cu")
		(net "PHY_DPB_TO_SCC_C_30_DN")
	)
	(segment
		(start 131.689348 -62.334648)
		(end 131.689348 -62.182248)
		(width 0.0889)
		(layer "B.Cu")
		(net "PHY_DPB_TO_SCC_C_30_DN")
	)
	(segment
		(start 131.689348 -62.182248)
		(end 131.704842 -62.166754)
		(width 0.0889)
		(layer "B.Cu")
		(net "PHY_DPB_TO_SCC_C_30_DN")
	)
	(arc
		(start 126.404624 -62.749938)
		(mid 126.506247 -62.504597)
		(end 126.751588 -62.402974)
		(width 0.0889)
		(layer "B.Cu")
		(net "PHY_DPB_TO_SCC_C_30_DN")
	)
	(arc
		(start 126.304802 -63.000128)
		(mid 126.375387 -62.970891)
		(end 126.404624 -62.900306)
		(width 0.0889)
		(layer "B.Cu")
		(net "PHY_DPB_TO_SCC_C_30_DN")
	)
	(segment
		(start 126.500128 -68.500244)
		(end 127 -69.000116)
		(width 0.104902)
		(layer "F.Cu")
		(net "PHY_DPB_TO_SCC_C_3_DP")
	)
	(via
		(at 127 -69.000116)
		(size 0.4572)
		(drill 0.2032)
		(layers "F.Cu" "B.Cu")
		(net "PHY_DPB_TO_SCC_C_3_DP")
	)
	(segment
		(start 131.319524 -68.702682)
		(end 131.211574 -68.594732)
		(width 0.0889)
		(layer "B.Cu")
		(net "PHY_DPB_TO_SCC_C_3_DP")
	)
	(segment
		(start 133.42112 -68.267072)
		(end 133.04774 -68.267072)
		(width 0.12446)
		(layer "B.Cu")
		(net "PHY_DPB_TO_SCC_C_3_DP")
	)
	(segment
		(start 126.6952 -69.000116)
		(end 127 -69.000116)
		(width 0.0889)
		(layer "B.Cu")
		(net "PHY_DPB_TO_SCC_C_3_DP")
	)
	(segment
		(start 136.149334 -67.987672)
		(end 133.70052 -67.987672)
		(width 0.12446)
		(layer "B.Cu")
		(net "PHY_DPB_TO_SCC_C_3_DP")
	)
	(segment
		(start 133.70052 -67.987672)
		(end 133.42112 -68.267072)
		(width 0.12446)
		(layer "B.Cu")
		(net "PHY_DPB_TO_SCC_C_3_DP")
	)
	(segment
		(start 132.76834 -67.987672)
		(end 132.39496 -67.987672)
		(width 0.12446)
		(layer "B.Cu")
		(net "PHY_DPB_TO_SCC_C_3_DP")
	)
	(segment
		(start 136.397746 -68.236084)
		(end 136.149334 -67.987672)
		(width 0.12446)
		(layer "B.Cu")
		(net "PHY_DPB_TO_SCC_C_3_DP")
	)
	(segment
		(start 137.1854 -68.3514)
		(end 136.919716 -68.3514)
		(width 0.12446)
		(layer "B.Cu")
		(net "PHY_DPB_TO_SCC_C_3_DP")
	)
	(segment
		(start 132.39496 -67.987672)
		(end 131.67995 -68.702682)
		(width 0.12446)
		(layer "B.Cu")
		(net "PHY_DPB_TO_SCC_C_3_DP")
	)
	(segment
		(start 133.04774 -68.267072)
		(end 132.76834 -67.987672)
		(width 0.12446)
		(layer "B.Cu")
		(net "PHY_DPB_TO_SCC_C_3_DP")
	)
	(segment
		(start 136.919716 -68.3514)
		(end 136.8044 -68.236084)
		(width 0.12446)
		(layer "B.Cu")
		(net "PHY_DPB_TO_SCC_C_3_DP")
	)
	(segment
		(start 136.8044 -68.236084)
		(end 136.397746 -68.236084)
		(width 0.12446)
		(layer "B.Cu")
		(net "PHY_DPB_TO_SCC_C_3_DP")
	)
	(segment
		(start 131.341622 -68.702682)
		(end 131.319524 -68.702682)
		(width 0.0889)
		(layer "B.Cu")
		(net "PHY_DPB_TO_SCC_C_3_DP")
	)
	(segment
		(start 126.595124 -68.749926)
		(end 126.595124 -68.90004)
		(width 0.0889)
		(layer "B.Cu")
		(net "PHY_DPB_TO_SCC_C_3_DP")
	)
	(segment
		(start 131.211574 -68.594732)
		(end 126.750318 -68.594732)
		(width 0.0889)
		(layer "B.Cu")
		(net "PHY_DPB_TO_SCC_C_3_DP")
	)
	(segment
		(start 131.67995 -68.702682)
		(end 131.341622 -68.702682)
		(width 0.12446)
		(layer "B.Cu")
		(net "PHY_DPB_TO_SCC_C_3_DP")
	)
	(arc
		(start 126.595124 -68.90004)
		(mid 126.624436 -68.970804)
		(end 126.6952 -69.000116)
		(width 0.0889)
		(layer "B.Cu")
		(net "PHY_DPB_TO_SCC_C_3_DP")
	)
	(arc
		(start 126.750318 -68.594732)
		(mid 126.640579 -68.640187)
		(end 126.595124 -68.749926)
		(width 0.0889)
		(layer "B.Cu")
		(net "PHY_DPB_TO_SCC_C_3_DP")
	)
	(segment
		(start 125.50013 -68.500244)
		(end 126.000002 -69.000116)
		(width 0.104902)
		(layer "F.Cu")
		(net "PHY_DPB_TO_SCC_C_3_DN")
	)
	(via
		(at 126.000002 -69.000116)
		(size 0.4572)
		(drill 0.2032)
		(layers "F.Cu" "B.Cu")
		(net "PHY_DPB_TO_SCC_C_3_DN")
	)
	(segment
		(start 132.226558 -67.581272)
		(end 131.511548 -68.296282)
		(width 0.12446)
		(layer "B.Cu")
		(net "PHY_DPB_TO_SCC_C_3_DN")
	)
	(segment
		(start 131.319524 -68.296282)
		(end 131.211574 -68.404232)
		(width 0.0889)
		(layer "B.Cu")
		(net "PHY_DPB_TO_SCC_C_3_DN")
	)
	(segment
		(start 131.341622 -68.296282)
		(end 131.319524 -68.296282)
		(width 0.0889)
		(layer "B.Cu")
		(net "PHY_DPB_TO_SCC_C_3_DN")
	)
	(segment
		(start 136.566148 -67.829684)
		(end 136.317736 -67.581272)
		(width 0.12446)
		(layer "B.Cu")
		(net "PHY_DPB_TO_SCC_C_3_DN")
	)
	(segment
		(start 126.304802 -69.000116)
		(end 126.000002 -69.000116)
		(width 0.0889)
		(layer "B.Cu")
		(net "PHY_DPB_TO_SCC_C_3_DN")
	)
	(segment
		(start 136.806432 -67.7926)
		(end 136.769348 -67.829684)
		(width 0.12446)
		(layer "B.Cu")
		(net "PHY_DPB_TO_SCC_C_3_DN")
	)
	(segment
		(start 137.1854 -67.7926)
		(end 136.806432 -67.7926)
		(width 0.12446)
		(layer "B.Cu")
		(net "PHY_DPB_TO_SCC_C_3_DN")
	)
	(segment
		(start 131.211574 -68.404232)
		(end 126.750318 -68.404232)
		(width 0.0889)
		(layer "B.Cu")
		(net "PHY_DPB_TO_SCC_C_3_DN")
	)
	(segment
		(start 126.404624 -68.749926)
		(end 126.404624 -68.900294)
		(width 0.0889)
		(layer "B.Cu")
		(net "PHY_DPB_TO_SCC_C_3_DN")
	)
	(segment
		(start 136.769348 -67.829684)
		(end 136.566148 -67.829684)
		(width 0.12446)
		(layer "B.Cu")
		(net "PHY_DPB_TO_SCC_C_3_DN")
	)
	(segment
		(start 136.317736 -67.581272)
		(end 132.226558 -67.581272)
		(width 0.12446)
		(layer "B.Cu")
		(net "PHY_DPB_TO_SCC_C_3_DN")
	)
	(segment
		(start 131.511548 -68.296282)
		(end 131.341622 -68.296282)
		(width 0.12446)
		(layer "B.Cu")
		(net "PHY_DPB_TO_SCC_C_3_DN")
	)
	(arc
		(start 126.750318 -68.404232)
		(mid 126.505875 -68.505483)
		(end 126.404624 -68.749926)
		(width 0.0889)
		(layer "B.Cu")
		(net "PHY_DPB_TO_SCC_C_3_DN")
	)
	(arc
		(start 126.404624 -68.900294)
		(mid 126.375387 -68.970879)
		(end 126.304802 -69.000116)
		(width 0.0889)
		(layer "B.Cu")
		(net "PHY_DPB_TO_SCC_C_3_DN")
	)
	(segment
		(start 126.500128 -62.500002)
		(end 127 -62.00013)
		(width 0.104902)
		(layer "F.Cu")
		(net "PHY_DPB_TO_SCC_C_29_DP")
	)
	(via
		(at 127 -62.00013)
		(size 0.4572)
		(drill 0.2032)
		(layers "F.Cu" "B.Cu")
		(net "PHY_DPB_TO_SCC_C_29_DP")
	)
	(segment
		(start 132.642102 -50.291746)
		(end 131.05384 -46.550072)
		(width 0.12446)
		(layer "B.Cu")
		(net "PHY_DPB_TO_SCC_C_29_DP")
	)
	(segment
		(start 131.379214 -61.593984)
		(end 131.602734 -61.370464)
		(width 0.0889)
		(layer "B.Cu")
		(net "PHY_DPB_TO_SCC_C_29_DP")
	)
	(segment
		(start 131.748022 -61.370464)
		(end 131.763516 -61.35497)
		(width 0.0889)
		(layer "B.Cu")
		(net "PHY_DPB_TO_SCC_C_29_DP")
	)
	(segment
		(start 126.595124 -61.900054)
		(end 126.595124 -61.74994)
		(width 0.0889)
		(layer "B.Cu")
		(net "PHY_DPB_TO_SCC_C_29_DP")
	)
	(segment
		(start 126.75108 -61.593984)
		(end 131.379214 -61.593984)
		(width 0.0889)
		(layer "B.Cu")
		(net "PHY_DPB_TO_SCC_C_29_DP")
	)
	(segment
		(start 131.05384 -46.550072)
		(end 131.284472 -45.463968)
		(width 0.12446)
		(layer "B.Cu")
		(net "PHY_DPB_TO_SCC_C_29_DP")
	)
	(segment
		(start 132.794502 -57.074308)
		(end 133.439408 -54.04231)
		(width 0.12446)
		(layer "B.Cu")
		(net "PHY_DPB_TO_SCC_C_29_DP")
	)
	(segment
		(start 132.12572 -58.104278)
		(end 132.794502 -57.074308)
		(width 0.12446)
		(layer "B.Cu")
		(net "PHY_DPB_TO_SCC_C_29_DP")
	)
	(segment
		(start 131.763516 -61.35497)
		(end 132.12572 -60.992766)
		(width 0.12446)
		(layer "B.Cu")
		(net "PHY_DPB_TO_SCC_C_29_DP")
	)
	(segment
		(start 131.284472 -45.463968)
		(end 131.284472 -45.021754)
		(width 0.12446)
		(layer "B.Cu")
		(net "PHY_DPB_TO_SCC_C_29_DP")
	)
	(segment
		(start 132.12572 -60.992766)
		(end 132.12572 -58.104278)
		(width 0.12446)
		(layer "B.Cu")
		(net "PHY_DPB_TO_SCC_C_29_DP")
	)
	(segment
		(start 133.439408 -54.04231)
		(end 132.642102 -50.291746)
		(width 0.12446)
		(layer "B.Cu")
		(net "PHY_DPB_TO_SCC_C_29_DP")
	)
	(segment
		(start 127 -62.00013)
		(end 126.6952 -62.00013)
		(width 0.0889)
		(layer "B.Cu")
		(net "PHY_DPB_TO_SCC_C_29_DP")
	)
	(segment
		(start 131.284472 -45.021754)
		(end 131.38277 -44.923456)
		(width 0.12446)
		(layer "B.Cu")
		(net "PHY_DPB_TO_SCC_C_29_DP")
	)
	(segment
		(start 131.38277 -44.923456)
		(end 131.38277 -44.658788)
		(width 0.12446)
		(layer "B.Cu")
		(net "PHY_DPB_TO_SCC_C_29_DP")
	)
	(segment
		(start 131.602734 -61.370464)
		(end 131.748022 -61.370464)
		(width 0.0889)
		(layer "B.Cu")
		(net "PHY_DPB_TO_SCC_C_29_DP")
	)
	(arc
		(start 126.595124 -61.74994)
		(mid 126.640802 -61.639662)
		(end 126.75108 -61.593984)
		(width 0.0889)
		(layer "B.Cu")
		(net "PHY_DPB_TO_SCC_C_29_DP")
	)
	(arc
		(start 126.6952 -62.00013)
		(mid 126.624436 -61.970818)
		(end 126.595124 -61.900054)
		(width 0.0889)
		(layer "B.Cu")
		(net "PHY_DPB_TO_SCC_C_29_DP")
	)
	(segment
		(start 125.50013 -62.500002)
		(end 126.000002 -62.00013)
		(width 0.104902)
		(layer "F.Cu")
		(net "PHY_DPB_TO_SCC_C_29_DN")
	)
	(via
		(at 126.000002 -62.00013)
		(size 0.4572)
		(drill 0.2032)
		(layers "F.Cu" "B.Cu")
		(net "PHY_DPB_TO_SCC_C_29_DN")
	)
	(segment
		(start 131.71932 -57.983882)
		(end 131.71932 -60.824364)
		(width 0.12446)
		(layer "B.Cu")
		(net "PHY_DPB_TO_SCC_C_29_DN")
	)
	(segment
		(start 130.82397 -44.89577)
		(end 130.878072 -44.949872)
		(width 0.12446)
		(layer "B.Cu")
		(net "PHY_DPB_TO_SCC_C_29_DN")
	)
	(segment
		(start 130.878072 -44.949872)
		(end 130.878072 -45.421042)
		(width 0.12446)
		(layer "B.Cu")
		(net "PHY_DPB_TO_SCC_C_29_DN")
	)
	(segment
		(start 131.460494 -61.24321)
		(end 131.30022 -61.403484)
		(width 0.0889)
		(layer "B.Cu")
		(net "PHY_DPB_TO_SCC_C_29_DN")
	)
	(segment
		(start 126.404624 -61.74994)
		(end 126.404624 -61.900308)
		(width 0.0889)
		(layer "B.Cu")
		(net "PHY_DPB_TO_SCC_C_29_DN")
	)
	(segment
		(start 126.304802 -62.00013)
		(end 126.000002 -62.00013)
		(width 0.0889)
		(layer "B.Cu")
		(net "PHY_DPB_TO_SCC_C_29_DN")
	)
	(segment
		(start 132.412486 -56.916066)
		(end 131.71932 -57.983882)
		(width 0.12446)
		(layer "B.Cu")
		(net "PHY_DPB_TO_SCC_C_29_DN")
	)
	(segment
		(start 131.475988 -61.067696)
		(end 131.460494 -61.08319)
		(width 0.0889)
		(layer "B.Cu")
		(net "PHY_DPB_TO_SCC_C_29_DN")
	)
	(segment
		(start 131.30022 -61.403484)
		(end 126.75108 -61.403484)
		(width 0.0889)
		(layer "B.Cu")
		(net "PHY_DPB_TO_SCC_C_29_DN")
	)
	(segment
		(start 131.649724 -49.68367)
		(end 132.002784 -49.826164)
		(width 0.12446)
		(layer "B.Cu")
		(net "PHY_DPB_TO_SCC_C_29_DN")
	)
	(segment
		(start 130.62966 -46.590966)
		(end 131.646422 -48.986948)
		(width 0.12446)
		(layer "B.Cu")
		(net "PHY_DPB_TO_SCC_C_29_DN")
	)
	(segment
		(start 131.646422 -48.986948)
		(end 131.503928 -49.339754)
		(width 0.12446)
		(layer "B.Cu")
		(net "PHY_DPB_TO_SCC_C_29_DN")
	)
	(segment
		(start 131.71932 -60.824364)
		(end 131.475988 -61.067696)
		(width 0.12446)
		(layer "B.Cu")
		(net "PHY_DPB_TO_SCC_C_29_DN")
	)
	(segment
		(start 131.503928 -49.339754)
		(end 131.649724 -49.68367)
		(width 0.12446)
		(layer "B.Cu")
		(net "PHY_DPB_TO_SCC_C_29_DN")
	)
	(segment
		(start 131.460494 -61.08319)
		(end 131.460494 -61.24321)
		(width 0.0889)
		(layer "B.Cu")
		(net "PHY_DPB_TO_SCC_C_29_DN")
	)
	(segment
		(start 130.82397 -44.658788)
		(end 130.82397 -44.89577)
		(width 0.12446)
		(layer "B.Cu")
		(net "PHY_DPB_TO_SCC_C_29_DN")
	)
	(segment
		(start 132.252466 -50.414682)
		(end 133.023864 -54.04231)
		(width 0.12446)
		(layer "B.Cu")
		(net "PHY_DPB_TO_SCC_C_29_DN")
	)
	(segment
		(start 130.878072 -45.421042)
		(end 130.62966 -46.590966)
		(width 0.12446)
		(layer "B.Cu")
		(net "PHY_DPB_TO_SCC_C_29_DN")
	)
	(segment
		(start 132.002784 -49.826164)
		(end 132.252466 -50.414682)
		(width 0.12446)
		(layer "B.Cu")
		(net "PHY_DPB_TO_SCC_C_29_DN")
	)
	(segment
		(start 133.023864 -54.04231)
		(end 132.412486 -56.916066)
		(width 0.12446)
		(layer "B.Cu")
		(net "PHY_DPB_TO_SCC_C_29_DN")
	)
	(arc
		(start 126.404624 -61.900308)
		(mid 126.375387 -61.970893)
		(end 126.304802 -62.00013)
		(width 0.0889)
		(layer "B.Cu")
		(net "PHY_DPB_TO_SCC_C_29_DN")
	)
	(arc
		(start 126.75108 -61.403484)
		(mid 126.506099 -61.504959)
		(end 126.404624 -61.74994)
		(width 0.0889)
		(layer "B.Cu")
		(net "PHY_DPB_TO_SCC_C_29_DN")
	)
	(segment
		(start 126.500128 -61.500004)
		(end 127 -61.000132)
		(width 0.104902)
		(layer "F.Cu")
		(net "PHY_DPB_TO_SCC_C_28_DP")
	)
	(via
		(at 127 -61.000132)
		(size 0.4572)
		(drill 0.2032)
		(layers "F.Cu" "B.Cu")
		(net "PHY_DPB_TO_SCC_C_28_DP")
	)
	(segment
		(start 128.740154 -43.483276)
		(end 128.192784 -46.059344)
		(width 0.12446)
		(layer "B.Cu")
		(net "PHY_DPB_TO_SCC_C_28_DP")
	)
	(segment
		(start 130.416808 -60.593732)
		(end 126.751334 -60.593732)
		(width 0.0889)
		(layer "B.Cu")
		(net "PHY_DPB_TO_SCC_C_28_DP")
	)
	(segment
		(start 130.77825 -59.388248)
		(end 130.77825 -60.232036)
		(width 0.0889)
		(layer "B.Cu")
		(net "PHY_DPB_TO_SCC_C_28_DP")
	)
	(segment
		(start 128.8034 -41.148)
		(end 128.8034 -41.487344)
		(width 0.12446)
		(layer "B.Cu")
		(net "PHY_DPB_TO_SCC_C_28_DP")
	)
	(segment
		(start 130.597402 -60.413138)
		(end 130.416808 -60.593732)
		(width 0.0889)
		(layer "B.Cu")
		(net "PHY_DPB_TO_SCC_C_28_DP")
	)
	(segment
		(start 128.740154 -41.55059)
		(end 128.740154 -43.483276)
		(width 0.12446)
		(layer "B.Cu")
		(net "PHY_DPB_TO_SCC_C_28_DP")
	)
	(segment
		(start 128.61671 -48.05426)
		(end 129.230882 -49.000664)
		(width 0.12446)
		(layer "B.Cu")
		(net "PHY_DPB_TO_SCC_C_28_DP")
	)
	(segment
		(start 129.230882 -49.000664)
		(end 130.600196 -49.889918)
		(width 0.12446)
		(layer "B.Cu")
		(net "PHY_DPB_TO_SCC_C_28_DP")
	)
	(segment
		(start 130.8862 -59.2582)
		(end 130.8862 -59.280298)
		(width 0.0889)
		(layer "B.Cu")
		(net "PHY_DPB_TO_SCC_C_28_DP")
	)
	(segment
		(start 126.6952 -61.000132)
		(end 127 -61.000132)
		(width 0.0889)
		(layer "B.Cu")
		(net "PHY_DPB_TO_SCC_C_28_DP")
	)
	(segment
		(start 131.711446 -56.44261)
		(end 130.8862 -57.267602)
		(width 0.12446)
		(layer "B.Cu")
		(net "PHY_DPB_TO_SCC_C_28_DP")
	)
	(segment
		(start 130.8862 -57.267602)
		(end 130.8862 -59.2582)
		(width 0.12446)
		(layer "B.Cu")
		(net "PHY_DPB_TO_SCC_C_28_DP")
	)
	(segment
		(start 126.595124 -60.749942)
		(end 126.595124 -60.900056)
		(width 0.0889)
		(layer "B.Cu")
		(net "PHY_DPB_TO_SCC_C_28_DP")
	)
	(segment
		(start 132.169408 -52.696364)
		(end 132.169662 -52.696618)
		(width 0.12446)
		(layer "B.Cu")
		(net "PHY_DPB_TO_SCC_C_28_DP")
	)
	(segment
		(start 132.473954 -54.128924)
		(end 132.119878 -55.79618)
		(width 0.12446)
		(layer "B.Cu")
		(net "PHY_DPB_TO_SCC_C_28_DP")
	)
	(segment
		(start 128.192784 -46.059344)
		(end 128.61671 -48.05426)
		(width 0.12446)
		(layer "B.Cu")
		(net "PHY_DPB_TO_SCC_C_28_DP")
	)
	(segment
		(start 132.045964 -52.11572)
		(end 132.169408 -52.696364)
		(width 0.12446)
		(layer "B.Cu")
		(net "PHY_DPB_TO_SCC_C_28_DP")
	)
	(segment
		(start 132.169408 -52.696618)
		(end 132.473954 -54.128924)
		(width 0.12446)
		(layer "B.Cu")
		(net "PHY_DPB_TO_SCC_C_28_DP")
	)
	(segment
		(start 130.77825 -60.232036)
		(end 130.597402 -60.413138)
		(width 0.0889)
		(layer "B.Cu")
		(net "PHY_DPB_TO_SCC_C_28_DP")
	)
	(segment
		(start 132.169662 -52.696618)
		(end 132.169408 -52.696618)
		(width 0.12446)
		(layer "B.Cu")
		(net "PHY_DPB_TO_SCC_C_28_DP")
	)
	(segment
		(start 130.600196 -49.889918)
		(end 132.045964 -52.11572)
		(width 0.12446)
		(layer "B.Cu")
		(net "PHY_DPB_TO_SCC_C_28_DP")
	)
	(segment
		(start 130.8862 -59.280298)
		(end 130.77825 -59.388248)
		(width 0.0889)
		(layer "B.Cu")
		(net "PHY_DPB_TO_SCC_C_28_DP")
	)
	(segment
		(start 132.119878 -55.79618)
		(end 131.711446 -56.44261)
		(width 0.12446)
		(layer "B.Cu")
		(net "PHY_DPB_TO_SCC_C_28_DP")
	)
	(segment
		(start 128.8034 -41.487344)
		(end 128.740154 -41.55059)
		(width 0.12446)
		(layer "B.Cu")
		(net "PHY_DPB_TO_SCC_C_28_DP")
	)
	(arc
		(start 126.751334 -60.593732)
		(mid 126.640877 -60.639485)
		(end 126.595124 -60.749942)
		(width 0.0889)
		(layer "B.Cu")
		(net "PHY_DPB_TO_SCC_C_28_DP")
	)
	(arc
		(start 126.595124 -60.900056)
		(mid 126.624436 -60.97082)
		(end 126.6952 -61.000132)
		(width 0.0889)
		(layer "B.Cu")
		(net "PHY_DPB_TO_SCC_C_28_DP")
	)
	(segment
		(start 125.50013 -61.500004)
		(end 126.000002 -61.000132)
		(width 0.104902)
		(layer "F.Cu")
		(net "PHY_DPB_TO_SCC_C_28_DN")
	)
	(via
		(at 126.000002 -61.000132)
		(size 0.4572)
		(drill 0.2032)
		(layers "F.Cu" "B.Cu")
		(net "PHY_DPB_TO_SCC_C_28_DN")
	)
	(segment
		(start 130.306318 -50.183796)
		(end 131.663948 -52.273962)
		(width 0.12446)
		(layer "B.Cu")
		(net "PHY_DPB_TO_SCC_C_28_DN")
	)
	(segment
		(start 128.333754 -43.44035)
		(end 127.77724 -46.059344)
		(width 0.12446)
		(layer "B.Cu")
		(net "PHY_DPB_TO_SCC_C_28_DN")
	)
	(segment
		(start 130.337814 -60.403232)
		(end 126.751334 -60.403232)
		(width 0.0889)
		(layer "B.Cu")
		(net "PHY_DPB_TO_SCC_C_28_DN")
	)
	(segment
		(start 128.2192 -41.148)
		(end 128.2192 -41.440862)
		(width 0.12446)
		(layer "B.Cu")
		(net "PHY_DPB_TO_SCC_C_28_DN")
	)
	(segment
		(start 131.731258 -52.591208)
		(end 132.05841 -54.128924)
		(width 0.12446)
		(layer "B.Cu")
		(net "PHY_DPB_TO_SCC_C_28_DN")
	)
	(segment
		(start 127.77724 -46.059344)
		(end 128.234694 -48.212502)
		(width 0.12446)
		(layer "B.Cu")
		(net "PHY_DPB_TO_SCC_C_28_DN")
	)
	(segment
		(start 130.58775 -59.388248)
		(end 130.58775 -60.153042)
		(width 0.0889)
		(layer "B.Cu")
		(net "PHY_DPB_TO_SCC_C_28_DN")
	)
	(segment
		(start 126.304802 -61.000132)
		(end 126.000002 -61.000132)
		(width 0.0889)
		(layer "B.Cu")
		(net "PHY_DPB_TO_SCC_C_28_DN")
	)
	(segment
		(start 128.93675 -49.294542)
		(end 130.306318 -50.183796)
		(width 0.12446)
		(layer "B.Cu")
		(net "PHY_DPB_TO_SCC_C_28_DN")
	)
	(segment
		(start 131.391914 -56.187086)
		(end 130.4798 -57.0992)
		(width 0.12446)
		(layer "B.Cu")
		(net "PHY_DPB_TO_SCC_C_28_DN")
	)
	(segment
		(start 130.4798 -57.0992)
		(end 130.4798 -59.2582)
		(width 0.12446)
		(layer "B.Cu")
		(net "PHY_DPB_TO_SCC_C_28_DN")
	)
	(segment
		(start 128.234694 -48.212502)
		(end 128.93675 -49.294542)
		(width 0.12446)
		(layer "B.Cu")
		(net "PHY_DPB_TO_SCC_C_28_DN")
	)
	(segment
		(start 130.58775 -60.153042)
		(end 130.400298 -60.340748)
		(width 0.0889)
		(layer "B.Cu")
		(net "PHY_DPB_TO_SCC_C_28_DN")
	)
	(segment
		(start 126.404624 -60.749942)
		(end 126.404624 -60.90031)
		(width 0.0889)
		(layer "B.Cu")
		(net "PHY_DPB_TO_SCC_C_28_DN")
	)
	(segment
		(start 131.737354 -55.640478)
		(end 131.391914 -56.187086)
		(width 0.12446)
		(layer "B.Cu")
		(net "PHY_DPB_TO_SCC_C_28_DN")
	)
	(segment
		(start 132.05841 -54.128924)
		(end 131.737354 -55.640478)
		(width 0.12446)
		(layer "B.Cu")
		(net "PHY_DPB_TO_SCC_C_28_DN")
	)
	(segment
		(start 128.333754 -41.555416)
		(end 128.333754 -43.44035)
		(width 0.12446)
		(layer "B.Cu")
		(net "PHY_DPB_TO_SCC_C_28_DN")
	)
	(segment
		(start 130.4798 -59.2582)
		(end 130.4798 -59.280298)
		(width 0.0889)
		(layer "B.Cu")
		(net "PHY_DPB_TO_SCC_C_28_DN")
	)
	(segment
		(start 128.2192 -41.440862)
		(end 128.333754 -41.555416)
		(width 0.12446)
		(layer "B.Cu")
		(net "PHY_DPB_TO_SCC_C_28_DN")
	)
	(segment
		(start 130.400298 -60.340748)
		(end 130.337814 -60.403232)
		(width 0.0889)
		(layer "B.Cu")
		(net "PHY_DPB_TO_SCC_C_28_DN")
	)
	(segment
		(start 130.4798 -59.280298)
		(end 130.58775 -59.388248)
		(width 0.0889)
		(layer "B.Cu")
		(net "PHY_DPB_TO_SCC_C_28_DN")
	)
	(segment
		(start 131.663948 -52.273962)
		(end 131.731258 -52.591208)
		(width 0.12446)
		(layer "B.Cu")
		(net "PHY_DPB_TO_SCC_C_28_DN")
	)
	(arc
		(start 126.751334 -60.403232)
		(mid 126.506173 -60.504781)
		(end 126.404624 -60.749942)
		(width 0.0889)
		(layer "B.Cu")
		(net "PHY_DPB_TO_SCC_C_28_DN")
	)
	(arc
		(start 126.404624 -60.90031)
		(mid 126.375387 -60.970895)
		(end 126.304802 -61.000132)
		(width 0.0889)
		(layer "B.Cu")
		(net "PHY_DPB_TO_SCC_C_28_DN")
	)
	(segment
		(start 115.50015 -55.500016)
		(end 116.000022 -55.000144)
		(width 0.104902)
		(layer "F.Cu")
		(net "PHY_DPB_TO_SCC_C_27_DP")
	)
	(via
		(at 116.000022 -55.000144)
		(size 0.4572)
		(drill 0.2032)
		(layers "F.Cu" "B.Cu")
		(net "PHY_DPB_TO_SCC_C_27_DP")
	)
	(segment
		(start 113.9698 -44.7294)
		(end 113.9698 -44.5008)
		(width 0.12446)
		(layer "B.Cu")
		(net "PHY_DPB_TO_SCC_C_27_DP")
	)
	(segment
		(start 115.11915 -50.869088)
		(end 115.11915 -50.84699)
		(width 0.0889)
		(layer "B.Cu")
		(net "PHY_DPB_TO_SCC_C_27_DP")
	)
	(segment
		(start 115.580414 -55.205122)
		(end 115.580414 -51.894486)
		(width 0.0889)
		(layer "B.Cu")
		(net "PHY_DPB_TO_SCC_C_27_DP")
	)
	(segment
		(start 114.15522 -45.768768)
		(end 114.15522 -45.395388)
		(width 0.12446)
		(layer "B.Cu")
		(net "PHY_DPB_TO_SCC_C_27_DP")
	)
	(segment
		(start 115.11915 -47.968662)
		(end 113.88598 -46.735492)
		(width 0.12446)
		(layer "B.Cu")
		(net "PHY_DPB_TO_SCC_C_27_DP")
	)
	(segment
		(start 115.911122 -55.40502)
		(end 115.761262 -55.40502)
		(width 0.0889)
		(layer "B.Cu")
		(net "PHY_DPB_TO_SCC_C_27_DP")
	)
	(segment
		(start 113.88598 -46.735492)
		(end 113.88598 -46.038008)
		(width 0.12446)
		(layer "B.Cu")
		(net "PHY_DPB_TO_SCC_C_27_DP")
	)
	(segment
		(start 113.88598 -46.038008)
		(end 114.15522 -45.768768)
		(width 0.12446)
		(layer "B.Cu")
		(net "PHY_DPB_TO_SCC_C_27_DP")
	)
	(segment
		(start 116.000022 -55.000144)
		(end 116.000022 -55.31612)
		(width 0.0889)
		(layer "B.Cu")
		(net "PHY_DPB_TO_SCC_C_27_DP")
	)
	(segment
		(start 114.15522 -45.395388)
		(end 113.88598 -45.126148)
		(width 0.12446)
		(layer "B.Cu")
		(net "PHY_DPB_TO_SCC_C_27_DP")
	)
	(segment
		(start 115.11915 -50.84699)
		(end 115.11915 -47.968662)
		(width 0.12446)
		(layer "B.Cu")
		(net "PHY_DPB_TO_SCC_C_27_DP")
	)
	(segment
		(start 115.00358 -51.317398)
		(end 115.00358 -50.984658)
		(width 0.0889)
		(layer "B.Cu")
		(net "PHY_DPB_TO_SCC_C_27_DP")
	)
	(segment
		(start 113.88598 -45.126148)
		(end 113.88598 -44.81322)
		(width 0.12446)
		(layer "B.Cu")
		(net "PHY_DPB_TO_SCC_C_27_DP")
	)
	(segment
		(start 115.580414 -51.894486)
		(end 115.00358 -51.317398)
		(width 0.0889)
		(layer "B.Cu")
		(net "PHY_DPB_TO_SCC_C_27_DP")
	)
	(segment
		(start 113.88598 -44.81322)
		(end 113.9698 -44.7294)
		(width 0.12446)
		(layer "B.Cu")
		(net "PHY_DPB_TO_SCC_C_27_DP")
	)
	(segment
		(start 115.00358 -50.984658)
		(end 115.11915 -50.869088)
		(width 0.0889)
		(layer "B.Cu")
		(net "PHY_DPB_TO_SCC_C_27_DP")
	)
	(arc
		(start 115.642898 -55.355998)
		(mid 115.596645 -55.286776)
		(end 115.580414 -55.205122)
		(width 0.0889)
		(layer "B.Cu")
		(net "PHY_DPB_TO_SCC_C_27_DP")
	)
	(arc
		(start 116.000022 -55.31612)
		(mid 115.973984 -55.378982)
		(end 115.911122 -55.40502)
		(width 0.0889)
		(layer "B.Cu")
		(net "PHY_DPB_TO_SCC_C_27_DP")
	)
	(arc
		(start 115.761262 -55.40502)
		(mid 115.697206 -55.392278)
		(end 115.642898 -55.355998)
		(width 0.0889)
		(layer "B.Cu")
		(net "PHY_DPB_TO_SCC_C_27_DP")
	)
	(segment
		(start 115.50015 -56.500014)
		(end 116.000022 -56.000142)
		(width 0.104902)
		(layer "F.Cu")
		(net "PHY_DPB_TO_SCC_C_27_DN")
	)
	(via
		(at 116.000022 -56.000142)
		(size 0.4572)
		(drill 0.2032)
		(layers "F.Cu" "B.Cu")
		(net "PHY_DPB_TO_SCC_C_27_DN")
	)
	(segment
		(start 116.000022 -56.000142)
		(end 116.000022 -55.68442)
		(width 0.0889)
		(layer "B.Cu")
		(net "PHY_DPB_TO_SCC_C_27_DN")
	)
	(segment
		(start 114.71275 -48.137064)
		(end 113.47958 -46.903894)
		(width 0.12446)
		(layer "B.Cu")
		(net "PHY_DPB_TO_SCC_C_27_DN")
	)
	(segment
		(start 114.71275 -50.869088)
		(end 114.71275 -50.84699)
		(width 0.0889)
		(layer "B.Cu")
		(net "PHY_DPB_TO_SCC_C_27_DN")
	)
	(segment
		(start 115.389914 -55.20563)
		(end 115.389914 -51.97348)
		(width 0.0889)
		(layer "B.Cu")
		(net "PHY_DPB_TO_SCC_C_27_DN")
	)
	(segment
		(start 114.81308 -51.396392)
		(end 114.81308 -50.969418)
		(width 0.0889)
		(layer "B.Cu")
		(net "PHY_DPB_TO_SCC_C_27_DN")
	)
	(segment
		(start 113.47958 -46.903894)
		(end 113.47958 -44.77258)
		(width 0.12446)
		(layer "B.Cu")
		(net "PHY_DPB_TO_SCC_C_27_DN")
	)
	(segment
		(start 114.81308 -50.969418)
		(end 114.71275 -50.869088)
		(width 0.0889)
		(layer "B.Cu")
		(net "PHY_DPB_TO_SCC_C_27_DN")
	)
	(segment
		(start 115.911122 -55.59552)
		(end 115.761262 -55.59552)
		(width 0.0889)
		(layer "B.Cu")
		(net "PHY_DPB_TO_SCC_C_27_DN")
	)
	(segment
		(start 114.71275 -50.84699)
		(end 114.71275 -48.137064)
		(width 0.12446)
		(layer "B.Cu")
		(net "PHY_DPB_TO_SCC_C_27_DN")
	)
	(segment
		(start 115.389914 -51.97348)
		(end 114.81308 -51.396392)
		(width 0.0889)
		(layer "B.Cu")
		(net "PHY_DPB_TO_SCC_C_27_DN")
	)
	(segment
		(start 113.411 -44.704)
		(end 113.411 -44.5008)
		(width 0.12446)
		(layer "B.Cu")
		(net "PHY_DPB_TO_SCC_C_27_DN")
	)
	(segment
		(start 113.47958 -44.77258)
		(end 113.411 -44.704)
		(width 0.12446)
		(layer "B.Cu")
		(net "PHY_DPB_TO_SCC_C_27_DN")
	)
	(arc
		(start 115.508024 -55.490872)
		(mid 115.420633 -55.359988)
		(end 115.389914 -55.20563)
		(width 0.0889)
		(layer "B.Cu")
		(net "PHY_DPB_TO_SCC_C_27_DN")
	)
	(arc
		(start 115.761262 -55.59552)
		(mid 115.624237 -55.568376)
		(end 115.508024 -55.490872)
		(width 0.0889)
		(layer "B.Cu")
		(net "PHY_DPB_TO_SCC_C_27_DN")
	)
	(arc
		(start 116.000022 -55.68442)
		(mid 115.973984 -55.621558)
		(end 115.911122 -55.59552)
		(width 0.0889)
		(layer "B.Cu")
		(net "PHY_DPB_TO_SCC_C_27_DN")
	)
	(segment
		(start 114.499898 -55.500016)
		(end 114.000026 -55.000144)
		(width 0.104902)
		(layer "F.Cu")
		(net "PHY_DPB_TO_SCC_C_26_DP")
	)
	(via
		(at 114.000026 -55.000144)
		(size 0.4572)
		(drill 0.2032)
		(layers "F.Cu" "B.Cu")
		(net "PHY_DPB_TO_SCC_C_26_DP")
	)
	(segment
		(start 113.597182 -55.245508)
		(end 113.597182 -50.588164)
		(width 0.0889)
		(layer "B.Cu")
		(net "PHY_DPB_TO_SCC_C_26_DP")
	)
	(segment
		(start 113.705132 -50.480214)
		(end 113.705132 -50.458116)
		(width 0.0889)
		(layer "B.Cu")
		(net "PHY_DPB_TO_SCC_C_26_DP")
	)
	(segment
		(start 112.345978 -46.918372)
		(end 112.345978 -46.241208)
		(width 0.12446)
		(layer "B.Cu")
		(net "PHY_DPB_TO_SCC_C_26_DP")
	)
	(segment
		(start 112.345978 -46.241208)
		(end 112.615218 -45.971968)
		(width 0.12446)
		(layer "B.Cu")
		(net "PHY_DPB_TO_SCC_C_26_DP")
	)
	(segment
		(start 113.597182 -50.588164)
		(end 113.705132 -50.480214)
		(width 0.0889)
		(layer "B.Cu")
		(net "PHY_DPB_TO_SCC_C_26_DP")
	)
	(segment
		(start 112.345978 -45.329348)
		(end 112.345978 -44.97959)
		(width 0.12446)
		(layer "B.Cu")
		(net "PHY_DPB_TO_SCC_C_26_DP")
	)
	(segment
		(start 113.911126 -55.40502)
		(end 113.761266 -55.40502)
		(width 0.0889)
		(layer "B.Cu")
		(net "PHY_DPB_TO_SCC_C_26_DP")
	)
	(segment
		(start 112.615218 -45.971968)
		(end 112.615218 -45.598588)
		(width 0.12446)
		(layer "B.Cu")
		(net "PHY_DPB_TO_SCC_C_26_DP")
	)
	(segment
		(start 113.705132 -50.458116)
		(end 113.705132 -48.277526)
		(width 0.12446)
		(layer "B.Cu")
		(net "PHY_DPB_TO_SCC_C_26_DP")
	)
	(segment
		(start 113.705132 -48.277526)
		(end 112.345978 -46.918372)
		(width 0.12446)
		(layer "B.Cu")
		(net "PHY_DPB_TO_SCC_C_26_DP")
	)
	(segment
		(start 114.000026 -55.000144)
		(end 114.000026 -55.31612)
		(width 0.0889)
		(layer "B.Cu")
		(net "PHY_DPB_TO_SCC_C_26_DP")
	)
	(segment
		(start 112.4458 -44.879768)
		(end 112.4458 -44.5008)
		(width 0.12446)
		(layer "B.Cu")
		(net "PHY_DPB_TO_SCC_C_26_DP")
	)
	(segment
		(start 112.615218 -45.598588)
		(end 112.345978 -45.329348)
		(width 0.12446)
		(layer "B.Cu")
		(net "PHY_DPB_TO_SCC_C_26_DP")
	)
	(segment
		(start 112.345978 -44.97959)
		(end 112.4458 -44.879768)
		(width 0.12446)
		(layer "B.Cu")
		(net "PHY_DPB_TO_SCC_C_26_DP")
	)
	(arc
		(start 114.000026 -55.31612)
		(mid 113.973988 -55.378982)
		(end 113.911126 -55.40502)
		(width 0.0889)
		(layer "B.Cu")
		(net "PHY_DPB_TO_SCC_C_26_DP")
	)
	(arc
		(start 113.642902 -55.355998)
		(mid 113.60903 -55.305305)
		(end 113.597182 -55.245508)
		(width 0.0889)
		(layer "B.Cu")
		(net "PHY_DPB_TO_SCC_C_26_DP")
	)
	(arc
		(start 113.761266 -55.40502)
		(mid 113.69721 -55.392278)
		(end 113.642902 -55.355998)
		(width 0.0889)
		(layer "B.Cu")
		(net "PHY_DPB_TO_SCC_C_26_DP")
	)
	(segment
		(start 114.499898 -56.500014)
		(end 114.000026 -56.000142)
		(width 0.104902)
		(layer "F.Cu")
		(net "PHY_DPB_TO_SCC_C_26_DN")
	)
	(via
		(at 114.000026 -56.000142)
		(size 0.4572)
		(drill 0.2032)
		(layers "F.Cu" "B.Cu")
		(net "PHY_DPB_TO_SCC_C_26_DN")
	)
	(segment
		(start 113.406682 -50.588164)
		(end 113.298732 -50.480214)
		(width 0.0889)
		(layer "B.Cu")
		(net "PHY_DPB_TO_SCC_C_26_DN")
	)
	(segment
		(start 114.000026 -56.000142)
		(end 114.000026 -55.68442)
		(width 0.0889)
		(layer "B.Cu")
		(net "PHY_DPB_TO_SCC_C_26_DN")
	)
	(segment
		(start 111.939578 -47.086774)
		(end 111.939578 -44.932346)
		(width 0.12446)
		(layer "B.Cu")
		(net "PHY_DPB_TO_SCC_C_26_DN")
	)
	(segment
		(start 113.298732 -50.480214)
		(end 113.298732 -50.458116)
		(width 0.0889)
		(layer "B.Cu")
		(net "PHY_DPB_TO_SCC_C_26_DN")
	)
	(segment
		(start 113.298732 -50.458116)
		(end 113.298732 -48.445928)
		(width 0.12446)
		(layer "B.Cu")
		(net "PHY_DPB_TO_SCC_C_26_DN")
	)
	(segment
		(start 113.406682 -55.24627)
		(end 113.406682 -50.588164)
		(width 0.0889)
		(layer "B.Cu")
		(net "PHY_DPB_TO_SCC_C_26_DN")
	)
	(segment
		(start 113.911126 -55.59552)
		(end 113.761266 -55.59552)
		(width 0.0889)
		(layer "B.Cu")
		(net "PHY_DPB_TO_SCC_C_26_DN")
	)
	(segment
		(start 111.939578 -44.932346)
		(end 111.887 -44.879768)
		(width 0.12446)
		(layer "B.Cu")
		(net "PHY_DPB_TO_SCC_C_26_DN")
	)
	(segment
		(start 111.887 -44.879768)
		(end 111.887 -44.5008)
		(width 0.12446)
		(layer "B.Cu")
		(net "PHY_DPB_TO_SCC_C_26_DN")
	)
	(segment
		(start 113.298732 -48.445928)
		(end 111.939578 -47.086774)
		(width 0.12446)
		(layer "B.Cu")
		(net "PHY_DPB_TO_SCC_C_26_DN")
	)
	(arc
		(start 114.000026 -55.68442)
		(mid 113.973988 -55.621558)
		(end 113.911126 -55.59552)
		(width 0.0889)
		(layer "B.Cu")
		(net "PHY_DPB_TO_SCC_C_26_DN")
	)
	(arc
		(start 113.761266 -55.59552)
		(mid 113.624241 -55.568376)
		(end 113.508028 -55.490872)
		(width 0.0889)
		(layer "B.Cu")
		(net "PHY_DPB_TO_SCC_C_26_DN")
	)
	(arc
		(start 113.508028 -55.490872)
		(mid 113.433042 -55.378648)
		(end 113.406682 -55.24627)
		(width 0.0889)
		(layer "B.Cu")
		(net "PHY_DPB_TO_SCC_C_26_DN")
	)
	(segment
		(start 113.4999 -55.500016)
		(end 113.000028 -55.000144)
		(width 0.104902)
		(layer "F.Cu")
		(net "PHY_DPB_TO_SCC_C_25_DP")
	)
	(via
		(at 113.000028 -55.000144)
		(size 0.4572)
		(drill 0.2032)
		(layers "F.Cu" "B.Cu")
		(net "PHY_DPB_TO_SCC_C_25_DP")
	)
	(segment
		(start 110.821978 -46.241208)
		(end 111.091218 -45.971968)
		(width 0.12446)
		(layer "B.Cu")
		(net "PHY_DPB_TO_SCC_C_25_DP")
	)
	(segment
		(start 112.601502 -50.045874)
		(end 112.601502 -48.918368)
		(width 0.12446)
		(layer "B.Cu")
		(net "PHY_DPB_TO_SCC_C_25_DP")
	)
	(segment
		(start 112.493552 -50.596038)
		(end 112.493552 -50.175922)
		(width 0.0889)
		(layer "B.Cu")
		(net "PHY_DPB_TO_SCC_C_25_DP")
	)
	(segment
		(start 110.821978 -45.329348)
		(end 110.821978 -44.97959)
		(width 0.12446)
		(layer "B.Cu")
		(net "PHY_DPB_TO_SCC_C_25_DP")
	)
	(segment
		(start 111.091218 -45.598588)
		(end 110.821978 -45.329348)
		(width 0.12446)
		(layer "B.Cu")
		(net "PHY_DPB_TO_SCC_C_25_DP")
	)
	(segment
		(start 112.601502 -48.918368)
		(end 110.821978 -47.138844)
		(width 0.12446)
		(layer "B.Cu")
		(net "PHY_DPB_TO_SCC_C_25_DP")
	)
	(segment
		(start 112.911128 -55.40502)
		(end 112.761268 -55.40502)
		(width 0.0889)
		(layer "B.Cu")
		(net "PHY_DPB_TO_SCC_C_25_DP")
	)
	(segment
		(start 113.000028 -55.000144)
		(end 113.000028 -55.31612)
		(width 0.0889)
		(layer "B.Cu")
		(net "PHY_DPB_TO_SCC_C_25_DP")
	)
	(segment
		(start 112.493552 -50.175922)
		(end 112.601502 -50.067972)
		(width 0.0889)
		(layer "B.Cu")
		(net "PHY_DPB_TO_SCC_C_25_DP")
	)
	(segment
		(start 112.594644 -55.239412)
		(end 112.594644 -50.69713)
		(width 0.0889)
		(layer "B.Cu")
		(net "PHY_DPB_TO_SCC_C_25_DP")
	)
	(segment
		(start 112.594644 -50.69713)
		(end 112.493552 -50.596038)
		(width 0.0889)
		(layer "B.Cu")
		(net "PHY_DPB_TO_SCC_C_25_DP")
	)
	(segment
		(start 110.821978 -44.97959)
		(end 110.9218 -44.879768)
		(width 0.12446)
		(layer "B.Cu")
		(net "PHY_DPB_TO_SCC_C_25_DP")
	)
	(segment
		(start 110.821978 -47.138844)
		(end 110.821978 -46.241208)
		(width 0.12446)
		(layer "B.Cu")
		(net "PHY_DPB_TO_SCC_C_25_DP")
	)
	(segment
		(start 111.091218 -45.971968)
		(end 111.091218 -45.598588)
		(width 0.12446)
		(layer "B.Cu")
		(net "PHY_DPB_TO_SCC_C_25_DP")
	)
	(segment
		(start 112.601502 -50.067972)
		(end 112.601502 -50.045874)
		(width 0.0889)
		(layer "B.Cu")
		(net "PHY_DPB_TO_SCC_C_25_DP")
	)
	(segment
		(start 110.9218 -44.879768)
		(end 110.9218 -44.5008)
		(width 0.12446)
		(layer "B.Cu")
		(net "PHY_DPB_TO_SCC_C_25_DP")
	)
	(arc
		(start 113.000028 -55.31612)
		(mid 112.97399 -55.378982)
		(end 112.911128 -55.40502)
		(width 0.0889)
		(layer "B.Cu")
		(net "PHY_DPB_TO_SCC_C_25_DP")
	)
	(arc
		(start 112.761268 -55.40502)
		(mid 112.697212 -55.392278)
		(end 112.642904 -55.355998)
		(width 0.0889)
		(layer "B.Cu")
		(net "PHY_DPB_TO_SCC_C_25_DP")
	)
	(arc
		(start 112.642904 -55.355998)
		(mid 112.607163 -55.302508)
		(end 112.594644 -55.239412)
		(width 0.0889)
		(layer "B.Cu")
		(net "PHY_DPB_TO_SCC_C_25_DP")
	)
	(segment
		(start 113.4999 -56.500014)
		(end 113.000028 -56.000142)
		(width 0.104902)
		(layer "F.Cu")
		(net "PHY_DPB_TO_SCC_C_25_DN")
	)
	(via
		(at 113.000028 -56.000142)
		(size 0.4572)
		(drill 0.2032)
		(layers "F.Cu" "B.Cu")
		(net "PHY_DPB_TO_SCC_C_25_DN")
	)
	(segment
		(start 110.363 -44.879768)
		(end 110.363 -44.5008)
		(width 0.12446)
		(layer "B.Cu")
		(net "PHY_DPB_TO_SCC_C_25_DN")
	)
	(segment
		(start 112.303052 -50.675032)
		(end 112.303052 -50.175922)
		(width 0.0889)
		(layer "B.Cu")
		(net "PHY_DPB_TO_SCC_C_25_DN")
	)
	(segment
		(start 112.195102 -50.045874)
		(end 112.195102 -49.08677)
		(width 0.12446)
		(layer "B.Cu")
		(net "PHY_DPB_TO_SCC_C_25_DN")
	)
	(segment
		(start 110.415578 -47.307246)
		(end 110.415578 -44.932346)
		(width 0.12446)
		(layer "B.Cu")
		(net "PHY_DPB_TO_SCC_C_25_DN")
	)
	(segment
		(start 112.404144 -55.240174)
		(end 112.404144 -50.776124)
		(width 0.0889)
		(layer "B.Cu")
		(net "PHY_DPB_TO_SCC_C_25_DN")
	)
	(segment
		(start 112.195102 -50.067972)
		(end 112.195102 -50.045874)
		(width 0.0889)
		(layer "B.Cu")
		(net "PHY_DPB_TO_SCC_C_25_DN")
	)
	(segment
		(start 112.404144 -50.776124)
		(end 112.303052 -50.675032)
		(width 0.0889)
		(layer "B.Cu")
		(net "PHY_DPB_TO_SCC_C_25_DN")
	)
	(segment
		(start 112.303052 -50.175922)
		(end 112.195102 -50.067972)
		(width 0.0889)
		(layer "B.Cu")
		(net "PHY_DPB_TO_SCC_C_25_DN")
	)
	(segment
		(start 112.911128 -55.59552)
		(end 112.761268 -55.59552)
		(width 0.0889)
		(layer "B.Cu")
		(net "PHY_DPB_TO_SCC_C_25_DN")
	)
	(segment
		(start 112.195102 -49.08677)
		(end 110.415578 -47.307246)
		(width 0.12446)
		(layer "B.Cu")
		(net "PHY_DPB_TO_SCC_C_25_DN")
	)
	(segment
		(start 113.000028 -56.000142)
		(end 113.000028 -55.68442)
		(width 0.0889)
		(layer "B.Cu")
		(net "PHY_DPB_TO_SCC_C_25_DN")
	)
	(segment
		(start 110.415578 -44.932346)
		(end 110.363 -44.879768)
		(width 0.12446)
		(layer "B.Cu")
		(net "PHY_DPB_TO_SCC_C_25_DN")
	)
	(arc
		(start 112.761268 -55.59552)
		(mid 112.624243 -55.568376)
		(end 112.50803 -55.490872)
		(width 0.0889)
		(layer "B.Cu")
		(net "PHY_DPB_TO_SCC_C_25_DN")
	)
	(arc
		(start 112.50803 -55.490872)
		(mid 112.431122 -55.375865)
		(end 112.404144 -55.240174)
		(width 0.0889)
		(layer "B.Cu")
		(net "PHY_DPB_TO_SCC_C_25_DN")
	)
	(arc
		(start 113.000028 -55.68442)
		(mid 112.97399 -55.621558)
		(end 112.911128 -55.59552)
		(width 0.0889)
		(layer "B.Cu")
		(net "PHY_DPB_TO_SCC_C_25_DN")
	)
	(segment
		(start 112.499902 -55.500016)
		(end 112.00003 -55.000144)
		(width 0.104902)
		(layer "F.Cu")
		(net "PHY_DPB_TO_SCC_C_24_DP")
	)
	(via
		(at 112.00003 -55.000144)
		(size 0.4572)
		(drill 0.2032)
		(layers "F.Cu" "B.Cu")
		(net "PHY_DPB_TO_SCC_C_24_DP")
	)
	(segment
		(start 111.420402 -49.464468)
		(end 109.305852 -47.349918)
		(width 0.12446)
		(layer "B.Cu")
		(net "PHY_DPB_TO_SCC_C_24_DP")
	)
	(segment
		(start 111.312452 -50.175922)
		(end 111.420402 -50.067972)
		(width 0.0889)
		(layer "B.Cu")
		(net "PHY_DPB_TO_SCC_C_24_DP")
	)
	(segment
		(start 109.3978 -44.879768)
		(end 109.3978 -44.5008)
		(width 0.12446)
		(layer "B.Cu")
		(net "PHY_DPB_TO_SCC_C_24_DP")
	)
	(segment
		(start 109.305852 -44.971716)
		(end 109.3978 -44.879768)
		(width 0.12446)
		(layer "B.Cu")
		(net "PHY_DPB_TO_SCC_C_24_DP")
	)
	(segment
		(start 111.597186 -55.245508)
		(end 111.597186 -50.688748)
		(width 0.0889)
		(layer "B.Cu")
		(net "PHY_DPB_TO_SCC_C_24_DP")
	)
	(segment
		(start 109.305852 -47.349918)
		(end 109.305852 -46.288198)
		(width 0.12446)
		(layer "B.Cu")
		(net "PHY_DPB_TO_SCC_C_24_DP")
	)
	(segment
		(start 112.00003 -55.000144)
		(end 112.00003 -55.31612)
		(width 0.0889)
		(layer "B.Cu")
		(net "PHY_DPB_TO_SCC_C_24_DP")
	)
	(segment
		(start 109.575092 -46.018958)
		(end 109.575092 -45.645578)
		(width 0.12446)
		(layer "B.Cu")
		(net "PHY_DPB_TO_SCC_C_24_DP")
	)
	(segment
		(start 111.420402 -50.045874)
		(end 111.420402 -49.464468)
		(width 0.12446)
		(layer "B.Cu")
		(net "PHY_DPB_TO_SCC_C_24_DP")
	)
	(segment
		(start 109.305852 -45.376338)
		(end 109.305852 -44.971716)
		(width 0.12446)
		(layer "B.Cu")
		(net "PHY_DPB_TO_SCC_C_24_DP")
	)
	(segment
		(start 111.91113 -55.40502)
		(end 111.76127 -55.40502)
		(width 0.0889)
		(layer "B.Cu")
		(net "PHY_DPB_TO_SCC_C_24_DP")
	)
	(segment
		(start 109.575092 -45.645578)
		(end 109.305852 -45.376338)
		(width 0.12446)
		(layer "B.Cu")
		(net "PHY_DPB_TO_SCC_C_24_DP")
	)
	(segment
		(start 111.597186 -50.688748)
		(end 111.312452 -50.404014)
		(width 0.0889)
		(layer "B.Cu")
		(net "PHY_DPB_TO_SCC_C_24_DP")
	)
	(segment
		(start 109.305852 -46.288198)
		(end 109.575092 -46.018958)
		(width 0.12446)
		(layer "B.Cu")
		(net "PHY_DPB_TO_SCC_C_24_DP")
	)
	(segment
		(start 111.312452 -50.404014)
		(end 111.312452 -50.175922)
		(width 0.0889)
		(layer "B.Cu")
		(net "PHY_DPB_TO_SCC_C_24_DP")
	)
	(segment
		(start 111.420402 -50.067972)
		(end 111.420402 -50.045874)
		(width 0.0889)
		(layer "B.Cu")
		(net "PHY_DPB_TO_SCC_C_24_DP")
	)
	(arc
		(start 111.642906 -55.355998)
		(mid 111.609034 -55.305305)
		(end 111.597186 -55.245508)
		(width 0.0889)
		(layer "B.Cu")
		(net "PHY_DPB_TO_SCC_C_24_DP")
	)
	(arc
		(start 111.76127 -55.40502)
		(mid 111.697214 -55.392278)
		(end 111.642906 -55.355998)
		(width 0.0889)
		(layer "B.Cu")
		(net "PHY_DPB_TO_SCC_C_24_DP")
	)
	(arc
		(start 112.00003 -55.31612)
		(mid 111.973992 -55.378982)
		(end 111.91113 -55.40502)
		(width 0.0889)
		(layer "B.Cu")
		(net "PHY_DPB_TO_SCC_C_24_DP")
	)
	(segment
		(start 112.499902 -56.500014)
		(end 112.00003 -56.000142)
		(width 0.104902)
		(layer "F.Cu")
		(net "PHY_DPB_TO_SCC_C_24_DN")
	)
	(via
		(at 112.00003 -56.000142)
		(size 0.4572)
		(drill 0.2032)
		(layers "F.Cu" "B.Cu")
		(net "PHY_DPB_TO_SCC_C_24_DN")
	)
	(segment
		(start 111.406686 -50.767742)
		(end 111.121952 -50.483008)
		(width 0.0889)
		(layer "B.Cu")
		(net "PHY_DPB_TO_SCC_C_24_DN")
	)
	(segment
		(start 108.899452 -44.94022)
		(end 108.839 -44.879768)
		(width 0.12446)
		(layer "B.Cu")
		(net "PHY_DPB_TO_SCC_C_24_DN")
	)
	(segment
		(start 112.00003 -56.000142)
		(end 112.00003 -55.68442)
		(width 0.0889)
		(layer "B.Cu")
		(net "PHY_DPB_TO_SCC_C_24_DN")
	)
	(segment
		(start 111.014002 -50.045874)
		(end 111.014002 -49.63287)
		(width 0.12446)
		(layer "B.Cu")
		(net "PHY_DPB_TO_SCC_C_24_DN")
	)
	(segment
		(start 111.014002 -49.63287)
		(end 108.899452 -47.51832)
		(width 0.12446)
		(layer "B.Cu")
		(net "PHY_DPB_TO_SCC_C_24_DN")
	)
	(segment
		(start 111.014002 -50.067972)
		(end 111.014002 -50.045874)
		(width 0.0889)
		(layer "B.Cu")
		(net "PHY_DPB_TO_SCC_C_24_DN")
	)
	(segment
		(start 108.839 -44.879768)
		(end 108.839 -44.5008)
		(width 0.12446)
		(layer "B.Cu")
		(net "PHY_DPB_TO_SCC_C_24_DN")
	)
	(segment
		(start 111.121952 -50.483008)
		(end 111.121952 -50.175922)
		(width 0.0889)
		(layer "B.Cu")
		(net "PHY_DPB_TO_SCC_C_24_DN")
	)
	(segment
		(start 111.121952 -50.175922)
		(end 111.014002 -50.067972)
		(width 0.0889)
		(layer "B.Cu")
		(net "PHY_DPB_TO_SCC_C_24_DN")
	)
	(segment
		(start 108.899452 -47.51832)
		(end 108.899452 -44.94022)
		(width 0.12446)
		(layer "B.Cu")
		(net "PHY_DPB_TO_SCC_C_24_DN")
	)
	(segment
		(start 111.91113 -55.59552)
		(end 111.76127 -55.59552)
		(width 0.0889)
		(layer "B.Cu")
		(net "PHY_DPB_TO_SCC_C_24_DN")
	)
	(segment
		(start 111.406686 -55.24627)
		(end 111.406686 -50.767742)
		(width 0.0889)
		(layer "B.Cu")
		(net "PHY_DPB_TO_SCC_C_24_DN")
	)
	(arc
		(start 111.508032 -55.490872)
		(mid 111.433046 -55.378648)
		(end 111.406686 -55.24627)
		(width 0.0889)
		(layer "B.Cu")
		(net "PHY_DPB_TO_SCC_C_24_DN")
	)
	(arc
		(start 112.00003 -55.68442)
		(mid 111.973992 -55.621558)
		(end 111.91113 -55.59552)
		(width 0.0889)
		(layer "B.Cu")
		(net "PHY_DPB_TO_SCC_C_24_DN")
	)
	(arc
		(start 111.76127 -55.59552)
		(mid 111.624245 -55.568376)
		(end 111.508032 -55.490872)
		(width 0.0889)
		(layer "B.Cu")
		(net "PHY_DPB_TO_SCC_C_24_DN")
	)
	(segment
		(start 111.499904 -55.500016)
		(end 111.000032 -55.000144)
		(width 0.104902)
		(layer "F.Cu")
		(net "PHY_DPB_TO_SCC_C_23_DP")
	)
	(via
		(at 111.000032 -55.000144)
		(size 0.4572)
		(drill 0.2032)
		(layers "F.Cu" "B.Cu")
		(net "PHY_DPB_TO_SCC_C_23_DP")
	)
	(segment
		(start 109.74197 -50.612548)
		(end 109.74197 -49.799494)
		(width 0.12446)
		(layer "B.Cu")
		(net "PHY_DPB_TO_SCC_C_23_DP")
	)
	(segment
		(start 109.74197 -50.634646)
		(end 109.74197 -50.612548)
		(width 0.0889)
		(layer "B.Cu")
		(net "PHY_DPB_TO_SCC_C_23_DP")
	)
	(segment
		(start 108.031534 -46.030388)
		(end 108.031534 -45.657008)
		(width 0.12446)
		(layer "B.Cu")
		(net "PHY_DPB_TO_SCC_C_23_DP")
	)
	(segment
		(start 109.831378 -52.40528)
		(end 109.59592 -52.169822)
		(width 0.0889)
		(layer "B.Cu")
		(net "PHY_DPB_TO_SCC_C_23_DP")
	)
	(segment
		(start 110.594648 -52.724558)
		(end 110.27537 -52.40528)
		(width 0.0889)
		(layer "B.Cu")
		(net "PHY_DPB_TO_SCC_C_23_DP")
	)
	(segment
		(start 111.000032 -55.000144)
		(end 111.000032 -55.31612)
		(width 0.0889)
		(layer "B.Cu")
		(net "PHY_DPB_TO_SCC_C_23_DP")
	)
	(segment
		(start 109.59592 -52.169822)
		(end 109.59592 -50.780696)
		(width 0.0889)
		(layer "B.Cu")
		(net "PHY_DPB_TO_SCC_C_23_DP")
	)
	(segment
		(start 107.762294 -45.387768)
		(end 107.762294 -44.991274)
		(width 0.12446)
		(layer "B.Cu")
		(net "PHY_DPB_TO_SCC_C_23_DP")
	)
	(segment
		(start 110.594648 -55.239412)
		(end 110.594648 -52.724558)
		(width 0.0889)
		(layer "B.Cu")
		(net "PHY_DPB_TO_SCC_C_23_DP")
	)
	(segment
		(start 107.762294 -47.819818)
		(end 107.762294 -46.299628)
		(width 0.12446)
		(layer "B.Cu")
		(net "PHY_DPB_TO_SCC_C_23_DP")
	)
	(segment
		(start 109.74197 -49.799494)
		(end 107.762294 -47.819818)
		(width 0.12446)
		(layer "B.Cu")
		(net "PHY_DPB_TO_SCC_C_23_DP")
	)
	(segment
		(start 107.8738 -44.879768)
		(end 107.8738 -44.5008)
		(width 0.12446)
		(layer "B.Cu")
		(net "PHY_DPB_TO_SCC_C_23_DP")
	)
	(segment
		(start 110.911132 -55.40502)
		(end 110.761272 -55.40502)
		(width 0.0889)
		(layer "B.Cu")
		(net "PHY_DPB_TO_SCC_C_23_DP")
	)
	(segment
		(start 107.762294 -44.991274)
		(end 107.8738 -44.879768)
		(width 0.12446)
		(layer "B.Cu")
		(net "PHY_DPB_TO_SCC_C_23_DP")
	)
	(segment
		(start 108.031534 -45.657008)
		(end 107.762294 -45.387768)
		(width 0.12446)
		(layer "B.Cu")
		(net "PHY_DPB_TO_SCC_C_23_DP")
	)
	(segment
		(start 109.59592 -50.780696)
		(end 109.74197 -50.634646)
		(width 0.0889)
		(layer "B.Cu")
		(net "PHY_DPB_TO_SCC_C_23_DP")
	)
	(segment
		(start 110.27537 -52.40528)
		(end 109.831378 -52.40528)
		(width 0.0889)
		(layer "B.Cu")
		(net "PHY_DPB_TO_SCC_C_23_DP")
	)
	(segment
		(start 107.762294 -46.299628)
		(end 108.031534 -46.030388)
		(width 0.12446)
		(layer "B.Cu")
		(net "PHY_DPB_TO_SCC_C_23_DP")
	)
	(arc
		(start 110.761272 -55.40502)
		(mid 110.697216 -55.392278)
		(end 110.642908 -55.355998)
		(width 0.0889)
		(layer "B.Cu")
		(net "PHY_DPB_TO_SCC_C_23_DP")
	)
	(arc
		(start 111.000032 -55.31612)
		(mid 110.973994 -55.378982)
		(end 110.911132 -55.40502)
		(width 0.0889)
		(layer "B.Cu")
		(net "PHY_DPB_TO_SCC_C_23_DP")
	)
	(arc
		(start 110.642908 -55.355998)
		(mid 110.607167 -55.302508)
		(end 110.594648 -55.239412)
		(width 0.0889)
		(layer "B.Cu")
		(net "PHY_DPB_TO_SCC_C_23_DP")
	)
	(segment
		(start 111.499904 -56.500014)
		(end 111.000032 -56.000142)
		(width 0.104902)
		(layer "F.Cu")
		(net "PHY_DPB_TO_SCC_C_23_DN")
	)
	(via
		(at 111.000032 -56.000142)
		(size 0.4572)
		(drill 0.2032)
		(layers "F.Cu" "B.Cu")
		(net "PHY_DPB_TO_SCC_C_23_DN")
	)
	(segment
		(start 110.196376 -52.59578)
		(end 109.752384 -52.59578)
		(width 0.0889)
		(layer "B.Cu")
		(net "PHY_DPB_TO_SCC_C_23_DN")
	)
	(segment
		(start 109.40542 -50.704496)
		(end 109.33557 -50.634646)
		(width 0.0889)
		(layer "B.Cu")
		(net "PHY_DPB_TO_SCC_C_23_DN")
	)
	(segment
		(start 110.911132 -55.59552)
		(end 110.761272 -55.59552)
		(width 0.0889)
		(layer "B.Cu")
		(net "PHY_DPB_TO_SCC_C_23_DN")
	)
	(segment
		(start 111.000032 -56.000142)
		(end 111.000032 -55.68442)
		(width 0.0889)
		(layer "B.Cu")
		(net "PHY_DPB_TO_SCC_C_23_DN")
	)
	(segment
		(start 110.404148 -52.803552)
		(end 110.196376 -52.59578)
		(width 0.0889)
		(layer "B.Cu")
		(net "PHY_DPB_TO_SCC_C_23_DN")
	)
	(segment
		(start 109.33557 -49.967896)
		(end 107.355894 -47.98822)
		(width 0.12446)
		(layer "B.Cu")
		(net "PHY_DPB_TO_SCC_C_23_DN")
	)
	(segment
		(start 110.404148 -55.240174)
		(end 110.404148 -52.803552)
		(width 0.0889)
		(layer "B.Cu")
		(net "PHY_DPB_TO_SCC_C_23_DN")
	)
	(segment
		(start 107.355894 -47.98822)
		(end 107.355894 -44.920662)
		(width 0.12446)
		(layer "B.Cu")
		(net "PHY_DPB_TO_SCC_C_23_DN")
	)
	(segment
		(start 109.40542 -52.248816)
		(end 109.40542 -50.704496)
		(width 0.0889)
		(layer "B.Cu")
		(net "PHY_DPB_TO_SCC_C_23_DN")
	)
	(segment
		(start 107.315 -44.879768)
		(end 107.315 -44.5008)
		(width 0.12446)
		(layer "B.Cu")
		(net "PHY_DPB_TO_SCC_C_23_DN")
	)
	(segment
		(start 107.355894 -44.920662)
		(end 107.315 -44.879768)
		(width 0.12446)
		(layer "B.Cu")
		(net "PHY_DPB_TO_SCC_C_23_DN")
	)
	(segment
		(start 109.33557 -50.612548)
		(end 109.33557 -49.967896)
		(width 0.12446)
		(layer "B.Cu")
		(net "PHY_DPB_TO_SCC_C_23_DN")
	)
	(segment
		(start 109.752384 -52.59578)
		(end 109.40542 -52.248816)
		(width 0.0889)
		(layer "B.Cu")
		(net "PHY_DPB_TO_SCC_C_23_DN")
	)
	(segment
		(start 109.33557 -50.634646)
		(end 109.33557 -50.612548)
		(width 0.0889)
		(layer "B.Cu")
		(net "PHY_DPB_TO_SCC_C_23_DN")
	)
	(arc
		(start 110.508034 -55.490872)
		(mid 110.431126 -55.375865)
		(end 110.404148 -55.240174)
		(width 0.0889)
		(layer "B.Cu")
		(net "PHY_DPB_TO_SCC_C_23_DN")
	)
	(arc
		(start 111.000032 -55.68442)
		(mid 110.973994 -55.621558)
		(end 110.911132 -55.59552)
		(width 0.0889)
		(layer "B.Cu")
		(net "PHY_DPB_TO_SCC_C_23_DN")
	)
	(arc
		(start 110.761272 -55.59552)
		(mid 110.624247 -55.568376)
		(end 110.508034 -55.490872)
		(width 0.0889)
		(layer "B.Cu")
		(net "PHY_DPB_TO_SCC_C_23_DN")
	)
	(segment
		(start 110.499906 -55.500016)
		(end 110.000034 -55.000144)
		(width 0.104902)
		(layer "F.Cu")
		(net "PHY_DPB_TO_SCC_C_22_DP")
	)
	(via
		(at 110.000034 -55.000144)
		(size 0.4572)
		(drill 0.2032)
		(layers "F.Cu" "B.Cu")
		(net "PHY_DPB_TO_SCC_C_22_DP")
	)
	(segment
		(start 106.244136 -46.340522)
		(end 106.513376 -46.071282)
		(width 0.12446)
		(layer "B.Cu")
		(net "PHY_DPB_TO_SCC_C_22_DP")
	)
	(segment
		(start 109.597444 -53.742844)
		(end 109.260894 -53.406294)
		(width 0.0889)
		(layer "B.Cu")
		(net "PHY_DPB_TO_SCC_C_22_DP")
	)
	(segment
		(start 109.260894 -53.406294)
		(end 108.724192 -53.406294)
		(width 0.0889)
		(layer "B.Cu")
		(net "PHY_DPB_TO_SCC_C_22_DP")
	)
	(segment
		(start 108.594398 -53.2765)
		(end 108.594398 -50.80127)
		(width 0.0889)
		(layer "B.Cu")
		(net "PHY_DPB_TO_SCC_C_22_DP")
	)
	(segment
		(start 109.597444 -55.24627)
		(end 109.597444 -53.742844)
		(width 0.0889)
		(layer "B.Cu")
		(net "PHY_DPB_TO_SCC_C_22_DP")
	)
	(segment
		(start 109.911134 -55.40502)
		(end 109.761274 -55.40502)
		(width 0.0889)
		(layer "B.Cu")
		(net "PHY_DPB_TO_SCC_C_22_DP")
	)
	(segment
		(start 106.3498 -44.88561)
		(end 106.3498 -44.5008)
		(width 0.12446)
		(layer "B.Cu")
		(net "PHY_DPB_TO_SCC_C_22_DP")
	)
	(segment
		(start 106.244136 -44.991274)
		(end 106.3498 -44.88561)
		(width 0.12446)
		(layer "B.Cu")
		(net "PHY_DPB_TO_SCC_C_22_DP")
	)
	(segment
		(start 106.513376 -45.697902)
		(end 106.244136 -45.428662)
		(width 0.12446)
		(layer "B.Cu")
		(net "PHY_DPB_TO_SCC_C_22_DP")
	)
	(segment
		(start 106.244136 -47.741332)
		(end 106.244136 -46.340522)
		(width 0.12446)
		(layer "B.Cu")
		(net "PHY_DPB_TO_SCC_C_22_DP")
	)
	(segment
		(start 108.594398 -50.80127)
		(end 108.740194 -50.655474)
		(width 0.0889)
		(layer "B.Cu")
		(net "PHY_DPB_TO_SCC_C_22_DP")
	)
	(segment
		(start 106.513376 -46.071282)
		(end 106.513376 -45.697902)
		(width 0.12446)
		(layer "B.Cu")
		(net "PHY_DPB_TO_SCC_C_22_DP")
	)
	(segment
		(start 108.740194 -50.633376)
		(end 108.740194 -50.23739)
		(width 0.12446)
		(layer "B.Cu")
		(net "PHY_DPB_TO_SCC_C_22_DP")
	)
	(segment
		(start 110.000034 -55.000144)
		(end 110.000034 -55.31612)
		(width 0.0889)
		(layer "B.Cu")
		(net "PHY_DPB_TO_SCC_C_22_DP")
	)
	(segment
		(start 106.244136 -45.428662)
		(end 106.244136 -44.991274)
		(width 0.12446)
		(layer "B.Cu")
		(net "PHY_DPB_TO_SCC_C_22_DP")
	)
	(segment
		(start 108.740194 -50.23739)
		(end 106.244136 -47.741332)
		(width 0.12446)
		(layer "B.Cu")
		(net "PHY_DPB_TO_SCC_C_22_DP")
	)
	(segment
		(start 108.724192 -53.406294)
		(end 108.594398 -53.2765)
		(width 0.0889)
		(layer "B.Cu")
		(net "PHY_DPB_TO_SCC_C_22_DP")
	)
	(segment
		(start 108.740194 -50.655474)
		(end 108.740194 -50.633376)
		(width 0.0889)
		(layer "B.Cu")
		(net "PHY_DPB_TO_SCC_C_22_DP")
	)
	(arc
		(start 110.000034 -55.31612)
		(mid 109.973996 -55.378982)
		(end 109.911134 -55.40502)
		(width 0.0889)
		(layer "B.Cu")
		(net "PHY_DPB_TO_SCC_C_22_DP")
	)
	(arc
		(start 109.761274 -55.40502)
		(mid 109.697218 -55.392278)
		(end 109.64291 -55.355998)
		(width 0.0889)
		(layer "B.Cu")
		(net "PHY_DPB_TO_SCC_C_22_DP")
	)
	(arc
		(start 109.64291 -55.355998)
		(mid 109.609271 -55.305654)
		(end 109.597444 -55.24627)
		(width 0.0889)
		(layer "B.Cu")
		(net "PHY_DPB_TO_SCC_C_22_DP")
	)
	(segment
		(start 110.499906 -56.500014)
		(end 110.000034 -56.000142)
		(width 0.104902)
		(layer "F.Cu")
		(net "PHY_DPB_TO_SCC_C_22_DN")
	)
	(via
		(at 110.000034 -56.000142)
		(size 0.4572)
		(drill 0.2032)
		(layers "F.Cu" "B.Cu")
		(net "PHY_DPB_TO_SCC_C_22_DN")
	)
	(segment
		(start 108.645198 -53.596794)
		(end 109.1819 -53.596794)
		(width 0.0889)
		(layer "B.Cu")
		(net "PHY_DPB_TO_SCC_C_22_DN")
	)
	(segment
		(start 105.837736 -47.909734)
		(end 108.333794 -50.405792)
		(width 0.12446)
		(layer "B.Cu")
		(net "PHY_DPB_TO_SCC_C_22_DN")
	)
	(segment
		(start 108.403898 -50.725578)
		(end 108.403898 -53.355494)
		(width 0.0889)
		(layer "B.Cu")
		(net "PHY_DPB_TO_SCC_C_22_DN")
	)
	(segment
		(start 109.406944 -53.821838)
		(end 109.406944 -55.246778)
		(width 0.0889)
		(layer "B.Cu")
		(net "PHY_DPB_TO_SCC_C_22_DN")
	)
	(segment
		(start 108.403898 -53.355494)
		(end 108.645198 -53.596794)
		(width 0.0889)
		(layer "B.Cu")
		(net "PHY_DPB_TO_SCC_C_22_DN")
	)
	(segment
		(start 109.761274 -55.59552)
		(end 109.911134 -55.59552)
		(width 0.0889)
		(layer "B.Cu")
		(net "PHY_DPB_TO_SCC_C_22_DN")
	)
	(segment
		(start 110.000034 -55.68442)
		(end 110.000034 -56.000142)
		(width 0.0889)
		(layer "B.Cu")
		(net "PHY_DPB_TO_SCC_C_22_DN")
	)
	(segment
		(start 105.837736 -44.903136)
		(end 105.837736 -47.909734)
		(width 0.12446)
		(layer "B.Cu")
		(net "PHY_DPB_TO_SCC_C_22_DN")
	)
	(segment
		(start 105.791 -44.5008)
		(end 105.791 -44.8564)
		(width 0.12446)
		(layer "B.Cu")
		(net "PHY_DPB_TO_SCC_C_22_DN")
	)
	(segment
		(start 108.333794 -50.633376)
		(end 108.333794 -50.655474)
		(width 0.0889)
		(layer "B.Cu")
		(net "PHY_DPB_TO_SCC_C_22_DN")
	)
	(segment
		(start 108.333794 -50.405792)
		(end 108.333794 -50.633376)
		(width 0.12446)
		(layer "B.Cu")
		(net "PHY_DPB_TO_SCC_C_22_DN")
	)
	(segment
		(start 108.333794 -50.655474)
		(end 108.403898 -50.725578)
		(width 0.0889)
		(layer "B.Cu")
		(net "PHY_DPB_TO_SCC_C_22_DN")
	)
	(segment
		(start 109.1819 -53.596794)
		(end 109.406944 -53.821838)
		(width 0.0889)
		(layer "B.Cu")
		(net "PHY_DPB_TO_SCC_C_22_DN")
	)
	(segment
		(start 105.791 -44.8564)
		(end 105.837736 -44.903136)
		(width 0.12446)
		(layer "B.Cu")
		(net "PHY_DPB_TO_SCC_C_22_DN")
	)
	(arc
		(start 109.911134 -55.59552)
		(mid 109.973996 -55.621558)
		(end 110.000034 -55.68442)
		(width 0.0889)
		(layer "B.Cu")
		(net "PHY_DPB_TO_SCC_C_22_DN")
	)
	(arc
		(start 109.406944 -55.246778)
		(mid 109.43322 -55.378875)
		(end 109.508036 -55.490872)
		(width 0.0889)
		(layer "B.Cu")
		(net "PHY_DPB_TO_SCC_C_22_DN")
	)
	(arc
		(start 109.508036 -55.490872)
		(mid 109.624252 -55.568369)
		(end 109.761274 -55.59552)
		(width 0.0889)
		(layer "B.Cu")
		(net "PHY_DPB_TO_SCC_C_22_DN")
	)
	(segment
		(start 109.499908 -55.500016)
		(end 109.000036 -55.000144)
		(width 0.104902)
		(layer "F.Cu")
		(net "PHY_DPB_TO_SCC_C_21_DP")
	)
	(via
		(at 109.000036 -55.000144)
		(size 0.4572)
		(drill 0.2032)
		(layers "F.Cu" "B.Cu")
		(net "PHY_DPB_TO_SCC_C_21_DP")
	)
	(segment
		(start 107.735878 -50.671222)
		(end 107.59567 -50.81143)
		(width 0.0889)
		(layer "B.Cu")
		(net "PHY_DPB_TO_SCC_C_21_DP")
	)
	(segment
		(start 104.8258 -44.5008)
		(end 104.8258 -44.752768)
		(width 0.12446)
		(layer "B.Cu")
		(net "PHY_DPB_TO_SCC_C_21_DP")
	)
	(segment
		(start 104.72039 -45.958252)
		(end 104.98963 -46.227492)
		(width 0.12446)
		(layer "B.Cu")
		(net "PHY_DPB_TO_SCC_C_21_DP")
	)
	(segment
		(start 107.59567 -50.81143)
		(end 107.59567 -54.15026)
		(width 0.0889)
		(layer "B.Cu")
		(net "PHY_DPB_TO_SCC_C_21_DP")
	)
	(segment
		(start 108.343192 -54.405784)
		(end 108.59389 -54.656482)
		(width 0.0889)
		(layer "B.Cu")
		(net "PHY_DPB_TO_SCC_C_21_DP")
	)
	(segment
		(start 104.98963 -46.227492)
		(end 104.98963 -46.600872)
		(width 0.12446)
		(layer "B.Cu")
		(net "PHY_DPB_TO_SCC_C_21_DP")
	)
	(segment
		(start 109.000036 -55.31612)
		(end 109.000036 -55.000144)
		(width 0.0889)
		(layer "B.Cu")
		(net "PHY_DPB_TO_SCC_C_21_DP")
	)
	(segment
		(start 104.98963 -46.600872)
		(end 104.72039 -46.870112)
		(width 0.12446)
		(layer "B.Cu")
		(net "PHY_DPB_TO_SCC_C_21_DP")
	)
	(segment
		(start 104.8258 -44.752768)
		(end 104.72039 -44.858178)
		(width 0.12446)
		(layer "B.Cu")
		(net "PHY_DPB_TO_SCC_C_21_DP")
	)
	(segment
		(start 104.72039 -44.858178)
		(end 104.72039 -45.958252)
		(width 0.12446)
		(layer "B.Cu")
		(net "PHY_DPB_TO_SCC_C_21_DP")
	)
	(segment
		(start 108.761276 -55.40502)
		(end 108.911136 -55.40502)
		(width 0.0889)
		(layer "B.Cu")
		(net "PHY_DPB_TO_SCC_C_21_DP")
	)
	(segment
		(start 108.59389 -54.656482)
		(end 108.59389 -55.237634)
		(width 0.0889)
		(layer "B.Cu")
		(net "PHY_DPB_TO_SCC_C_21_DP")
	)
	(segment
		(start 107.735878 -50.398426)
		(end 107.735878 -50.671222)
		(width 0.12446)
		(layer "B.Cu")
		(net "PHY_DPB_TO_SCC_C_21_DP")
	)
	(segment
		(start 107.851194 -54.405784)
		(end 108.343192 -54.405784)
		(width 0.0889)
		(layer "B.Cu")
		(net "PHY_DPB_TO_SCC_C_21_DP")
	)
	(segment
		(start 104.72039 -47.382938)
		(end 107.735878 -50.398426)
		(width 0.12446)
		(layer "B.Cu")
		(net "PHY_DPB_TO_SCC_C_21_DP")
	)
	(segment
		(start 104.72039 -46.870112)
		(end 104.72039 -47.382938)
		(width 0.12446)
		(layer "B.Cu")
		(net "PHY_DPB_TO_SCC_C_21_DP")
	)
	(segment
		(start 107.59567 -54.15026)
		(end 107.851194 -54.405784)
		(width 0.0889)
		(layer "B.Cu")
		(net "PHY_DPB_TO_SCC_C_21_DP")
	)
	(arc
		(start 108.911136 -55.40502)
		(mid 108.973998 -55.378982)
		(end 109.000036 -55.31612)
		(width 0.0889)
		(layer "B.Cu")
		(net "PHY_DPB_TO_SCC_C_21_DP")
	)
	(arc
		(start 108.59389 -55.237634)
		(mid 108.606632 -55.30169)
		(end 108.642912 -55.355998)
		(width 0.0889)
		(layer "B.Cu")
		(net "PHY_DPB_TO_SCC_C_21_DP")
	)
	(arc
		(start 108.642912 -55.355998)
		(mid 108.697218 -55.392284)
		(end 108.761276 -55.40502)
		(width 0.0889)
		(layer "B.Cu")
		(net "PHY_DPB_TO_SCC_C_21_DP")
	)
	(segment
		(start 109.499908 -56.500014)
		(end 109.000036 -56.000142)
		(width 0.104902)
		(layer "F.Cu")
		(net "PHY_DPB_TO_SCC_C_21_DN")
	)
	(via
		(at 109.000036 -56.000142)
		(size 0.4572)
		(drill 0.2032)
		(layers "F.Cu" "B.Cu")
		(net "PHY_DPB_TO_SCC_C_21_DN")
	)
	(segment
		(start 107.40517 -50.76571)
		(end 107.40517 -54.229254)
		(width 0.0889)
		(layer "B.Cu")
		(net "PHY_DPB_TO_SCC_C_21_DN")
	)
	(segment
		(start 107.329478 -50.690018)
		(end 107.40517 -50.76571)
		(width 0.0889)
		(layer "B.Cu")
		(net "PHY_DPB_TO_SCC_C_21_DN")
	)
	(segment
		(start 104.31399 -47.55134)
		(end 107.329478 -50.566828)
		(width 0.12446)
		(layer "B.Cu")
		(net "PHY_DPB_TO_SCC_C_21_DN")
	)
	(segment
		(start 108.40339 -54.735476)
		(end 108.40339 -55.237634)
		(width 0.0889)
		(layer "B.Cu")
		(net "PHY_DPB_TO_SCC_C_21_DN")
	)
	(segment
		(start 109.000036 -55.68442)
		(end 109.000036 -56.000142)
		(width 0.0889)
		(layer "B.Cu")
		(net "PHY_DPB_TO_SCC_C_21_DN")
	)
	(segment
		(start 104.267 -44.5008)
		(end 104.267 -44.752768)
		(width 0.12446)
		(layer "B.Cu")
		(net "PHY_DPB_TO_SCC_C_21_DN")
	)
	(segment
		(start 104.31399 -44.799758)
		(end 104.31399 -47.55134)
		(width 0.12446)
		(layer "B.Cu")
		(net "PHY_DPB_TO_SCC_C_21_DN")
	)
	(segment
		(start 107.40517 -54.229254)
		(end 107.7722 -54.596284)
		(width 0.0889)
		(layer "B.Cu")
		(net "PHY_DPB_TO_SCC_C_21_DN")
	)
	(segment
		(start 107.329478 -50.566828)
		(end 107.329478 -50.690018)
		(width 0.12446)
		(layer "B.Cu")
		(net "PHY_DPB_TO_SCC_C_21_DN")
	)
	(segment
		(start 108.264198 -54.596284)
		(end 108.40339 -54.735476)
		(width 0.0889)
		(layer "B.Cu")
		(net "PHY_DPB_TO_SCC_C_21_DN")
	)
	(segment
		(start 107.7722 -54.596284)
		(end 108.264198 -54.596284)
		(width 0.0889)
		(layer "B.Cu")
		(net "PHY_DPB_TO_SCC_C_21_DN")
	)
	(segment
		(start 104.267 -44.752768)
		(end 104.31399 -44.799758)
		(width 0.12446)
		(layer "B.Cu")
		(net "PHY_DPB_TO_SCC_C_21_DN")
	)
	(segment
		(start 108.761276 -55.59552)
		(end 108.911136 -55.59552)
		(width 0.0889)
		(layer "B.Cu")
		(net "PHY_DPB_TO_SCC_C_21_DN")
	)
	(arc
		(start 108.508038 -55.490872)
		(mid 108.624254 -55.568369)
		(end 108.761276 -55.59552)
		(width 0.0889)
		(layer "B.Cu")
		(net "PHY_DPB_TO_SCC_C_21_DN")
	)
	(arc
		(start 108.911136 -55.59552)
		(mid 108.973998 -55.621558)
		(end 109.000036 -55.68442)
		(width 0.0889)
		(layer "B.Cu")
		(net "PHY_DPB_TO_SCC_C_21_DN")
	)
	(arc
		(start 108.40339 -55.237634)
		(mid 108.430534 -55.374659)
		(end 108.508038 -55.490872)
		(width 0.0889)
		(layer "B.Cu")
		(net "PHY_DPB_TO_SCC_C_21_DN")
	)
	(segment
		(start 108.49991 -55.500016)
		(end 108.000038 -55.000144)
		(width 0.104902)
		(layer "F.Cu")
		(net "PHY_DPB_TO_SCC_C_20_DP")
	)
	(via
		(at 108.000038 -55.000144)
		(size 0.4572)
		(drill 0.2032)
		(layers "F.Cu" "B.Cu")
		(net "PHY_DPB_TO_SCC_C_20_DP")
	)
	(segment
		(start 105.595674 -50.535078)
		(end 105.595674 -53.170328)
		(width 0.0889)
		(layer "B.Cu")
		(net "PHY_DPB_TO_SCC_C_20_DP")
	)
	(segment
		(start 103.3018 -44.5008)
		(end 103.3018 -44.7294)
		(width 0.12446)
		(layer "B.Cu")
		(net "PHY_DPB_TO_SCC_C_20_DP")
	)
	(segment
		(start 103.3018 -44.7294)
		(end 103.213662 -44.817538)
		(width 0.12446)
		(layer "B.Cu")
		(net "PHY_DPB_TO_SCC_C_20_DP")
	)
	(segment
		(start 103.213662 -47.19828)
		(end 105.753662 -49.73828)
		(width 0.12446)
		(layer "B.Cu")
		(net "PHY_DPB_TO_SCC_C_20_DP")
	)
	(segment
		(start 105.753662 -49.73828)
		(end 105.753662 -50.354992)
		(width 0.12446)
		(layer "B.Cu")
		(net "PHY_DPB_TO_SCC_C_20_DP")
	)
	(segment
		(start 103.482902 -46.193202)
		(end 103.482902 -46.566582)
		(width 0.12446)
		(layer "B.Cu")
		(net "PHY_DPB_TO_SCC_C_20_DP")
	)
	(segment
		(start 107.593892 -54.732428)
		(end 107.593892 -55.237634)
		(width 0.0889)
		(layer "B.Cu")
		(net "PHY_DPB_TO_SCC_C_20_DP")
	)
	(segment
		(start 106.830622 -54.40172)
		(end 107.263184 -54.40172)
		(width 0.0889)
		(layer "B.Cu")
		(net "PHY_DPB_TO_SCC_C_20_DP")
	)
	(segment
		(start 103.213662 -46.835822)
		(end 103.213662 -47.19828)
		(width 0.12446)
		(layer "B.Cu")
		(net "PHY_DPB_TO_SCC_C_20_DP")
	)
	(segment
		(start 108.000038 -55.31612)
		(end 108.000038 -55.000144)
		(width 0.0889)
		(layer "B.Cu")
		(net "PHY_DPB_TO_SCC_C_20_DP")
	)
	(segment
		(start 105.753662 -50.354992)
		(end 105.753662 -50.37709)
		(width 0.0889)
		(layer "B.Cu")
		(net "PHY_DPB_TO_SCC_C_20_DP")
	)
	(segment
		(start 106.224578 -53.4162)
		(end 106.5784 -53.770022)
		(width 0.0889)
		(layer "B.Cu")
		(net "PHY_DPB_TO_SCC_C_20_DP")
	)
	(segment
		(start 107.263184 -54.40172)
		(end 107.593892 -54.732428)
		(width 0.0889)
		(layer "B.Cu")
		(net "PHY_DPB_TO_SCC_C_20_DP")
	)
	(segment
		(start 105.753662 -50.37709)
		(end 105.595674 -50.535078)
		(width 0.0889)
		(layer "B.Cu")
		(net "PHY_DPB_TO_SCC_C_20_DP")
	)
	(segment
		(start 103.213662 -45.923962)
		(end 103.482902 -46.193202)
		(width 0.12446)
		(layer "B.Cu")
		(net "PHY_DPB_TO_SCC_C_20_DP")
	)
	(segment
		(start 103.482902 -46.566582)
		(end 103.213662 -46.835822)
		(width 0.12446)
		(layer "B.Cu")
		(net "PHY_DPB_TO_SCC_C_20_DP")
	)
	(segment
		(start 105.841546 -53.4162)
		(end 106.224578 -53.4162)
		(width 0.0889)
		(layer "B.Cu")
		(net "PHY_DPB_TO_SCC_C_20_DP")
	)
	(segment
		(start 107.761278 -55.40502)
		(end 107.911138 -55.40502)
		(width 0.0889)
		(layer "B.Cu")
		(net "PHY_DPB_TO_SCC_C_20_DP")
	)
	(segment
		(start 106.5784 -53.770022)
		(end 106.5784 -54.149498)
		(width 0.0889)
		(layer "B.Cu")
		(net "PHY_DPB_TO_SCC_C_20_DP")
	)
	(segment
		(start 105.595674 -53.170328)
		(end 105.841546 -53.4162)
		(width 0.0889)
		(layer "B.Cu")
		(net "PHY_DPB_TO_SCC_C_20_DP")
	)
	(segment
		(start 103.213662 -44.817538)
		(end 103.213662 -45.923962)
		(width 0.12446)
		(layer "B.Cu")
		(net "PHY_DPB_TO_SCC_C_20_DP")
	)
	(segment
		(start 106.5784 -54.149498)
		(end 106.830622 -54.40172)
		(width 0.0889)
		(layer "B.Cu")
		(net "PHY_DPB_TO_SCC_C_20_DP")
	)
	(arc
		(start 107.911138 -55.40502)
		(mid 107.974 -55.378982)
		(end 108.000038 -55.31612)
		(width 0.0889)
		(layer "B.Cu")
		(net "PHY_DPB_TO_SCC_C_20_DP")
	)
	(arc
		(start 107.593892 -55.237634)
		(mid 107.606634 -55.30169)
		(end 107.642914 -55.355998)
		(width 0.0889)
		(layer "B.Cu")
		(net "PHY_DPB_TO_SCC_C_20_DP")
	)
	(arc
		(start 107.642914 -55.355998)
		(mid 107.69722 -55.392284)
		(end 107.761278 -55.40502)
		(width 0.0889)
		(layer "B.Cu")
		(net "PHY_DPB_TO_SCC_C_20_DP")
	)
	(segment
		(start 108.49991 -56.500014)
		(end 108.000038 -56.000142)
		(width 0.104902)
		(layer "F.Cu")
		(net "PHY_DPB_TO_SCC_C_20_DN")
	)
	(via
		(at 108.000038 -56.000142)
		(size 0.4572)
		(drill 0.2032)
		(layers "F.Cu" "B.Cu")
		(net "PHY_DPB_TO_SCC_C_20_DN")
	)
	(segment
		(start 107.18419 -54.59222)
		(end 107.403392 -54.811422)
		(width 0.0889)
		(layer "B.Cu")
		(net "PHY_DPB_TO_SCC_C_20_DN")
	)
	(segment
		(start 105.347262 -49.906682)
		(end 105.347262 -50.354992)
		(width 0.12446)
		(layer "B.Cu")
		(net "PHY_DPB_TO_SCC_C_20_DN")
	)
	(segment
		(start 105.405174 -50.435002)
		(end 105.405174 -53.249322)
		(width 0.0889)
		(layer "B.Cu")
		(net "PHY_DPB_TO_SCC_C_20_DN")
	)
	(segment
		(start 102.743 -44.7294)
		(end 102.807262 -44.793662)
		(width 0.12446)
		(layer "B.Cu")
		(net "PHY_DPB_TO_SCC_C_20_DN")
	)
	(segment
		(start 102.743 -44.5008)
		(end 102.743 -44.7294)
		(width 0.12446)
		(layer "B.Cu")
		(net "PHY_DPB_TO_SCC_C_20_DN")
	)
	(segment
		(start 102.807262 -47.366682)
		(end 105.347262 -49.906682)
		(width 0.12446)
		(layer "B.Cu")
		(net "PHY_DPB_TO_SCC_C_20_DN")
	)
	(segment
		(start 105.347262 -50.354992)
		(end 105.347262 -50.37709)
		(width 0.0889)
		(layer "B.Cu")
		(net "PHY_DPB_TO_SCC_C_20_DN")
	)
	(segment
		(start 105.347262 -50.37709)
		(end 105.405174 -50.435002)
		(width 0.0889)
		(layer "B.Cu")
		(net "PHY_DPB_TO_SCC_C_20_DN")
	)
	(segment
		(start 105.762552 -53.6067)
		(end 106.145584 -53.6067)
		(width 0.0889)
		(layer "B.Cu")
		(net "PHY_DPB_TO_SCC_C_20_DN")
	)
	(segment
		(start 107.403392 -54.811422)
		(end 107.403392 -55.237634)
		(width 0.0889)
		(layer "B.Cu")
		(net "PHY_DPB_TO_SCC_C_20_DN")
	)
	(segment
		(start 102.807262 -44.793662)
		(end 102.807262 -47.366682)
		(width 0.12446)
		(layer "B.Cu")
		(net "PHY_DPB_TO_SCC_C_20_DN")
	)
	(segment
		(start 107.761278 -55.59552)
		(end 107.911138 -55.59552)
		(width 0.0889)
		(layer "B.Cu")
		(net "PHY_DPB_TO_SCC_C_20_DN")
	)
	(segment
		(start 108.000038 -55.68442)
		(end 108.000038 -56.000142)
		(width 0.0889)
		(layer "B.Cu")
		(net "PHY_DPB_TO_SCC_C_20_DN")
	)
	(segment
		(start 105.405174 -53.249322)
		(end 105.762552 -53.6067)
		(width 0.0889)
		(layer "B.Cu")
		(net "PHY_DPB_TO_SCC_C_20_DN")
	)
	(segment
		(start 106.3879 -53.849016)
		(end 106.3879 -54.228492)
		(width 0.0889)
		(layer "B.Cu")
		(net "PHY_DPB_TO_SCC_C_20_DN")
	)
	(segment
		(start 106.751628 -54.59222)
		(end 107.18419 -54.59222)
		(width 0.0889)
		(layer "B.Cu")
		(net "PHY_DPB_TO_SCC_C_20_DN")
	)
	(segment
		(start 106.3879 -54.228492)
		(end 106.751628 -54.59222)
		(width 0.0889)
		(layer "B.Cu")
		(net "PHY_DPB_TO_SCC_C_20_DN")
	)
	(segment
		(start 106.145584 -53.6067)
		(end 106.3879 -53.849016)
		(width 0.0889)
		(layer "B.Cu")
		(net "PHY_DPB_TO_SCC_C_20_DN")
	)
	(arc
		(start 107.911138 -55.59552)
		(mid 107.974 -55.621558)
		(end 108.000038 -55.68442)
		(width 0.0889)
		(layer "B.Cu")
		(net "PHY_DPB_TO_SCC_C_20_DN")
	)
	(arc
		(start 107.403392 -55.237634)
		(mid 107.430536 -55.374659)
		(end 107.50804 -55.490872)
		(width 0.0889)
		(layer "B.Cu")
		(net "PHY_DPB_TO_SCC_C_20_DN")
	)
	(arc
		(start 107.50804 -55.490872)
		(mid 107.624256 -55.568369)
		(end 107.761278 -55.59552)
		(width 0.0889)
		(layer "B.Cu")
		(net "PHY_DPB_TO_SCC_C_20_DN")
	)
	(segment
		(start 126.500128 -67.500246)
		(end 127 -68.000118)
		(width 0.104902)
		(layer "F.Cu")
		(net "PHY_DPB_TO_SCC_C_2_DP")
	)
	(via
		(at 127 -68.000118)
		(size 0.4572)
		(drill 0.2032)
		(layers "F.Cu" "B.Cu")
		(net "PHY_DPB_TO_SCC_C_2_DP")
	)
	(segment
		(start 132.08381 -66.7512)
		(end 131.687316 -66.7512)
		(width 0.12446)
		(layer "B.Cu")
		(net "PHY_DPB_TO_SCC_C_2_DP")
	)
	(segment
		(start 136.831832 -66.8274)
		(end 136.755632 -66.7512)
		(width 0.12446)
		(layer "B.Cu")
		(net "PHY_DPB_TO_SCC_C_2_DP")
	)
	(segment
		(start 137.1854 -66.8274)
		(end 136.831832 -66.8274)
		(width 0.12446)
		(layer "B.Cu")
		(net "PHY_DPB_TO_SCC_C_2_DP")
	)
	(segment
		(start 130.34899 -67.722242)
		(end 130.221482 -67.594734)
		(width 0.0889)
		(layer "B.Cu")
		(net "PHY_DPB_TO_SCC_C_2_DP")
	)
	(segment
		(start 126.595124 -67.749928)
		(end 126.595124 -67.900042)
		(width 0.0889)
		(layer "B.Cu")
		(net "PHY_DPB_TO_SCC_C_2_DP")
	)
	(segment
		(start 130.221482 -67.594734)
		(end 126.750318 -67.594734)
		(width 0.0889)
		(layer "B.Cu")
		(net "PHY_DPB_TO_SCC_C_2_DP")
	)
	(segment
		(start 136.755632 -66.7512)
		(end 133.01599 -66.7512)
		(width 0.12446)
		(layer "B.Cu")
		(net "PHY_DPB_TO_SCC_C_2_DP")
	)
	(segment
		(start 130.716274 -67.722242)
		(end 130.371088 -67.722242)
		(width 0.12446)
		(layer "B.Cu")
		(net "PHY_DPB_TO_SCC_C_2_DP")
	)
	(segment
		(start 132.36321 -67.0306)
		(end 132.08381 -66.7512)
		(width 0.12446)
		(layer "B.Cu")
		(net "PHY_DPB_TO_SCC_C_2_DP")
	)
	(segment
		(start 126.6952 -68.000118)
		(end 127 -68.000118)
		(width 0.0889)
		(layer "B.Cu")
		(net "PHY_DPB_TO_SCC_C_2_DP")
	)
	(segment
		(start 131.687316 -66.7512)
		(end 130.716274 -67.722242)
		(width 0.12446)
		(layer "B.Cu")
		(net "PHY_DPB_TO_SCC_C_2_DP")
	)
	(segment
		(start 133.01599 -66.7512)
		(end 132.73659 -67.0306)
		(width 0.12446)
		(layer "B.Cu")
		(net "PHY_DPB_TO_SCC_C_2_DP")
	)
	(segment
		(start 130.371088 -67.722242)
		(end 130.34899 -67.722242)
		(width 0.0889)
		(layer "B.Cu")
		(net "PHY_DPB_TO_SCC_C_2_DP")
	)
	(segment
		(start 132.73659 -67.0306)
		(end 132.36321 -67.0306)
		(width 0.12446)
		(layer "B.Cu")
		(net "PHY_DPB_TO_SCC_C_2_DP")
	)
	(arc
		(start 126.595124 -67.900042)
		(mid 126.624436 -67.970806)
		(end 126.6952 -68.000118)
		(width 0.0889)
		(layer "B.Cu")
		(net "PHY_DPB_TO_SCC_C_2_DP")
	)
	(arc
		(start 126.750318 -67.594734)
		(mid 126.640579 -67.640189)
		(end 126.595124 -67.749928)
		(width 0.0889)
		(layer "B.Cu")
		(net "PHY_DPB_TO_SCC_C_2_DP")
	)
	(segment
		(start 125.50013 -67.500246)
		(end 126.000002 -68.000118)
		(width 0.104902)
		(layer "F.Cu")
		(net "PHY_DPB_TO_SCC_C_2_DN")
	)
	(via
		(at 126.000002 -68.000118)
		(size 0.4572)
		(drill 0.2032)
		(layers "F.Cu" "B.Cu")
		(net "PHY_DPB_TO_SCC_C_2_DN")
	)
	(segment
		(start 131.518914 -66.3448)
		(end 130.547872 -67.315842)
		(width 0.12446)
		(layer "B.Cu")
		(net "PHY_DPB_TO_SCC_C_2_DN")
	)
	(segment
		(start 126.404624 -67.749928)
		(end 126.404624 -67.900296)
		(width 0.0889)
		(layer "B.Cu")
		(net "PHY_DPB_TO_SCC_C_2_DN")
	)
	(segment
		(start 130.371088 -67.315842)
		(end 130.34899 -67.315842)
		(width 0.0889)
		(layer "B.Cu")
		(net "PHY_DPB_TO_SCC_C_2_DN")
	)
	(segment
		(start 126.304802 -68.000118)
		(end 126.000002 -68.000118)
		(width 0.0889)
		(layer "B.Cu")
		(net "PHY_DPB_TO_SCC_C_2_DN")
	)
	(segment
		(start 130.547872 -67.315842)
		(end 130.371088 -67.315842)
		(width 0.12446)
		(layer "B.Cu")
		(net "PHY_DPB_TO_SCC_C_2_DN")
	)
	(segment
		(start 136.831832 -66.2686)
		(end 136.755632 -66.3448)
		(width 0.12446)
		(layer "B.Cu")
		(net "PHY_DPB_TO_SCC_C_2_DN")
	)
	(segment
		(start 137.1854 -66.2686)
		(end 136.831832 -66.2686)
		(width 0.12446)
		(layer "B.Cu")
		(net "PHY_DPB_TO_SCC_C_2_DN")
	)
	(segment
		(start 136.755632 -66.3448)
		(end 131.518914 -66.3448)
		(width 0.12446)
		(layer "B.Cu")
		(net "PHY_DPB_TO_SCC_C_2_DN")
	)
	(segment
		(start 130.260598 -67.404234)
		(end 126.750318 -67.404234)
		(width 0.0889)
		(layer "B.Cu")
		(net "PHY_DPB_TO_SCC_C_2_DN")
	)
	(segment
		(start 130.34899 -67.315842)
		(end 130.260598 -67.404234)
		(width 0.0889)
		(layer "B.Cu")
		(net "PHY_DPB_TO_SCC_C_2_DN")
	)
	(arc
		(start 126.750318 -67.404234)
		(mid 126.505875 -67.505485)
		(end 126.404624 -67.749928)
		(width 0.0889)
		(layer "B.Cu")
		(net "PHY_DPB_TO_SCC_C_2_DN")
	)
	(arc
		(start 126.404624 -67.900296)
		(mid 126.375387 -67.970881)
		(end 126.304802 -68.000118)
		(width 0.0889)
		(layer "B.Cu")
		(net "PHY_DPB_TO_SCC_C_2_DN")
	)
	(segment
		(start 107.499912 -55.500016)
		(end 107.00004 -55.000144)
		(width 0.104902)
		(layer "F.Cu")
		(net "PHY_DPB_TO_SCC_C_19_DP")
	)
	(via
		(at 107.00004 -55.000144)
		(size 0.4572)
		(drill 0.2032)
		(layers "F.Cu" "B.Cu")
		(net "PHY_DPB_TO_SCC_C_19_DP")
	)
	(segment
		(start 101.936042 -46.474888)
		(end 101.666802 -46.744128)
		(width 0.12446)
		(layer "B.Cu")
		(net "PHY_DPB_TO_SCC_C_19_DP")
	)
	(segment
		(start 101.666802 -47.127414)
		(end 104.731566 -50.192178)
		(width 0.12446)
		(layer "B.Cu")
		(net "PHY_DPB_TO_SCC_C_19_DP")
	)
	(segment
		(start 105.841292 -54.399942)
		(end 106.247692 -54.399942)
		(width 0.0889)
		(layer "B.Cu")
		(net "PHY_DPB_TO_SCC_C_19_DP")
	)
	(segment
		(start 101.666802 -46.744128)
		(end 101.666802 -47.127414)
		(width 0.12446)
		(layer "B.Cu")
		(net "PHY_DPB_TO_SCC_C_19_DP")
	)
	(segment
		(start 104.731566 -50.192178)
		(end 104.731566 -50.491644)
		(width 0.12446)
		(layer "B.Cu")
		(net "PHY_DPB_TO_SCC_C_19_DP")
	)
	(segment
		(start 104.596184 -50.649124)
		(end 104.596184 -53.17363)
		(width 0.0889)
		(layer "B.Cu")
		(net "PHY_DPB_TO_SCC_C_19_DP")
	)
	(segment
		(start 106.76128 -55.40502)
		(end 106.91114 -55.40502)
		(width 0.0889)
		(layer "B.Cu")
		(net "PHY_DPB_TO_SCC_C_19_DP")
	)
	(segment
		(start 101.666802 -44.907454)
		(end 101.666802 -45.832268)
		(width 0.12446)
		(layer "B.Cu")
		(net "PHY_DPB_TO_SCC_C_19_DP")
	)
	(segment
		(start 106.247692 -54.399942)
		(end 106.593894 -54.746144)
		(width 0.0889)
		(layer "B.Cu")
		(net "PHY_DPB_TO_SCC_C_19_DP")
	)
	(segment
		(start 101.936042 -46.101508)
		(end 101.936042 -46.474888)
		(width 0.12446)
		(layer "B.Cu")
		(net "PHY_DPB_TO_SCC_C_19_DP")
	)
	(segment
		(start 107.00004 -55.31612)
		(end 107.00004 -55.000144)
		(width 0.0889)
		(layer "B.Cu")
		(net "PHY_DPB_TO_SCC_C_19_DP")
	)
	(segment
		(start 104.596184 -53.17363)
		(end 104.830626 -53.408072)
		(width 0.0889)
		(layer "B.Cu")
		(net "PHY_DPB_TO_SCC_C_19_DP")
	)
	(segment
		(start 101.7778 -44.5008)
		(end 101.7778 -44.796456)
		(width 0.12446)
		(layer "B.Cu")
		(net "PHY_DPB_TO_SCC_C_19_DP")
	)
	(segment
		(start 105.253282 -53.408072)
		(end 105.6132 -53.76799)
		(width 0.0889)
		(layer "B.Cu")
		(net "PHY_DPB_TO_SCC_C_19_DP")
	)
	(segment
		(start 104.731566 -50.513742)
		(end 104.596184 -50.649124)
		(width 0.0889)
		(layer "B.Cu")
		(net "PHY_DPB_TO_SCC_C_19_DP")
	)
	(segment
		(start 104.830626 -53.408072)
		(end 105.253282 -53.408072)
		(width 0.0889)
		(layer "B.Cu")
		(net "PHY_DPB_TO_SCC_C_19_DP")
	)
	(segment
		(start 101.666802 -45.832268)
		(end 101.936042 -46.101508)
		(width 0.12446)
		(layer "B.Cu")
		(net "PHY_DPB_TO_SCC_C_19_DP")
	)
	(segment
		(start 106.593894 -54.746144)
		(end 106.593894 -55.237634)
		(width 0.0889)
		(layer "B.Cu")
		(net "PHY_DPB_TO_SCC_C_19_DP")
	)
	(segment
		(start 104.731566 -50.491644)
		(end 104.731566 -50.513742)
		(width 0.0889)
		(layer "B.Cu")
		(net "PHY_DPB_TO_SCC_C_19_DP")
	)
	(segment
		(start 105.6132 -54.17185)
		(end 105.841292 -54.399942)
		(width 0.0889)
		(layer "B.Cu")
		(net "PHY_DPB_TO_SCC_C_19_DP")
	)
	(segment
		(start 101.7778 -44.796456)
		(end 101.666802 -44.907454)
		(width 0.12446)
		(layer "B.Cu")
		(net "PHY_DPB_TO_SCC_C_19_DP")
	)
	(segment
		(start 105.6132 -53.76799)
		(end 105.6132 -54.17185)
		(width 0.0889)
		(layer "B.Cu")
		(net "PHY_DPB_TO_SCC_C_19_DP")
	)
	(arc
		(start 106.642916 -55.355998)
		(mid 106.697222 -55.392284)
		(end 106.76128 -55.40502)
		(width 0.0889)
		(layer "B.Cu")
		(net "PHY_DPB_TO_SCC_C_19_DP")
	)
	(arc
		(start 106.91114 -55.40502)
		(mid 106.974002 -55.378982)
		(end 107.00004 -55.31612)
		(width 0.0889)
		(layer "B.Cu")
		(net "PHY_DPB_TO_SCC_C_19_DP")
	)
	(arc
		(start 106.593894 -55.237634)
		(mid 106.606636 -55.30169)
		(end 106.642916 -55.355998)
		(width 0.0889)
		(layer "B.Cu")
		(net "PHY_DPB_TO_SCC_C_19_DP")
	)
	(segment
		(start 107.499912 -56.500014)
		(end 107.00004 -56.000142)
		(width 0.104902)
		(layer "F.Cu")
		(net "PHY_DPB_TO_SCC_C_19_DN")
	)
	(via
		(at 107.00004 -56.000142)
		(size 0.4572)
		(drill 0.2032)
		(layers "F.Cu" "B.Cu")
		(net "PHY_DPB_TO_SCC_C_19_DN")
	)
	(segment
		(start 105.4227 -54.250844)
		(end 105.762298 -54.590442)
		(width 0.0889)
		(layer "B.Cu")
		(net "PHY_DPB_TO_SCC_C_19_DN")
	)
	(segment
		(start 104.751632 -53.598572)
		(end 105.174288 -53.598572)
		(width 0.0889)
		(layer "B.Cu")
		(net "PHY_DPB_TO_SCC_C_19_DN")
	)
	(segment
		(start 104.325166 -50.36058)
		(end 104.325166 -50.491644)
		(width 0.12446)
		(layer "B.Cu")
		(net "PHY_DPB_TO_SCC_C_19_DN")
	)
	(segment
		(start 104.405684 -53.252624)
		(end 104.751632 -53.598572)
		(width 0.0889)
		(layer "B.Cu")
		(net "PHY_DPB_TO_SCC_C_19_DN")
	)
	(segment
		(start 107.00004 -55.68442)
		(end 107.00004 -56.000142)
		(width 0.0889)
		(layer "B.Cu")
		(net "PHY_DPB_TO_SCC_C_19_DN")
	)
	(segment
		(start 104.325166 -50.513742)
		(end 104.405684 -50.59426)
		(width 0.0889)
		(layer "B.Cu")
		(net "PHY_DPB_TO_SCC_C_19_DN")
	)
	(segment
		(start 101.219 -44.798996)
		(end 101.260402 -44.840398)
		(width 0.12446)
		(layer "B.Cu")
		(net "PHY_DPB_TO_SCC_C_19_DN")
	)
	(segment
		(start 106.165904 -54.590442)
		(end 106.403394 -54.827932)
		(width 0.0889)
		(layer "B.Cu")
		(net "PHY_DPB_TO_SCC_C_19_DN")
	)
	(segment
		(start 105.4227 -53.846984)
		(end 105.4227 -54.250844)
		(width 0.0889)
		(layer "B.Cu")
		(net "PHY_DPB_TO_SCC_C_19_DN")
	)
	(segment
		(start 106.403394 -54.827932)
		(end 106.403394 -55.237634)
		(width 0.0889)
		(layer "B.Cu")
		(net "PHY_DPB_TO_SCC_C_19_DN")
	)
	(segment
		(start 105.762298 -54.590442)
		(end 106.165904 -54.590442)
		(width 0.0889)
		(layer "B.Cu")
		(net "PHY_DPB_TO_SCC_C_19_DN")
	)
	(segment
		(start 105.174288 -53.598572)
		(end 105.4227 -53.846984)
		(width 0.0889)
		(layer "B.Cu")
		(net "PHY_DPB_TO_SCC_C_19_DN")
	)
	(segment
		(start 104.325166 -50.491644)
		(end 104.325166 -50.513742)
		(width 0.0889)
		(layer "B.Cu")
		(net "PHY_DPB_TO_SCC_C_19_DN")
	)
	(segment
		(start 101.260402 -47.295816)
		(end 104.325166 -50.36058)
		(width 0.12446)
		(layer "B.Cu")
		(net "PHY_DPB_TO_SCC_C_19_DN")
	)
	(segment
		(start 104.405684 -50.59426)
		(end 104.405684 -53.252624)
		(width 0.0889)
		(layer "B.Cu")
		(net "PHY_DPB_TO_SCC_C_19_DN")
	)
	(segment
		(start 101.260402 -44.840398)
		(end 101.260402 -47.295816)
		(width 0.12446)
		(layer "B.Cu")
		(net "PHY_DPB_TO_SCC_C_19_DN")
	)
	(segment
		(start 101.219 -44.5008)
		(end 101.219 -44.798996)
		(width 0.12446)
		(layer "B.Cu")
		(net "PHY_DPB_TO_SCC_C_19_DN")
	)
	(segment
		(start 106.76128 -55.59552)
		(end 106.91114 -55.59552)
		(width 0.0889)
		(layer "B.Cu")
		(net "PHY_DPB_TO_SCC_C_19_DN")
	)
	(arc
		(start 106.91114 -55.59552)
		(mid 106.974002 -55.621558)
		(end 107.00004 -55.68442)
		(width 0.0889)
		(layer "B.Cu")
		(net "PHY_DPB_TO_SCC_C_19_DN")
	)
	(arc
		(start 106.508042 -55.490872)
		(mid 106.624258 -55.568369)
		(end 106.76128 -55.59552)
		(width 0.0889)
		(layer "B.Cu")
		(net "PHY_DPB_TO_SCC_C_19_DN")
	)
	(arc
		(start 106.403394 -55.237634)
		(mid 106.430538 -55.374659)
		(end 106.508042 -55.490872)
		(width 0.0889)
		(layer "B.Cu")
		(net "PHY_DPB_TO_SCC_C_19_DN")
	)
	(segment
		(start 106.499914 -55.500016)
		(end 106.000042 -55.000144)
		(width 0.104902)
		(layer "F.Cu")
		(net "PHY_DPB_TO_SCC_C_18_DP")
	)
	(via
		(at 106.000042 -55.000144)
		(size 0.4572)
		(drill 0.2032)
		(layers "F.Cu" "B.Cu")
		(net "PHY_DPB_TO_SCC_C_18_DP")
	)
	(segment
		(start 101.53396 -48.11268)
		(end 103.409496 -49.988216)
		(width 0.12446)
		(layer "B.Cu")
		(net "PHY_DPB_TO_SCC_C_18_DP")
	)
	(segment
		(start 103.596186 -53.1622)
		(end 103.850186 -53.4162)
		(width 0.0889)
		(layer "B.Cu")
		(net "PHY_DPB_TO_SCC_C_18_DP")
	)
	(segment
		(start 100.2538 -44.5008)
		(end 100.2538 -44.736512)
		(width 0.12446)
		(layer "B.Cu")
		(net "PHY_DPB_TO_SCC_C_18_DP")
	)
	(segment
		(start 105.254552 -54.40426)
		(end 105.593896 -54.743604)
		(width 0.0889)
		(layer "B.Cu")
		(net "PHY_DPB_TO_SCC_C_18_DP")
	)
	(segment
		(start 103.596186 -50.321972)
		(end 103.596186 -53.1622)
		(width 0.0889)
		(layer "B.Cu")
		(net "PHY_DPB_TO_SCC_C_18_DP")
	)
	(segment
		(start 105.593896 -54.743604)
		(end 105.593896 -55.237634)
		(width 0.0889)
		(layer "B.Cu")
		(net "PHY_DPB_TO_SCC_C_18_DP")
	)
	(segment
		(start 100.453444 -48.11268)
		(end 101.53396 -48.11268)
		(width 0.12446)
		(layer "B.Cu")
		(net "PHY_DPB_TO_SCC_C_18_DP")
	)
	(segment
		(start 100.446586 -45.866304)
		(end 100.164646 -46.148244)
		(width 0.12446)
		(layer "B.Cu")
		(net "PHY_DPB_TO_SCC_C_18_DP")
	)
	(segment
		(start 100.446586 -47.176944)
		(end 100.164646 -47.458884)
		(width 0.12446)
		(layer "B.Cu")
		(net "PHY_DPB_TO_SCC_C_18_DP")
	)
	(segment
		(start 103.409496 -49.988216)
		(end 103.409496 -50.135282)
		(width 0.0889)
		(layer "B.Cu")
		(net "PHY_DPB_TO_SCC_C_18_DP")
	)
	(segment
		(start 100.164646 -47.823882)
		(end 100.453444 -48.11268)
		(width 0.12446)
		(layer "B.Cu")
		(net "PHY_DPB_TO_SCC_C_18_DP")
	)
	(segment
		(start 100.164646 -47.458884)
		(end 100.164646 -47.823882)
		(width 0.12446)
		(layer "B.Cu")
		(net "PHY_DPB_TO_SCC_C_18_DP")
	)
	(segment
		(start 100.446586 -45.492924)
		(end 100.446586 -45.866304)
		(width 0.12446)
		(layer "B.Cu")
		(net "PHY_DPB_TO_SCC_C_18_DP")
	)
	(segment
		(start 105.761282 -55.40502)
		(end 105.911142 -55.40502)
		(width 0.0889)
		(layer "B.Cu")
		(net "PHY_DPB_TO_SCC_C_18_DP")
	)
	(segment
		(start 103.409496 -50.135282)
		(end 103.596186 -50.321972)
		(width 0.0889)
		(layer "B.Cu")
		(net "PHY_DPB_TO_SCC_C_18_DP")
	)
	(segment
		(start 100.2538 -44.736512)
		(end 100.164646 -44.825666)
		(width 0.12446)
		(layer "B.Cu")
		(net "PHY_DPB_TO_SCC_C_18_DP")
	)
	(segment
		(start 103.850186 -53.4162)
		(end 104.253284 -53.4162)
		(width 0.0889)
		(layer "B.Cu")
		(net "PHY_DPB_TO_SCC_C_18_DP")
	)
	(segment
		(start 104.83088 -54.40426)
		(end 105.254552 -54.40426)
		(width 0.0889)
		(layer "B.Cu")
		(net "PHY_DPB_TO_SCC_C_18_DP")
	)
	(segment
		(start 104.596184 -54.169564)
		(end 104.83088 -54.40426)
		(width 0.0889)
		(layer "B.Cu")
		(net "PHY_DPB_TO_SCC_C_18_DP")
	)
	(segment
		(start 100.164646 -45.210984)
		(end 100.446586 -45.492924)
		(width 0.12446)
		(layer "B.Cu")
		(net "PHY_DPB_TO_SCC_C_18_DP")
	)
	(segment
		(start 104.253284 -53.4162)
		(end 104.596184 -53.7591)
		(width 0.0889)
		(layer "B.Cu")
		(net "PHY_DPB_TO_SCC_C_18_DP")
	)
	(segment
		(start 100.164646 -46.521624)
		(end 100.446586 -46.803564)
		(width 0.12446)
		(layer "B.Cu")
		(net "PHY_DPB_TO_SCC_C_18_DP")
	)
	(segment
		(start 100.164646 -46.148244)
		(end 100.164646 -46.521624)
		(width 0.12446)
		(layer "B.Cu")
		(net "PHY_DPB_TO_SCC_C_18_DP")
	)
	(segment
		(start 104.596184 -53.7591)
		(end 104.596184 -54.169564)
		(width 0.0889)
		(layer "B.Cu")
		(net "PHY_DPB_TO_SCC_C_18_DP")
	)
	(segment
		(start 100.446586 -46.803564)
		(end 100.446586 -47.176944)
		(width 0.12446)
		(layer "B.Cu")
		(net "PHY_DPB_TO_SCC_C_18_DP")
	)
	(segment
		(start 106.000042 -55.31612)
		(end 106.000042 -55.000144)
		(width 0.0889)
		(layer "B.Cu")
		(net "PHY_DPB_TO_SCC_C_18_DP")
	)
	(segment
		(start 100.164646 -44.825666)
		(end 100.164646 -45.210984)
		(width 0.12446)
		(layer "B.Cu")
		(net "PHY_DPB_TO_SCC_C_18_DP")
	)
	(arc
		(start 105.642918 -55.355998)
		(mid 105.697224 -55.392284)
		(end 105.761282 -55.40502)
		(width 0.0889)
		(layer "B.Cu")
		(net "PHY_DPB_TO_SCC_C_18_DP")
	)
	(arc
		(start 105.911142 -55.40502)
		(mid 105.974004 -55.378982)
		(end 106.000042 -55.31612)
		(width 0.0889)
		(layer "B.Cu")
		(net "PHY_DPB_TO_SCC_C_18_DP")
	)
	(arc
		(start 105.593896 -55.237634)
		(mid 105.606638 -55.30169)
		(end 105.642918 -55.355998)
		(width 0.0889)
		(layer "B.Cu")
		(net "PHY_DPB_TO_SCC_C_18_DP")
	)
	(segment
		(start 106.499914 -56.500014)
		(end 106.000042 -56.000142)
		(width 0.104902)
		(layer "F.Cu")
		(net "PHY_DPB_TO_SCC_C_18_DN")
	)
	(via
		(at 106.000042 -56.000142)
		(size 0.4572)
		(drill 0.2032)
		(layers "F.Cu" "B.Cu")
		(net "PHY_DPB_TO_SCC_C_18_DN")
	)
	(segment
		(start 103.405686 -53.241194)
		(end 103.771192 -53.6067)
		(width 0.0889)
		(layer "B.Cu")
		(net "PHY_DPB_TO_SCC_C_18_DN")
	)
	(segment
		(start 103.121968 -50.27549)
		(end 103.28021 -50.27549)
		(width 0.0889)
		(layer "B.Cu")
		(net "PHY_DPB_TO_SCC_C_18_DN")
	)
	(segment
		(start 100.285042 -48.51908)
		(end 101.365558 -48.51908)
		(width 0.12446)
		(layer "B.Cu")
		(net "PHY_DPB_TO_SCC_C_18_DN")
	)
	(segment
		(start 105.403396 -54.822598)
		(end 105.403396 -55.237634)
		(width 0.0889)
		(layer "B.Cu")
		(net "PHY_DPB_TO_SCC_C_18_DN")
	)
	(segment
		(start 105.761282 -55.59552)
		(end 105.911142 -55.59552)
		(width 0.0889)
		(layer "B.Cu")
		(net "PHY_DPB_TO_SCC_C_18_DN")
	)
	(segment
		(start 104.405684 -54.248558)
		(end 104.751886 -54.59476)
		(width 0.0889)
		(layer "B.Cu")
		(net "PHY_DPB_TO_SCC_C_18_DN")
	)
	(segment
		(start 104.751886 -54.59476)
		(end 105.175558 -54.59476)
		(width 0.0889)
		(layer "B.Cu")
		(net "PHY_DPB_TO_SCC_C_18_DN")
	)
	(segment
		(start 104.17429 -53.6067)
		(end 104.405684 -53.838094)
		(width 0.0889)
		(layer "B.Cu")
		(net "PHY_DPB_TO_SCC_C_18_DN")
	)
	(segment
		(start 103.405686 -50.400966)
		(end 103.405686 -53.241194)
		(width 0.0889)
		(layer "B.Cu")
		(net "PHY_DPB_TO_SCC_C_18_DN")
	)
	(segment
		(start 103.771192 -53.6067)
		(end 104.17429 -53.6067)
		(width 0.0889)
		(layer "B.Cu")
		(net "PHY_DPB_TO_SCC_C_18_DN")
	)
	(segment
		(start 99.695 -44.7294)
		(end 99.758246 -44.792646)
		(width 0.12446)
		(layer "B.Cu")
		(net "PHY_DPB_TO_SCC_C_18_DN")
	)
	(segment
		(start 106.000042 -55.68442)
		(end 106.000042 -56.000142)
		(width 0.0889)
		(layer "B.Cu")
		(net "PHY_DPB_TO_SCC_C_18_DN")
	)
	(segment
		(start 103.28021 -50.27549)
		(end 103.405686 -50.400966)
		(width 0.0889)
		(layer "B.Cu")
		(net "PHY_DPB_TO_SCC_C_18_DN")
	)
	(segment
		(start 99.758246 -47.992284)
		(end 100.285042 -48.51908)
		(width 0.12446)
		(layer "B.Cu")
		(net "PHY_DPB_TO_SCC_C_18_DN")
	)
	(segment
		(start 104.405684 -53.838094)
		(end 104.405684 -54.248558)
		(width 0.0889)
		(layer "B.Cu")
		(net "PHY_DPB_TO_SCC_C_18_DN")
	)
	(segment
		(start 101.365558 -48.51908)
		(end 103.121968 -50.27549)
		(width 0.12446)
		(layer "B.Cu")
		(net "PHY_DPB_TO_SCC_C_18_DN")
	)
	(segment
		(start 105.175558 -54.59476)
		(end 105.403396 -54.822598)
		(width 0.0889)
		(layer "B.Cu")
		(net "PHY_DPB_TO_SCC_C_18_DN")
	)
	(segment
		(start 99.758246 -44.792646)
		(end 99.758246 -47.992284)
		(width 0.12446)
		(layer "B.Cu")
		(net "PHY_DPB_TO_SCC_C_18_DN")
	)
	(segment
		(start 99.695 -44.5008)
		(end 99.695 -44.7294)
		(width 0.12446)
		(layer "B.Cu")
		(net "PHY_DPB_TO_SCC_C_18_DN")
	)
	(arc
		(start 105.911142 -55.59552)
		(mid 105.974004 -55.621558)
		(end 106.000042 -55.68442)
		(width 0.0889)
		(layer "B.Cu")
		(net "PHY_DPB_TO_SCC_C_18_DN")
	)
	(arc
		(start 105.508044 -55.490872)
		(mid 105.62426 -55.568369)
		(end 105.761282 -55.59552)
		(width 0.0889)
		(layer "B.Cu")
		(net "PHY_DPB_TO_SCC_C_18_DN")
	)
	(arc
		(start 105.403396 -55.237634)
		(mid 105.43054 -55.374659)
		(end 105.508044 -55.490872)
		(width 0.0889)
		(layer "B.Cu")
		(net "PHY_DPB_TO_SCC_C_18_DN")
	)
	(segment
		(start 105.499916 -55.500016)
		(end 105.000044 -55.000144)
		(width 0.104902)
		(layer "F.Cu")
		(net "PHY_DPB_TO_SCC_C_17_DP")
	)
	(via
		(at 105.000044 -55.000144)
		(size 0.4572)
		(drill 0.2032)
		(layers "F.Cu" "B.Cu")
		(net "PHY_DPB_TO_SCC_C_17_DP")
	)
	(segment
		(start 98.911156 -45.75683)
		(end 98.911156 -46.13021)
		(width 0.12446)
		(layer "B.Cu")
		(net "PHY_DPB_TO_SCC_C_17_DP")
	)
	(segment
		(start 98.7298 -44.879768)
		(end 98.641916 -44.967652)
		(width 0.12446)
		(layer "B.Cu")
		(net "PHY_DPB_TO_SCC_C_17_DP")
	)
	(segment
		(start 103.595424 -53.74513)
		(end 103.595424 -54.138068)
		(width 0.0889)
		(layer "B.Cu")
		(net "PHY_DPB_TO_SCC_C_17_DP")
	)
	(segment
		(start 98.911156 -46.13021)
		(end 98.641916 -46.39945)
		(width 0.12446)
		(layer "B.Cu")
		(net "PHY_DPB_TO_SCC_C_17_DP")
	)
	(segment
		(start 104.593898 -54.746144)
		(end 104.593898 -55.237634)
		(width 0.0889)
		(layer "B.Cu")
		(net "PHY_DPB_TO_SCC_C_17_DP")
	)
	(segment
		(start 99.691952 -49.102264)
		(end 101.393498 -49.102264)
		(width 0.12446)
		(layer "B.Cu")
		(net "PHY_DPB_TO_SCC_C_17_DP")
	)
	(segment
		(start 98.911156 -47.41545)
		(end 98.641916 -47.68469)
		(width 0.12446)
		(layer "B.Cu")
		(net "PHY_DPB_TO_SCC_C_17_DP")
	)
	(segment
		(start 101.393498 -49.102264)
		(end 102.45217 -50.160936)
		(width 0.12446)
		(layer "B.Cu")
		(net "PHY_DPB_TO_SCC_C_17_DP")
	)
	(segment
		(start 98.7298 -44.5008)
		(end 98.7298 -44.879768)
		(width 0.12446)
		(layer "B.Cu")
		(net "PHY_DPB_TO_SCC_C_17_DP")
	)
	(segment
		(start 103.595424 -54.138068)
		(end 103.840534 -54.383178)
		(width 0.0889)
		(layer "B.Cu")
		(net "PHY_DPB_TO_SCC_C_17_DP")
	)
	(segment
		(start 98.641916 -48.052228)
		(end 99.691952 -49.102264)
		(width 0.12446)
		(layer "B.Cu")
		(net "PHY_DPB_TO_SCC_C_17_DP")
	)
	(segment
		(start 102.59568 -53.172614)
		(end 102.83063 -53.407564)
		(width 0.0889)
		(layer "B.Cu")
		(net "PHY_DPB_TO_SCC_C_17_DP")
	)
	(segment
		(start 103.257858 -53.407564)
		(end 103.595424 -53.74513)
		(width 0.0889)
		(layer "B.Cu")
		(net "PHY_DPB_TO_SCC_C_17_DP")
	)
	(segment
		(start 103.840534 -54.383178)
		(end 104.230932 -54.383178)
		(width 0.0889)
		(layer "B.Cu")
		(net "PHY_DPB_TO_SCC_C_17_DP")
	)
	(segment
		(start 98.641916 -45.48759)
		(end 98.911156 -45.75683)
		(width 0.12446)
		(layer "B.Cu")
		(net "PHY_DPB_TO_SCC_C_17_DP")
	)
	(segment
		(start 102.45217 -50.160936)
		(end 102.446582 -50.166524)
		(width 0.0889)
		(layer "B.Cu")
		(net "PHY_DPB_TO_SCC_C_17_DP")
	)
	(segment
		(start 98.641916 -47.68469)
		(end 98.641916 -48.052228)
		(width 0.12446)
		(layer "B.Cu")
		(net "PHY_DPB_TO_SCC_C_17_DP")
	)
	(segment
		(start 102.446582 -50.305208)
		(end 102.59568 -50.454306)
		(width 0.0889)
		(layer "B.Cu")
		(net "PHY_DPB_TO_SCC_C_17_DP")
	)
	(segment
		(start 102.83063 -53.407564)
		(end 103.257858 -53.407564)
		(width 0.0889)
		(layer "B.Cu")
		(net "PHY_DPB_TO_SCC_C_17_DP")
	)
	(segment
		(start 102.59568 -50.454306)
		(end 102.59568 -53.172614)
		(width 0.0889)
		(layer "B.Cu")
		(net "PHY_DPB_TO_SCC_C_17_DP")
	)
	(segment
		(start 102.446582 -50.166524)
		(end 102.446582 -50.305208)
		(width 0.0889)
		(layer "B.Cu")
		(net "PHY_DPB_TO_SCC_C_17_DP")
	)
	(segment
		(start 98.641916 -44.967652)
		(end 98.641916 -45.48759)
		(width 0.12446)
		(layer "B.Cu")
		(net "PHY_DPB_TO_SCC_C_17_DP")
	)
	(segment
		(start 104.761284 -55.40502)
		(end 104.911144 -55.40502)
		(width 0.0889)
		(layer "B.Cu")
		(net "PHY_DPB_TO_SCC_C_17_DP")
	)
	(segment
		(start 105.000044 -55.31612)
		(end 105.000044 -55.000144)
		(width 0.0889)
		(layer "B.Cu")
		(net "PHY_DPB_TO_SCC_C_17_DP")
	)
	(segment
		(start 98.641916 -46.39945)
		(end 98.641916 -46.77283)
		(width 0.12446)
		(layer "B.Cu")
		(net "PHY_DPB_TO_SCC_C_17_DP")
	)
	(segment
		(start 104.230932 -54.383178)
		(end 104.593898 -54.746144)
		(width 0.0889)
		(layer "B.Cu")
		(net "PHY_DPB_TO_SCC_C_17_DP")
	)
	(segment
		(start 98.911156 -47.04207)
		(end 98.911156 -47.41545)
		(width 0.12446)
		(layer "B.Cu")
		(net "PHY_DPB_TO_SCC_C_17_DP")
	)
	(segment
		(start 98.641916 -46.77283)
		(end 98.911156 -47.04207)
		(width 0.12446)
		(layer "B.Cu")
		(net "PHY_DPB_TO_SCC_C_17_DP")
	)
	(arc
		(start 104.593898 -55.237634)
		(mid 104.60664 -55.30169)
		(end 104.64292 -55.355998)
		(width 0.0889)
		(layer "B.Cu")
		(net "PHY_DPB_TO_SCC_C_17_DP")
	)
	(arc
		(start 104.64292 -55.355998)
		(mid 104.697226 -55.392284)
		(end 104.761284 -55.40502)
		(width 0.0889)
		(layer "B.Cu")
		(net "PHY_DPB_TO_SCC_C_17_DP")
	)
	(arc
		(start 104.911144 -55.40502)
		(mid 104.974006 -55.378982)
		(end 105.000044 -55.31612)
		(width 0.0889)
		(layer "B.Cu")
		(net "PHY_DPB_TO_SCC_C_17_DP")
	)
	(segment
		(start 105.499916 -56.500014)
		(end 105.000044 -56.000142)
		(width 0.104902)
		(layer "F.Cu")
		(net "PHY_DPB_TO_SCC_C_17_DN")
	)
	(via
		(at 105.000044 -56.000142)
		(size 0.4572)
		(drill 0.2032)
		(layers "F.Cu" "B.Cu")
		(net "PHY_DPB_TO_SCC_C_17_DN")
	)
	(segment
		(start 98.235516 -48.22063)
		(end 99.52355 -49.508664)
		(width 0.12446)
		(layer "B.Cu")
		(net "PHY_DPB_TO_SCC_C_17_DN")
	)
	(segment
		(start 102.15626 -50.439828)
		(end 102.311708 -50.439828)
		(width 0.0889)
		(layer "B.Cu")
		(net "PHY_DPB_TO_SCC_C_17_DN")
	)
	(segment
		(start 102.751636 -53.598064)
		(end 103.178864 -53.598064)
		(width 0.0889)
		(layer "B.Cu")
		(net "PHY_DPB_TO_SCC_C_17_DN")
	)
	(segment
		(start 98.171 -44.5008)
		(end 98.171 -44.879768)
		(width 0.12446)
		(layer "B.Cu")
		(net "PHY_DPB_TO_SCC_C_17_DN")
	)
	(segment
		(start 101.225096 -49.508664)
		(end 102.15626 -50.439828)
		(width 0.12446)
		(layer "B.Cu")
		(net "PHY_DPB_TO_SCC_C_17_DN")
	)
	(segment
		(start 102.40518 -50.5333)
		(end 102.40518 -53.251608)
		(width 0.0889)
		(layer "B.Cu")
		(net "PHY_DPB_TO_SCC_C_17_DN")
	)
	(segment
		(start 104.761284 -55.59552)
		(end 104.911144 -55.59552)
		(width 0.0889)
		(layer "B.Cu")
		(net "PHY_DPB_TO_SCC_C_17_DN")
	)
	(segment
		(start 104.403398 -54.827932)
		(end 104.403398 -55.237634)
		(width 0.0889)
		(layer "B.Cu")
		(net "PHY_DPB_TO_SCC_C_17_DN")
	)
	(segment
		(start 104.149144 -54.573678)
		(end 104.403398 -54.827932)
		(width 0.0889)
		(layer "B.Cu")
		(net "PHY_DPB_TO_SCC_C_17_DN")
	)
	(segment
		(start 98.171 -44.879768)
		(end 98.235516 -44.944284)
		(width 0.12446)
		(layer "B.Cu")
		(net "PHY_DPB_TO_SCC_C_17_DN")
	)
	(segment
		(start 103.178864 -53.598064)
		(end 103.404924 -53.824124)
		(width 0.0889)
		(layer "B.Cu")
		(net "PHY_DPB_TO_SCC_C_17_DN")
	)
	(segment
		(start 102.311708 -50.439828)
		(end 102.40518 -50.5333)
		(width 0.0889)
		(layer "B.Cu")
		(net "PHY_DPB_TO_SCC_C_17_DN")
	)
	(segment
		(start 103.404924 -53.824124)
		(end 103.404924 -54.217062)
		(width 0.0889)
		(layer "B.Cu")
		(net "PHY_DPB_TO_SCC_C_17_DN")
	)
	(segment
		(start 103.76154 -54.573678)
		(end 104.149144 -54.573678)
		(width 0.0889)
		(layer "B.Cu")
		(net "PHY_DPB_TO_SCC_C_17_DN")
	)
	(segment
		(start 98.235516 -44.944284)
		(end 98.235516 -48.22063)
		(width 0.12446)
		(layer "B.Cu")
		(net "PHY_DPB_TO_SCC_C_17_DN")
	)
	(segment
		(start 105.000044 -55.68442)
		(end 105.000044 -56.000142)
		(width 0.0889)
		(layer "B.Cu")
		(net "PHY_DPB_TO_SCC_C_17_DN")
	)
	(segment
		(start 99.52355 -49.508664)
		(end 101.225096 -49.508664)
		(width 0.12446)
		(layer "B.Cu")
		(net "PHY_DPB_TO_SCC_C_17_DN")
	)
	(segment
		(start 103.404924 -54.217062)
		(end 103.76154 -54.573678)
		(width 0.0889)
		(layer "B.Cu")
		(net "PHY_DPB_TO_SCC_C_17_DN")
	)
	(segment
		(start 102.40518 -53.251608)
		(end 102.751636 -53.598064)
		(width 0.0889)
		(layer "B.Cu")
		(net "PHY_DPB_TO_SCC_C_17_DN")
	)
	(arc
		(start 104.508046 -55.490872)
		(mid 104.624262 -55.568369)
		(end 104.761284 -55.59552)
		(width 0.0889)
		(layer "B.Cu")
		(net "PHY_DPB_TO_SCC_C_17_DN")
	)
	(arc
		(start 104.403398 -55.237634)
		(mid 104.430542 -55.374659)
		(end 104.508046 -55.490872)
		(width 0.0889)
		(layer "B.Cu")
		(net "PHY_DPB_TO_SCC_C_17_DN")
	)
	(arc
		(start 104.911144 -55.59552)
		(mid 104.974006 -55.621558)
		(end 105.000044 -55.68442)
		(width 0.0889)
		(layer "B.Cu")
		(net "PHY_DPB_TO_SCC_C_17_DN")
	)
	(segment
		(start 104.499918 -55.500016)
		(end 104.000046 -55.000144)
		(width 0.104902)
		(layer "F.Cu")
		(net "PHY_DPB_TO_SCC_C_16_DP")
	)
	(via
		(at 104.000046 -55.000144)
		(size 0.4572)
		(drill 0.2032)
		(layers "F.Cu" "B.Cu")
		(net "PHY_DPB_TO_SCC_C_16_DP")
	)
	(segment
		(start 103.252778 -54.40172)
		(end 103.5939 -54.742842)
		(width 0.0889)
		(layer "B.Cu")
		(net "PHY_DPB_TO_SCC_C_16_DP")
	)
	(segment
		(start 101.596698 -51.68646)
		(end 101.596698 -53.168804)
		(width 0.0889)
		(layer "B.Cu")
		(net "PHY_DPB_TO_SCC_C_16_DP")
	)
	(segment
		(start 102.25659 -53.4162)
		(end 102.597204 -53.756814)
		(width 0.0889)
		(layer "B.Cu")
		(net "PHY_DPB_TO_SCC_C_16_DP")
	)
	(segment
		(start 99.443794 -50.273204)
		(end 99.551744 -50.381154)
		(width 0.0889)
		(layer "B.Cu")
		(net "PHY_DPB_TO_SCC_C_16_DP")
	)
	(segment
		(start 101.844094 -53.4162)
		(end 102.25659 -53.4162)
		(width 0.0889)
		(layer "B.Cu")
		(net "PHY_DPB_TO_SCC_C_16_DP")
	)
	(segment
		(start 104.000046 -55.31612)
		(end 104.000046 -55.000144)
		(width 0.0889)
		(layer "B.Cu")
		(net "PHY_DPB_TO_SCC_C_16_DP")
	)
	(segment
		(start 97.774506 -48.692562)
		(end 98.038412 -48.956722)
		(width 0.12446)
		(layer "B.Cu")
		(net "PHY_DPB_TO_SCC_C_16_DP")
	)
	(segment
		(start 97.153222 -46.503336)
		(end 97.422462 -46.772576)
		(width 0.12446)
		(layer "B.Cu")
		(net "PHY_DPB_TO_SCC_C_16_DP")
	)
	(segment
		(start 98.038412 -48.956722)
		(end 98.038412 -49.337468)
		(width 0.12446)
		(layer "B.Cu")
		(net "PHY_DPB_TO_SCC_C_16_DP")
	)
	(segment
		(start 102.597204 -54.169564)
		(end 102.82936 -54.40172)
		(width 0.0889)
		(layer "B.Cu")
		(net "PHY_DPB_TO_SCC_C_16_DP")
	)
	(segment
		(start 98.038412 -49.337468)
		(end 98.974148 -50.273204)
		(width 0.12446)
		(layer "B.Cu")
		(net "PHY_DPB_TO_SCC_C_16_DP")
	)
	(segment
		(start 100.796344 -51.386994)
		(end 101.297232 -51.386994)
		(width 0.0889)
		(layer "B.Cu")
		(net "PHY_DPB_TO_SCC_C_16_DP")
	)
	(segment
		(start 98.974148 -50.273204)
		(end 99.421696 -50.273204)
		(width 0.12446)
		(layer "B.Cu")
		(net "PHY_DPB_TO_SCC_C_16_DP")
	)
	(segment
		(start 102.597204 -53.756814)
		(end 102.597204 -54.169564)
		(width 0.0889)
		(layer "B.Cu")
		(net "PHY_DPB_TO_SCC_C_16_DP")
	)
	(segment
		(start 97.422462 -45.860716)
		(end 97.153222 -46.129956)
		(width 0.12446)
		(layer "B.Cu")
		(net "PHY_DPB_TO_SCC_C_16_DP")
	)
	(segment
		(start 97.2058 -44.7294)
		(end 97.153222 -44.781978)
		(width 0.12446)
		(layer "B.Cu")
		(net "PHY_DPB_TO_SCC_C_16_DP")
	)
	(segment
		(start 102.82936 -54.40172)
		(end 103.252778 -54.40172)
		(width 0.0889)
		(layer "B.Cu")
		(net "PHY_DPB_TO_SCC_C_16_DP")
	)
	(segment
		(start 97.2058 -44.5008)
		(end 97.2058 -44.7294)
		(width 0.12446)
		(layer "B.Cu")
		(net "PHY_DPB_TO_SCC_C_16_DP")
	)
	(segment
		(start 100.229416 -50.381154)
		(end 100.607876 -50.759614)
		(width 0.0889)
		(layer "B.Cu")
		(net "PHY_DPB_TO_SCC_C_16_DP")
	)
	(segment
		(start 99.421696 -50.273204)
		(end 99.443794 -50.273204)
		(width 0.0889)
		(layer "B.Cu")
		(net "PHY_DPB_TO_SCC_C_16_DP")
	)
	(segment
		(start 97.153222 -44.781978)
		(end 97.153222 -45.218096)
		(width 0.12446)
		(layer "B.Cu")
		(net "PHY_DPB_TO_SCC_C_16_DP")
	)
	(segment
		(start 97.153222 -47.415196)
		(end 97.153222 -48.452278)
		(width 0.12446)
		(layer "B.Cu")
		(net "PHY_DPB_TO_SCC_C_16_DP")
	)
	(segment
		(start 103.5939 -54.742842)
		(end 103.5939 -55.237634)
		(width 0.0889)
		(layer "B.Cu")
		(net "PHY_DPB_TO_SCC_C_16_DP")
	)
	(segment
		(start 99.551744 -50.381154)
		(end 100.229416 -50.381154)
		(width 0.0889)
		(layer "B.Cu")
		(net "PHY_DPB_TO_SCC_C_16_DP")
	)
	(segment
		(start 100.607876 -51.198526)
		(end 100.796344 -51.386994)
		(width 0.0889)
		(layer "B.Cu")
		(net "PHY_DPB_TO_SCC_C_16_DP")
	)
	(segment
		(start 97.153222 -48.452278)
		(end 97.393506 -48.692562)
		(width 0.12446)
		(layer "B.Cu")
		(net "PHY_DPB_TO_SCC_C_16_DP")
	)
	(segment
		(start 97.393506 -48.692562)
		(end 97.774506 -48.692562)
		(width 0.12446)
		(layer "B.Cu")
		(net "PHY_DPB_TO_SCC_C_16_DP")
	)
	(segment
		(start 103.761286 -55.40502)
		(end 103.911146 -55.40502)
		(width 0.0889)
		(layer "B.Cu")
		(net "PHY_DPB_TO_SCC_C_16_DP")
	)
	(segment
		(start 100.607876 -50.759614)
		(end 100.607876 -51.198526)
		(width 0.0889)
		(layer "B.Cu")
		(net "PHY_DPB_TO_SCC_C_16_DP")
	)
	(segment
		(start 97.422462 -46.772576)
		(end 97.422462 -47.145956)
		(width 0.12446)
		(layer "B.Cu")
		(net "PHY_DPB_TO_SCC_C_16_DP")
	)
	(segment
		(start 97.153222 -46.129956)
		(end 97.153222 -46.503336)
		(width 0.12446)
		(layer "B.Cu")
		(net "PHY_DPB_TO_SCC_C_16_DP")
	)
	(segment
		(start 97.422462 -47.145956)
		(end 97.153222 -47.415196)
		(width 0.12446)
		(layer "B.Cu")
		(net "PHY_DPB_TO_SCC_C_16_DP")
	)
	(segment
		(start 101.596698 -53.168804)
		(end 101.844094 -53.4162)
		(width 0.0889)
		(layer "B.Cu")
		(net "PHY_DPB_TO_SCC_C_16_DP")
	)
	(segment
		(start 101.297232 -51.386994)
		(end 101.596698 -51.68646)
		(width 0.0889)
		(layer "B.Cu")
		(net "PHY_DPB_TO_SCC_C_16_DP")
	)
	(segment
		(start 97.422462 -45.487336)
		(end 97.422462 -45.860716)
		(width 0.12446)
		(layer "B.Cu")
		(net "PHY_DPB_TO_SCC_C_16_DP")
	)
	(segment
		(start 97.153222 -45.218096)
		(end 97.422462 -45.487336)
		(width 0.12446)
		(layer "B.Cu")
		(net "PHY_DPB_TO_SCC_C_16_DP")
	)
	(arc
		(start 103.642922 -55.355998)
		(mid 103.697228 -55.392284)
		(end 103.761286 -55.40502)
		(width 0.0889)
		(layer "B.Cu")
		(net "PHY_DPB_TO_SCC_C_16_DP")
	)
	(arc
		(start 103.5939 -55.237634)
		(mid 103.606642 -55.30169)
		(end 103.642922 -55.355998)
		(width 0.0889)
		(layer "B.Cu")
		(net "PHY_DPB_TO_SCC_C_16_DP")
	)
	(arc
		(start 103.911146 -55.40502)
		(mid 103.974008 -55.378982)
		(end 104.000046 -55.31612)
		(width 0.0889)
		(layer "B.Cu")
		(net "PHY_DPB_TO_SCC_C_16_DP")
	)
	(segment
		(start 104.499918 -56.500014)
		(end 104.000046 -56.000142)
		(width 0.104902)
		(layer "F.Cu")
		(net "PHY_DPB_TO_SCC_C_16_DN")
	)
	(via
		(at 104.000046 -56.000142)
		(size 0.4572)
		(drill 0.2032)
		(layers "F.Cu" "B.Cu")
		(net "PHY_DPB_TO_SCC_C_16_DN")
	)
	(segment
		(start 101.406198 -53.247798)
		(end 101.7651 -53.6067)
		(width 0.0889)
		(layer "B.Cu")
		(net "PHY_DPB_TO_SCC_C_16_DN")
	)
	(segment
		(start 100.71735 -51.577494)
		(end 101.218238 -51.577494)
		(width 0.0889)
		(layer "B.Cu")
		(net "PHY_DPB_TO_SCC_C_16_DN")
	)
	(segment
		(start 103.761286 -55.59552)
		(end 103.911146 -55.59552)
		(width 0.0889)
		(layer "B.Cu")
		(net "PHY_DPB_TO_SCC_C_16_DN")
	)
	(segment
		(start 96.746822 -44.803822)
		(end 96.746822 -48.62068)
		(width 0.12446)
		(layer "B.Cu")
		(net "PHY_DPB_TO_SCC_C_16_DN")
	)
	(segment
		(start 99.443794 -50.679604)
		(end 99.551744 -50.571654)
		(width 0.0889)
		(layer "B.Cu")
		(net "PHY_DPB_TO_SCC_C_16_DN")
	)
	(segment
		(start 101.7651 -53.6067)
		(end 102.177596 -53.6067)
		(width 0.0889)
		(layer "B.Cu")
		(net "PHY_DPB_TO_SCC_C_16_DN")
	)
	(segment
		(start 104.000046 -55.68442)
		(end 104.000046 -56.000142)
		(width 0.0889)
		(layer "B.Cu")
		(net "PHY_DPB_TO_SCC_C_16_DN")
	)
	(segment
		(start 99.551744 -50.571654)
		(end 100.150422 -50.571654)
		(width 0.0889)
		(layer "B.Cu")
		(net "PHY_DPB_TO_SCC_C_16_DN")
	)
	(segment
		(start 102.406704 -54.248558)
		(end 102.750366 -54.59222)
		(width 0.0889)
		(layer "B.Cu")
		(net "PHY_DPB_TO_SCC_C_16_DN")
	)
	(segment
		(start 102.406704 -53.835808)
		(end 102.406704 -54.248558)
		(width 0.0889)
		(layer "B.Cu")
		(net "PHY_DPB_TO_SCC_C_16_DN")
	)
	(segment
		(start 96.746822 -48.62068)
		(end 98.805746 -50.679604)
		(width 0.12446)
		(layer "B.Cu")
		(net "PHY_DPB_TO_SCC_C_16_DN")
	)
	(segment
		(start 101.406198 -51.765454)
		(end 101.406198 -53.247798)
		(width 0.0889)
		(layer "B.Cu")
		(net "PHY_DPB_TO_SCC_C_16_DN")
	)
	(segment
		(start 100.417376 -50.838608)
		(end 100.417376 -51.27752)
		(width 0.0889)
		(layer "B.Cu")
		(net "PHY_DPB_TO_SCC_C_16_DN")
	)
	(segment
		(start 100.150422 -50.571654)
		(end 100.417376 -50.838608)
		(width 0.0889)
		(layer "B.Cu")
		(net "PHY_DPB_TO_SCC_C_16_DN")
	)
	(segment
		(start 99.421696 -50.679604)
		(end 99.443794 -50.679604)
		(width 0.0889)
		(layer "B.Cu")
		(net "PHY_DPB_TO_SCC_C_16_DN")
	)
	(segment
		(start 96.647 -44.704)
		(end 96.746822 -44.803822)
		(width 0.12446)
		(layer "B.Cu")
		(net "PHY_DPB_TO_SCC_C_16_DN")
	)
	(segment
		(start 102.750366 -54.59222)
		(end 103.173784 -54.59222)
		(width 0.0889)
		(layer "B.Cu")
		(net "PHY_DPB_TO_SCC_C_16_DN")
	)
	(segment
		(start 103.173784 -54.59222)
		(end 103.4034 -54.821836)
		(width 0.0889)
		(layer "B.Cu")
		(net "PHY_DPB_TO_SCC_C_16_DN")
	)
	(segment
		(start 98.805746 -50.679604)
		(end 99.421696 -50.679604)
		(width 0.12446)
		(layer "B.Cu")
		(net "PHY_DPB_TO_SCC_C_16_DN")
	)
	(segment
		(start 102.177596 -53.6067)
		(end 102.406704 -53.835808)
		(width 0.0889)
		(layer "B.Cu")
		(net "PHY_DPB_TO_SCC_C_16_DN")
	)
	(segment
		(start 96.647 -44.5008)
		(end 96.647 -44.704)
		(width 0.12446)
		(layer "B.Cu")
		(net "PHY_DPB_TO_SCC_C_16_DN")
	)
	(segment
		(start 100.417376 -51.27752)
		(end 100.71735 -51.577494)
		(width 0.0889)
		(layer "B.Cu")
		(net "PHY_DPB_TO_SCC_C_16_DN")
	)
	(segment
		(start 101.218238 -51.577494)
		(end 101.406198 -51.765454)
		(width 0.0889)
		(layer "B.Cu")
		(net "PHY_DPB_TO_SCC_C_16_DN")
	)
	(segment
		(start 103.4034 -54.821836)
		(end 103.4034 -55.237634)
		(width 0.0889)
		(layer "B.Cu")
		(net "PHY_DPB_TO_SCC_C_16_DN")
	)
	(arc
		(start 103.508048 -55.490872)
		(mid 103.624264 -55.568369)
		(end 103.761286 -55.59552)
		(width 0.0889)
		(layer "B.Cu")
		(net "PHY_DPB_TO_SCC_C_16_DN")
	)
	(arc
		(start 103.4034 -55.237634)
		(mid 103.430544 -55.374659)
		(end 103.508048 -55.490872)
		(width 0.0889)
		(layer "B.Cu")
		(net "PHY_DPB_TO_SCC_C_16_DN")
	)
	(arc
		(start 103.911146 -55.59552)
		(mid 103.974008 -55.621558)
		(end 104.000046 -55.68442)
		(width 0.0889)
		(layer "B.Cu")
		(net "PHY_DPB_TO_SCC_C_16_DN")
	)
	(segment
		(start 126.500128 -66.499994)
		(end 127 -66.000122)
		(width 0.104902)
		(layer "F.Cu")
		(net "PHY_DPB_TO_SCC_C_1_DP")
	)
	(via
		(at 127 -66.000122)
		(size 0.4572)
		(drill 0.2032)
		(layers "F.Cu" "B.Cu")
		(net "PHY_DPB_TO_SCC_C_1_DP")
	)
	(segment
		(start 132.328666 -66.027554)
		(end 131.955286 -66.027554)
		(width 0.12446)
		(layer "B.Cu")
		(net "PHY_DPB_TO_SCC_C_1_DP")
	)
	(segment
		(start 131.219956 -65.597024)
		(end 126.748032 -65.597024)
		(width 0.0889)
		(layer "B.Cu")
		(net "PHY_DPB_TO_SCC_C_1_DP")
	)
	(segment
		(start 131.955286 -66.027554)
		(end 131.675886 -65.748154)
		(width 0.12446)
		(layer "B.Cu")
		(net "PHY_DPB_TO_SCC_C_1_DP")
	)
	(segment
		(start 134.213854 -65.066418)
		(end 134.130796 -64.98336)
		(width 0.12446)
		(layer "B.Cu")
		(net "PHY_DPB_TO_SCC_C_1_DP")
	)
	(segment
		(start 133.099556 -65.748154)
		(end 132.608066 -65.748154)
		(width 0.12446)
		(layer "B.Cu")
		(net "PHY_DPB_TO_SCC_C_1_DP")
	)
	(segment
		(start 134.130796 -64.98336)
		(end 133.86435 -64.98336)
		(width 0.12446)
		(layer "B.Cu")
		(net "PHY_DPB_TO_SCC_C_1_DP")
	)
	(segment
		(start 132.608066 -65.748154)
		(end 132.328666 -66.027554)
		(width 0.12446)
		(layer "B.Cu")
		(net "PHY_DPB_TO_SCC_C_1_DP")
	)
	(segment
		(start 131.393184 -65.748154)
		(end 131.371086 -65.748154)
		(width 0.0889)
		(layer "B.Cu")
		(net "PHY_DPB_TO_SCC_C_1_DP")
	)
	(segment
		(start 126.6952 -66.000122)
		(end 127 -66.000122)
		(width 0.0889)
		(layer "B.Cu")
		(net "PHY_DPB_TO_SCC_C_1_DP")
	)
	(segment
		(start 131.371086 -65.748154)
		(end 131.219956 -65.597024)
		(width 0.0889)
		(layer "B.Cu")
		(net "PHY_DPB_TO_SCC_C_1_DP")
	)
	(segment
		(start 131.675886 -65.748154)
		(end 131.393184 -65.748154)
		(width 0.12446)
		(layer "B.Cu")
		(net "PHY_DPB_TO_SCC_C_1_DP")
	)
	(segment
		(start 133.86435 -64.98336)
		(end 133.099556 -65.748154)
		(width 0.12446)
		(layer "B.Cu")
		(net "PHY_DPB_TO_SCC_C_1_DP")
	)
	(segment
		(start 126.595124 -65.749932)
		(end 126.595124 -65.900046)
		(width 0.0889)
		(layer "B.Cu")
		(net "PHY_DPB_TO_SCC_C_1_DP")
	)
	(arc
		(start 126.595124 -65.900046)
		(mid 126.624436 -65.97081)
		(end 126.6952 -66.000122)
		(width 0.0889)
		(layer "B.Cu")
		(net "PHY_DPB_TO_SCC_C_1_DP")
	)
	(arc
		(start 126.748032 -65.597024)
		(mid 126.63991 -65.64181)
		(end 126.595124 -65.749932)
		(width 0.0889)
		(layer "B.Cu")
		(net "PHY_DPB_TO_SCC_C_1_DP")
	)
	(segment
		(start 125.50013 -66.499994)
		(end 126.000002 -66.000122)
		(width 0.104902)
		(layer "F.Cu")
		(net "PHY_DPB_TO_SCC_C_1_DN")
	)
	(via
		(at 126.000002 -66.000122)
		(size 0.4572)
		(drill 0.2032)
		(layers "F.Cu" "B.Cu")
		(net "PHY_DPB_TO_SCC_C_1_DN")
	)
	(segment
		(start 131.393184 -65.341754)
		(end 131.371086 -65.341754)
		(width 0.0889)
		(layer "B.Cu")
		(net "PHY_DPB_TO_SCC_C_1_DN")
	)
	(segment
		(start 134.144512 -64.57696)
		(end 133.695948 -64.57696)
		(width 0.12446)
		(layer "B.Cu")
		(net "PHY_DPB_TO_SCC_C_1_DN")
	)
	(segment
		(start 126.304802 -66.000122)
		(end 126.000002 -66.000122)
		(width 0.0889)
		(layer "B.Cu")
		(net "PHY_DPB_TO_SCC_C_1_DN")
	)
	(segment
		(start 126.404624 -65.749932)
		(end 126.404624 -65.9003)
		(width 0.0889)
		(layer "B.Cu")
		(net "PHY_DPB_TO_SCC_C_1_DN")
	)
	(segment
		(start 131.306316 -65.406524)
		(end 126.748032 -65.406524)
		(width 0.0889)
		(layer "B.Cu")
		(net "PHY_DPB_TO_SCC_C_1_DN")
	)
	(segment
		(start 131.371086 -65.341754)
		(end 131.306316 -65.406524)
		(width 0.0889)
		(layer "B.Cu")
		(net "PHY_DPB_TO_SCC_C_1_DN")
	)
	(segment
		(start 132.931154 -65.341754)
		(end 131.393184 -65.341754)
		(width 0.12446)
		(layer "B.Cu")
		(net "PHY_DPB_TO_SCC_C_1_DN")
	)
	(segment
		(start 133.695948 -64.57696)
		(end 132.931154 -65.341754)
		(width 0.12446)
		(layer "B.Cu")
		(net "PHY_DPB_TO_SCC_C_1_DN")
	)
	(segment
		(start 134.213854 -64.507618)
		(end 134.144512 -64.57696)
		(width 0.12446)
		(layer "B.Cu")
		(net "PHY_DPB_TO_SCC_C_1_DN")
	)
	(arc
		(start 126.748032 -65.406524)
		(mid 126.505206 -65.507106)
		(end 126.404624 -65.749932)
		(width 0.0889)
		(layer "B.Cu")
		(net "PHY_DPB_TO_SCC_C_1_DN")
	)
	(arc
		(start 126.404624 -65.9003)
		(mid 126.375387 -65.970885)
		(end 126.304802 -66.000122)
		(width 0.0889)
		(layer "B.Cu")
		(net "PHY_DPB_TO_SCC_C_1_DN")
	)
	(segment
		(start 126.500128 -65.499996)
		(end 127 -65.000124)
		(width 0.104902)
		(layer "F.Cu")
		(net "PHY_DPB_TO_SCC_C_0_DP")
	)
	(via
		(at 127 -65.000124)
		(size 0.4572)
		(drill 0.2032)
		(layers "F.Cu" "B.Cu")
		(net "PHY_DPB_TO_SCC_C_0_DP")
	)
	(segment
		(start 135.66648 -61.584078)
		(end 135.66648 -62.818772)
		(width 0.12446)
		(layer "B.Cu")
		(net "PHY_DPB_TO_SCC_C_0_DP")
	)
	(segment
		(start 135.66648 -62.818772)
		(end 134.81304 -63.672212)
		(width 0.12446)
		(layer "B.Cu")
		(net "PHY_DPB_TO_SCC_C_0_DP")
	)
	(segment
		(start 134.81304 -63.672212)
		(end 133.26237 -63.672212)
		(width 0.12446)
		(layer "B.Cu")
		(net "PHY_DPB_TO_SCC_C_0_DP")
	)
	(segment
		(start 131.514088 -64.644524)
		(end 131.464558 -64.594994)
		(width 0.0889)
		(layer "B.Cu")
		(net "PHY_DPB_TO_SCC_C_0_DP")
	)
	(segment
		(start 131.53644 -64.644524)
		(end 131.514088 -64.644524)
		(width 0.0889)
		(layer "B.Cu")
		(net "PHY_DPB_TO_SCC_C_0_DP")
	)
	(segment
		(start 132.290058 -64.644524)
		(end 131.53644 -64.644524)
		(width 0.12446)
		(layer "B.Cu")
		(net "PHY_DPB_TO_SCC_C_0_DP")
	)
	(segment
		(start 133.26237 -63.672212)
		(end 132.290058 -64.644524)
		(width 0.12446)
		(layer "B.Cu")
		(net "PHY_DPB_TO_SCC_C_0_DP")
	)
	(segment
		(start 126.6952 -65.000124)
		(end 127 -65.000124)
		(width 0.0889)
		(layer "B.Cu")
		(net "PHY_DPB_TO_SCC_C_0_DP")
	)
	(segment
		(start 126.595124 -64.749934)
		(end 126.595124 -64.900048)
		(width 0.0889)
		(layer "B.Cu")
		(net "PHY_DPB_TO_SCC_C_0_DP")
	)
	(segment
		(start 131.464558 -64.594994)
		(end 126.750064 -64.594994)
		(width 0.0889)
		(layer "B.Cu")
		(net "PHY_DPB_TO_SCC_C_0_DP")
	)
	(arc
		(start 126.750064 -64.594994)
		(mid 126.640505 -64.640375)
		(end 126.595124 -64.749934)
		(width 0.0889)
		(layer "B.Cu")
		(net "PHY_DPB_TO_SCC_C_0_DP")
	)
	(arc
		(start 126.595124 -64.900048)
		(mid 126.624436 -64.970812)
		(end 126.6952 -65.000124)
		(width 0.0889)
		(layer "B.Cu")
		(net "PHY_DPB_TO_SCC_C_0_DP")
	)
	(segment
		(start 125.50013 -65.499996)
		(end 126.000002 -65.000124)
		(width 0.104902)
		(layer "F.Cu")
		(net "PHY_DPB_TO_SCC_C_0_DN")
	)
	(via
		(at 126.000002 -65.000124)
		(size 0.4572)
		(drill 0.2032)
		(layers "F.Cu" "B.Cu")
		(net "PHY_DPB_TO_SCC_C_0_DN")
	)
	(segment
		(start 131.347972 -64.404494)
		(end 126.750064 -64.404494)
		(width 0.0889)
		(layer "B.Cu")
		(net "PHY_DPB_TO_SCC_C_0_DN")
	)
	(segment
		(start 126.304802 -65.000124)
		(end 126.000002 -65.000124)
		(width 0.0889)
		(layer "B.Cu")
		(net "PHY_DPB_TO_SCC_C_0_DN")
	)
	(segment
		(start 133.093968 -63.265812)
		(end 132.121656 -64.238124)
		(width 0.12446)
		(layer "B.Cu")
		(net "PHY_DPB_TO_SCC_C_0_DN")
	)
	(segment
		(start 135.10768 -61.584078)
		(end 135.26008 -61.736478)
		(width 0.12446)
		(layer "B.Cu")
		(net "PHY_DPB_TO_SCC_C_0_DN")
	)
	(segment
		(start 135.26008 -62.65037)
		(end 134.644638 -63.265812)
		(width 0.12446)
		(layer "B.Cu")
		(net "PHY_DPB_TO_SCC_C_0_DN")
	)
	(segment
		(start 135.26008 -61.736478)
		(end 135.26008 -62.65037)
		(width 0.12446)
		(layer "B.Cu")
		(net "PHY_DPB_TO_SCC_C_0_DN")
	)
	(segment
		(start 134.644638 -63.265812)
		(end 134.379208 -63.265812)
		(width 0.12446)
		(layer "B.Cu")
		(net "PHY_DPB_TO_SCC_C_0_DN")
	)
	(segment
		(start 131.514342 -64.238124)
		(end 131.347972 -64.404494)
		(width 0.0889)
		(layer "B.Cu")
		(net "PHY_DPB_TO_SCC_C_0_DN")
	)
	(segment
		(start 132.121656 -64.238124)
		(end 131.53644 -64.238124)
		(width 0.12446)
		(layer "B.Cu")
		(net "PHY_DPB_TO_SCC_C_0_DN")
	)
	(segment
		(start 133.467348 -63.265812)
		(end 133.093968 -63.265812)
		(width 0.12446)
		(layer "B.Cu")
		(net "PHY_DPB_TO_SCC_C_0_DN")
	)
	(segment
		(start 133.736588 -62.996572)
		(end 133.467348 -63.265812)
		(width 0.12446)
		(layer "B.Cu")
		(net "PHY_DPB_TO_SCC_C_0_DN")
	)
	(segment
		(start 134.379208 -63.265812)
		(end 134.109968 -62.996572)
		(width 0.12446)
		(layer "B.Cu")
		(net "PHY_DPB_TO_SCC_C_0_DN")
	)
	(segment
		(start 131.53644 -64.238124)
		(end 131.514342 -64.238124)
		(width 0.0889)
		(layer "B.Cu")
		(net "PHY_DPB_TO_SCC_C_0_DN")
	)
	(segment
		(start 134.109968 -62.996572)
		(end 133.736588 -62.996572)
		(width 0.12446)
		(layer "B.Cu")
		(net "PHY_DPB_TO_SCC_C_0_DN")
	)
	(segment
		(start 126.404624 -64.749934)
		(end 126.404624 -64.900302)
		(width 0.0889)
		(layer "B.Cu")
		(net "PHY_DPB_TO_SCC_C_0_DN")
	)
	(arc
		(start 126.404624 -64.900302)
		(mid 126.375387 -64.970887)
		(end 126.304802 -65.000124)
		(width 0.0889)
		(layer "B.Cu")
		(net "PHY_DPB_TO_SCC_C_0_DN")
	)
	(arc
		(start 126.750064 -64.404494)
		(mid 126.505801 -64.505671)
		(end 126.404624 -64.749934)
		(width 0.0889)
		(layer "B.Cu")
		(net "PHY_DPB_TO_SCC_C_0_DN")
	)
	(segment
		(start 138.671046 -74.508614)
		(end 141.39164 -73.93051)
		(width 0.12446)
		(layer "B.Cu")
		(net "PHY_DPB_TO_SCC_7_DP")
	)
	(segment
		(start 149.732746 -61.331348)
		(end 148.565616 -55.839868)
		(width 0.12446)
		(layer "B.Cu")
		(net "PHY_DPB_TO_SCC_7_DP")
	)
	(segment
		(start 143.65224 -32.183832)
		(end 147.04441 -16.227552)
		(width 0.12446)
		(layer "B.Cu")
		(net "PHY_DPB_TO_SCC_7_DP")
	)
	(segment
		(start 138.072368 -74.5998)
		(end 138.163554 -74.508614)
		(width 0.12446)
		(layer "B.Cu")
		(net "PHY_DPB_TO_SCC_7_DP")
	)
	(segment
		(start 148.536406 -3.503168)
		(end 148.88083 -3.503168)
		(width 0.12446)
		(layer "B.Cu")
		(net "PHY_DPB_TO_SCC_7_DP")
	)
	(segment
		(start 147.784566 -54.636924)
		(end 146.001232 -46.284642)
		(width 0.12446)
		(layer "B.Cu")
		(net "PHY_DPB_TO_SCC_7_DP")
	)
	(segment
		(start 137.6934 -74.5998)
		(end 138.072368 -74.5998)
		(width 0.12446)
		(layer "B.Cu")
		(net "PHY_DPB_TO_SCC_7_DP")
	)
	(segment
		(start 146.32559 -44.75988)
		(end 143.65224 -32.183832)
		(width 0.12446)
		(layer "B.Cu")
		(net "PHY_DPB_TO_SCC_7_DP")
	)
	(segment
		(start 148.124164 -14.564868)
		(end 148.303234 -13.721334)
		(width 0.12446)
		(layer "B.Cu")
		(net "PHY_DPB_TO_SCC_7_DP")
	)
	(segment
		(start 148.60143 -66.990468)
		(end 149.732746 -61.331348)
		(width 0.12446)
		(layer "B.Cu")
		(net "PHY_DPB_TO_SCC_7_DP")
	)
	(segment
		(start 146.001232 -46.284642)
		(end 146.32559 -44.75988)
		(width 0.12446)
		(layer "B.Cu")
		(net "PHY_DPB_TO_SCC_7_DP")
	)
	(segment
		(start 148.565616 -55.839868)
		(end 147.784566 -54.636924)
		(width 0.12446)
		(layer "B.Cu")
		(net "PHY_DPB_TO_SCC_7_DP")
	)
	(segment
		(start 148.999956 -3.622294)
		(end 148.999956 -3.999992)
		(width 0.12446)
		(layer "B.Cu")
		(net "PHY_DPB_TO_SCC_7_DP")
	)
	(segment
		(start 138.163554 -74.508614)
		(end 138.671046 -74.508614)
		(width 0.12446)
		(layer "B.Cu")
		(net "PHY_DPB_TO_SCC_7_DP")
	)
	(segment
		(start 148.303234 -13.721334)
		(end 148.303234 -3.73634)
		(width 0.12446)
		(layer "B.Cu")
		(net "PHY_DPB_TO_SCC_7_DP")
	)
	(segment
		(start 141.39164 -73.93051)
		(end 146.068034 -70.892924)
		(width 0.12446)
		(layer "B.Cu")
		(net "PHY_DPB_TO_SCC_7_DP")
	)
	(segment
		(start 146.068034 -70.892924)
		(end 148.60143 -66.990468)
		(width 0.12446)
		(layer "B.Cu")
		(net "PHY_DPB_TO_SCC_7_DP")
	)
	(segment
		(start 147.04441 -16.227552)
		(end 148.124164 -14.564868)
		(width 0.12446)
		(layer "B.Cu")
		(net "PHY_DPB_TO_SCC_7_DP")
	)
	(arc
		(start 148.965158 -3.53822)
		(mid 148.990932 -3.576793)
		(end 148.999956 -3.622294)
		(width 0.12446)
		(layer "B.Cu")
		(net "PHY_DPB_TO_SCC_7_DP")
	)
	(arc
		(start 148.88083 -3.503168)
		(mid 148.926486 -3.512285)
		(end 148.965158 -3.53822)
		(width 0.12446)
		(layer "B.Cu")
		(net "PHY_DPB_TO_SCC_7_DP")
	)
	(arc
		(start 148.303234 -3.73634)
		(mid 148.371528 -3.571462)
		(end 148.536406 -3.503168)
		(width 0.12446)
		(layer "B.Cu")
		(net "PHY_DPB_TO_SCC_7_DP")
	)
	(segment
		(start 146.995896 -68.716906)
		(end 148.218144 -66.834512)
		(width 0.12446)
		(layer "B.Cu")
		(net "PHY_DPB_TO_SCC_7_DN")
	)
	(segment
		(start 145.773902 -70.599046)
		(end 146.995896 -68.716906)
		(width 0.12446)
		(layer "B.Cu")
		(net "PHY_DPB_TO_SCC_7_DN")
	)
	(segment
		(start 145.585434 -46.284896)
		(end 145.910046 -44.75988)
		(width 0.12446)
		(layer "B.Cu")
		(net "PHY_DPB_TO_SCC_7_DN")
	)
	(segment
		(start 148.536406 -3.096768)
		(end 148.88083 -3.096768)
		(width 0.12446)
		(layer "B.Cu")
		(net "PHY_DPB_TO_SCC_7_DN")
	)
	(segment
		(start 147.896834 -13.678662)
		(end 147.896834 -3.73634)
		(width 0.12446)
		(layer "B.Cu")
		(net "PHY_DPB_TO_SCC_7_DN")
	)
	(segment
		(start 146.662394 -16.06931)
		(end 147.742148 -14.406626)
		(width 0.12446)
		(layer "B.Cu")
		(net "PHY_DPB_TO_SCC_7_DN")
	)
	(segment
		(start 141.233398 -73.548494)
		(end 145.773902 -70.599046)
		(width 0.12446)
		(layer "B.Cu")
		(net "PHY_DPB_TO_SCC_7_DN")
	)
	(segment
		(start 138.072368 -74.041)
		(end 138.133582 -74.102214)
		(width 0.12446)
		(layer "B.Cu")
		(net "PHY_DPB_TO_SCC_7_DN")
	)
	(segment
		(start 143.236696 -32.183832)
		(end 146.662394 -16.06931)
		(width 0.12446)
		(layer "B.Cu")
		(net "PHY_DPB_TO_SCC_7_DN")
	)
	(segment
		(start 147.40255 -54.79542)
		(end 145.585434 -46.284896)
		(width 0.12446)
		(layer "B.Cu")
		(net "PHY_DPB_TO_SCC_7_DN")
	)
	(segment
		(start 147.742148 -14.406626)
		(end 147.896834 -13.678662)
		(width 0.12446)
		(layer "B.Cu")
		(net "PHY_DPB_TO_SCC_7_DN")
	)
	(segment
		(start 149.31771 -61.333888)
		(end 148.1836 -55.99811)
		(width 0.12446)
		(layer "B.Cu")
		(net "PHY_DPB_TO_SCC_7_DN")
	)
	(segment
		(start 148.1836 -55.99811)
		(end 147.40255 -54.79542)
		(width 0.12446)
		(layer "B.Cu")
		(net "PHY_DPB_TO_SCC_7_DN")
	)
	(segment
		(start 137.6934 -74.041)
		(end 138.072368 -74.041)
		(width 0.12446)
		(layer "B.Cu")
		(net "PHY_DPB_TO_SCC_7_DN")
	)
	(segment
		(start 138.62812 -74.102214)
		(end 141.233398 -73.548494)
		(width 0.12446)
		(layer "B.Cu")
		(net "PHY_DPB_TO_SCC_7_DN")
	)
	(segment
		(start 145.910046 -44.75988)
		(end 143.236696 -32.183832)
		(width 0.12446)
		(layer "B.Cu")
		(net "PHY_DPB_TO_SCC_7_DN")
	)
	(segment
		(start 148.999956 -2.977642)
		(end 148.999956 -2.600198)
		(width 0.12446)
		(layer "B.Cu")
		(net "PHY_DPB_TO_SCC_7_DN")
	)
	(segment
		(start 148.218144 -66.834512)
		(end 149.31771 -61.333888)
		(width 0.12446)
		(layer "B.Cu")
		(net "PHY_DPB_TO_SCC_7_DN")
	)
	(segment
		(start 138.133582 -74.102214)
		(end 138.62812 -74.102214)
		(width 0.12446)
		(layer "B.Cu")
		(net "PHY_DPB_TO_SCC_7_DN")
	)
	(arc
		(start 148.88083 -3.096768)
		(mid 148.926486 -3.087651)
		(end 148.965158 -3.061716)
		(width 0.12446)
		(layer "B.Cu")
		(net "PHY_DPB_TO_SCC_7_DN")
	)
	(arc
		(start 147.896834 -3.73634)
		(mid 148.08416 -3.284094)
		(end 148.536406 -3.096768)
		(width 0.12446)
		(layer "B.Cu")
		(net "PHY_DPB_TO_SCC_7_DN")
	)
	(arc
		(start 148.965158 -3.061716)
		(mid 148.990932 -3.023143)
		(end 148.999956 -2.977642)
		(width 0.12446)
		(layer "B.Cu")
		(net "PHY_DPB_TO_SCC_7_DN")
	)
	(segment
		(start 144.597882 -46.985174)
		(end 144.982184 -45.17771)
		(width 0.12446)
		(layer "B.Cu")
		(net "PHY_DPB_TO_SCC_6_DP")
	)
	(segment
		(start 145.114264 -70.038468)
		(end 147.347432 -66.60007)
		(width 0.12446)
		(layer "B.Cu")
		(net "PHY_DPB_TO_SCC_6_DP")
	)
	(segment
		(start 141.230604 -72.560942)
		(end 145.114264 -70.038468)
		(width 0.12446)
		(layer "B.Cu")
		(net "PHY_DPB_TO_SCC_6_DP")
	)
	(segment
		(start 147.3454 -56.293004)
		(end 146.199352 -54.528212)
		(width 0.12446)
		(layer "B.Cu")
		(net "PHY_DPB_TO_SCC_6_DP")
	)
	(segment
		(start 144.982184 -45.17771)
		(end 142.313406 -32.621982)
		(width 0.12446)
		(layer "B.Cu")
		(net "PHY_DPB_TO_SCC_6_DP")
	)
	(segment
		(start 147.347432 -66.60007)
		(end 148.441918 -61.45276)
		(width 0.12446)
		(layer "B.Cu")
		(net "PHY_DPB_TO_SCC_6_DP")
	)
	(segment
		(start 142.313406 -32.621982)
		(end 146.50339 -12.908026)
		(width 0.12446)
		(layer "B.Cu")
		(net "PHY_DPB_TO_SCC_6_DP")
	)
	(segment
		(start 147.200112 -4.822444)
		(end 147.200112 -5.200142)
		(width 0.12446)
		(layer "B.Cu")
		(net "PHY_DPB_TO_SCC_6_DP")
	)
	(segment
		(start 138.213592 -72.909176)
		(end 139.59205 -72.909176)
		(width 0.12446)
		(layer "B.Cu")
		(net "PHY_DPB_TO_SCC_6_DP")
	)
	(segment
		(start 146.736562 -4.703318)
		(end 147.080986 -4.703318)
		(width 0.12446)
		(layer "B.Cu")
		(net "PHY_DPB_TO_SCC_6_DP")
	)
	(segment
		(start 146.199352 -54.528212)
		(end 144.597882 -46.985174)
		(width 0.12446)
		(layer "B.Cu")
		(net "PHY_DPB_TO_SCC_6_DP")
	)
	(segment
		(start 139.59205 -72.909176)
		(end 141.230604 -72.560942)
		(width 0.12446)
		(layer "B.Cu")
		(net "PHY_DPB_TO_SCC_6_DP")
	)
	(segment
		(start 148.441918 -61.45276)
		(end 147.3454 -56.293004)
		(width 0.12446)
		(layer "B.Cu")
		(net "PHY_DPB_TO_SCC_6_DP")
	)
	(segment
		(start 138.123168 -72.9996)
		(end 138.213592 -72.909176)
		(width 0.12446)
		(layer "B.Cu")
		(net "PHY_DPB_TO_SCC_6_DP")
	)
	(segment
		(start 146.50339 -12.908026)
		(end 146.50339 -4.93649)
		(width 0.12446)
		(layer "B.Cu")
		(net "PHY_DPB_TO_SCC_6_DP")
	)
	(segment
		(start 137.7442 -72.9996)
		(end 138.123168 -72.9996)
		(width 0.12446)
		(layer "B.Cu")
		(net "PHY_DPB_TO_SCC_6_DP")
	)
	(arc
		(start 147.165314 -4.73837)
		(mid 147.191088 -4.776943)
		(end 147.200112 -4.822444)
		(width 0.12446)
		(layer "B.Cu")
		(net "PHY_DPB_TO_SCC_6_DP")
	)
	(arc
		(start 147.080986 -4.703318)
		(mid 147.126642 -4.712435)
		(end 147.165314 -4.73837)
		(width 0.12446)
		(layer "B.Cu")
		(net "PHY_DPB_TO_SCC_6_DP")
	)
	(arc
		(start 146.50339 -4.93649)
		(mid 146.571684 -4.771612)
		(end 146.736562 -4.703318)
		(width 0.12446)
		(layer "B.Cu")
		(net "PHY_DPB_TO_SCC_6_DP")
	)
	(segment
		(start 146.963384 -56.451246)
		(end 145.817336 -54.6862)
		(width 0.12446)
		(layer "B.Cu")
		(net "PHY_DPB_TO_SCC_6_DN")
	)
	(segment
		(start 146.736562 -4.296918)
		(end 147.080986 -4.296918)
		(width 0.12446)
		(layer "B.Cu")
		(net "PHY_DPB_TO_SCC_6_DN")
	)
	(segment
		(start 141.897862 -32.621982)
		(end 146.09699 -12.8651)
		(width 0.12446)
		(layer "B.Cu")
		(net "PHY_DPB_TO_SCC_6_DN")
	)
	(segment
		(start 138.185144 -72.502776)
		(end 139.549124 -72.502776)
		(width 0.12446)
		(layer "B.Cu")
		(net "PHY_DPB_TO_SCC_6_DN")
	)
	(segment
		(start 145.892774 -68.093336)
		(end 146.965416 -66.441828)
		(width 0.12446)
		(layer "B.Cu")
		(net "PHY_DPB_TO_SCC_6_DN")
	)
	(segment
		(start 139.549124 -72.502776)
		(end 141.072362 -72.178926)
		(width 0.12446)
		(layer "B.Cu")
		(net "PHY_DPB_TO_SCC_6_DN")
	)
	(segment
		(start 144.182338 -46.985174)
		(end 144.56664 -45.17771)
		(width 0.12446)
		(layer "B.Cu")
		(net "PHY_DPB_TO_SCC_6_DN")
	)
	(segment
		(start 146.09699 -12.8651)
		(end 146.09699 -4.93649)
		(width 0.12446)
		(layer "B.Cu")
		(net "PHY_DPB_TO_SCC_6_DN")
	)
	(segment
		(start 141.072362 -72.178926)
		(end 144.820386 -69.74459)
		(width 0.12446)
		(layer "B.Cu")
		(net "PHY_DPB_TO_SCC_6_DN")
	)
	(segment
		(start 145.817336 -54.686454)
		(end 144.182338 -46.985174)
		(width 0.12446)
		(layer "B.Cu")
		(net "PHY_DPB_TO_SCC_6_DN")
	)
	(segment
		(start 137.7442 -72.4408)
		(end 138.123168 -72.4408)
		(width 0.12446)
		(layer "B.Cu")
		(net "PHY_DPB_TO_SCC_6_DN")
	)
	(segment
		(start 144.820386 -69.74459)
		(end 145.892774 -68.093336)
		(width 0.12446)
		(layer "B.Cu")
		(net "PHY_DPB_TO_SCC_6_DN")
	)
	(segment
		(start 148.026374 -61.45276)
		(end 146.963384 -56.451246)
		(width 0.12446)
		(layer "B.Cu")
		(net "PHY_DPB_TO_SCC_6_DN")
	)
	(segment
		(start 145.817336 -54.6862)
		(end 145.817336 -54.686454)
		(width 0.12446)
		(layer "B.Cu")
		(net "PHY_DPB_TO_SCC_6_DN")
	)
	(segment
		(start 144.56664 -45.17771)
		(end 141.897862 -32.621982)
		(width 0.12446)
		(layer "B.Cu")
		(net "PHY_DPB_TO_SCC_6_DN")
	)
	(segment
		(start 147.200112 -4.177792)
		(end 147.200112 -3.800094)
		(width 0.12446)
		(layer "B.Cu")
		(net "PHY_DPB_TO_SCC_6_DN")
	)
	(segment
		(start 146.965416 -66.441828)
		(end 148.026374 -61.45276)
		(width 0.12446)
		(layer "B.Cu")
		(net "PHY_DPB_TO_SCC_6_DN")
	)
	(segment
		(start 138.123168 -72.4408)
		(end 138.185144 -72.502776)
		(width 0.12446)
		(layer "B.Cu")
		(net "PHY_DPB_TO_SCC_6_DN")
	)
	(arc
		(start 146.09699 -4.93649)
		(mid 146.284316 -4.484244)
		(end 146.736562 -4.296918)
		(width 0.12446)
		(layer "B.Cu")
		(net "PHY_DPB_TO_SCC_6_DN")
	)
	(arc
		(start 147.080986 -4.296918)
		(mid 147.126642 -4.287801)
		(end 147.165314 -4.261866)
		(width 0.12446)
		(layer "B.Cu")
		(net "PHY_DPB_TO_SCC_6_DN")
	)
	(arc
		(start 147.165314 -4.261866)
		(mid 147.191088 -4.223293)
		(end 147.200112 -4.177792)
		(width 0.12446)
		(layer "B.Cu")
		(net "PHY_DPB_TO_SCC_6_DN")
	)
	(segment
		(start 146.167856 -66.016632)
		(end 147.11934 -61.537596)
		(width 0.12446)
		(layer "B.Cu")
		(net "PHY_DPB_TO_SCC_5_DP")
	)
	(segment
		(start 146.08937 -56.690768)
		(end 144.658842 -54.48808)
		(width 0.12446)
		(layer "B.Cu")
		(net "PHY_DPB_TO_SCC_5_DP")
	)
	(segment
		(start 139.075922 -71.3486)
		(end 141.678406 -70.795896)
		(width 0.12446)
		(layer "B.Cu")
		(net "PHY_DPB_TO_SCC_5_DP")
	)
	(segment
		(start 138.224768 -71.3486)
		(end 139.075922 -71.3486)
		(width 0.12446)
		(layer "B.Cu")
		(net "PHY_DPB_TO_SCC_5_DP")
	)
	(segment
		(start 143.679672 -45.353986)
		(end 140.984478 -32.673544)
		(width 0.12446)
		(layer "B.Cu")
		(net "PHY_DPB_TO_SCC_5_DP")
	)
	(segment
		(start 144.076166 -69.238622)
		(end 146.167856 -66.016632)
		(width 0.12446)
		(layer "B.Cu")
		(net "PHY_DPB_TO_SCC_5_DP")
	)
	(segment
		(start 144.658842 -54.48808)
		(end 143.198596 -47.616872)
		(width 0.12446)
		(layer "B.Cu")
		(net "PHY_DPB_TO_SCC_5_DP")
	)
	(segment
		(start 140.984478 -32.673544)
		(end 144.703292 -15.1765)
		(width 0.12446)
		(layer "B.Cu")
		(net "PHY_DPB_TO_SCC_5_DP")
	)
	(segment
		(start 137.7442 -71.4502)
		(end 138.123168 -71.4502)
		(width 0.12446)
		(layer "B.Cu")
		(net "PHY_DPB_TO_SCC_5_DP")
	)
	(segment
		(start 145.400014 -3.622294)
		(end 145.400014 -3.999992)
		(width 0.12446)
		(layer "B.Cu")
		(net "PHY_DPB_TO_SCC_5_DP")
	)
	(segment
		(start 141.678406 -70.795896)
		(end 144.076166 -69.238622)
		(width 0.12446)
		(layer "B.Cu")
		(net "PHY_DPB_TO_SCC_5_DP")
	)
	(segment
		(start 138.123168 -71.4502)
		(end 138.224768 -71.3486)
		(width 0.12446)
		(layer "B.Cu")
		(net "PHY_DPB_TO_SCC_5_DP")
	)
	(segment
		(start 144.936464 -3.503168)
		(end 145.280888 -3.503168)
		(width 0.12446)
		(layer "B.Cu")
		(net "PHY_DPB_TO_SCC_5_DP")
	)
	(segment
		(start 143.198596 -47.616872)
		(end 143.679672 -45.353986)
		(width 0.12446)
		(layer "B.Cu")
		(net "PHY_DPB_TO_SCC_5_DP")
	)
	(segment
		(start 147.11934 -61.537596)
		(end 146.08937 -56.690768)
		(width 0.12446)
		(layer "B.Cu")
		(net "PHY_DPB_TO_SCC_5_DP")
	)
	(segment
		(start 144.703292 -15.1765)
		(end 144.703292 -3.73634)
		(width 0.12446)
		(layer "B.Cu")
		(net "PHY_DPB_TO_SCC_5_DP")
	)
	(arc
		(start 145.280888 -3.503168)
		(mid 145.326544 -3.512285)
		(end 145.365216 -3.53822)
		(width 0.12446)
		(layer "B.Cu")
		(net "PHY_DPB_TO_SCC_5_DP")
	)
	(arc
		(start 144.703292 -3.73634)
		(mid 144.771586 -3.571462)
		(end 144.936464 -3.503168)
		(width 0.12446)
		(layer "B.Cu")
		(net "PHY_DPB_TO_SCC_5_DP")
	)
	(arc
		(start 145.365216 -3.53822)
		(mid 145.39099 -3.576793)
		(end 145.400014 -3.622294)
		(width 0.12446)
		(layer "B.Cu")
		(net "PHY_DPB_TO_SCC_5_DP")
	)
	(segment
		(start 140.568934 -32.673544)
		(end 144.296892 -15.133574)
		(width 0.12446)
		(layer "B.Cu")
		(net "PHY_DPB_TO_SCC_5_DN")
	)
	(segment
		(start 143.782288 -68.944744)
		(end 144.784064 -67.401694)
		(width 0.12446)
		(layer "B.Cu")
		(net "PHY_DPB_TO_SCC_5_DN")
	)
	(segment
		(start 139.032996 -70.9422)
		(end 141.520164 -70.41388)
		(width 0.12446)
		(layer "B.Cu")
		(net "PHY_DPB_TO_SCC_5_DN")
	)
	(segment
		(start 144.936464 -3.096768)
		(end 145.280888 -3.096768)
		(width 0.12446)
		(layer "B.Cu")
		(net "PHY_DPB_TO_SCC_5_DN")
	)
	(segment
		(start 145.707354 -56.84901)
		(end 144.276826 -54.646322)
		(width 0.12446)
		(layer "B.Cu")
		(net "PHY_DPB_TO_SCC_5_DN")
	)
	(segment
		(start 144.296892 -15.133574)
		(end 144.296892 -3.73634)
		(width 0.12446)
		(layer "B.Cu")
		(net "PHY_DPB_TO_SCC_5_DN")
	)
	(segment
		(start 141.520164 -70.41388)
		(end 143.782288 -68.944744)
		(width 0.12446)
		(layer "B.Cu")
		(net "PHY_DPB_TO_SCC_5_DN")
	)
	(segment
		(start 143.264128 -45.353986)
		(end 140.568934 -32.673544)
		(width 0.12446)
		(layer "B.Cu")
		(net "PHY_DPB_TO_SCC_5_DN")
	)
	(segment
		(start 144.276826 -54.646322)
		(end 142.783052 -47.616872)
		(width 0.12446)
		(layer "B.Cu")
		(net "PHY_DPB_TO_SCC_5_DN")
	)
	(segment
		(start 145.400014 -2.977642)
		(end 145.400014 -2.600198)
		(width 0.12446)
		(layer "B.Cu")
		(net "PHY_DPB_TO_SCC_5_DN")
	)
	(segment
		(start 138.123168 -70.8914)
		(end 138.173968 -70.9422)
		(width 0.12446)
		(layer "B.Cu")
		(net "PHY_DPB_TO_SCC_5_DN")
	)
	(segment
		(start 142.783052 -47.616872)
		(end 143.264128 -45.353986)
		(width 0.12446)
		(layer "B.Cu")
		(net "PHY_DPB_TO_SCC_5_DN")
	)
	(segment
		(start 145.78584 -65.85839)
		(end 146.703796 -61.537596)
		(width 0.12446)
		(layer "B.Cu")
		(net "PHY_DPB_TO_SCC_5_DN")
	)
	(segment
		(start 146.703796 -61.537596)
		(end 145.707354 -56.84901)
		(width 0.12446)
		(layer "B.Cu")
		(net "PHY_DPB_TO_SCC_5_DN")
	)
	(segment
		(start 144.784064 -67.401694)
		(end 145.78584 -65.85839)
		(width 0.12446)
		(layer "B.Cu")
		(net "PHY_DPB_TO_SCC_5_DN")
	)
	(segment
		(start 137.7442 -70.8914)
		(end 138.123168 -70.8914)
		(width 0.12446)
		(layer "B.Cu")
		(net "PHY_DPB_TO_SCC_5_DN")
	)
	(segment
		(start 138.173968 -70.9422)
		(end 139.032996 -70.9422)
		(width 0.12446)
		(layer "B.Cu")
		(net "PHY_DPB_TO_SCC_5_DN")
	)
	(arc
		(start 144.296892 -3.73634)
		(mid 144.484218 -3.284094)
		(end 144.936464 -3.096768)
		(width 0.12446)
		(layer "B.Cu")
		(net "PHY_DPB_TO_SCC_5_DN")
	)
	(arc
		(start 145.280888 -3.096768)
		(mid 145.326544 -3.087651)
		(end 145.365216 -3.061716)
		(width 0.12446)
		(layer "B.Cu")
		(net "PHY_DPB_TO_SCC_5_DN")
	)
	(arc
		(start 145.365216 -3.061716)
		(mid 145.39099 -3.023143)
		(end 145.400014 -2.977642)
		(width 0.12446)
		(layer "B.Cu")
		(net "PHY_DPB_TO_SCC_5_DN")
	)
	(segment
		(start 143.480028 -67.86499)
		(end 144.96796 -65.575688)
		(width 0.12446)
		(layer "B.Cu")
		(net "PHY_DPB_TO_SCC_4_DP")
	)
	(segment
		(start 144.854422 -57.121044)
		(end 143.132302 -54.469284)
		(width 0.12446)
		(layer "B.Cu")
		(net "PHY_DPB_TO_SCC_4_DP")
	)
	(segment
		(start 144.96796 -65.575688)
		(end 145.809208 -61.613796)
		(width 0.12446)
		(layer "B.Cu")
		(net "PHY_DPB_TO_SCC_4_DP")
	)
	(segment
		(start 141.797278 -48.188372)
		(end 142.376906 -45.461936)
		(width 0.12446)
		(layer "B.Cu")
		(net "PHY_DPB_TO_SCC_4_DP")
	)
	(segment
		(start 141.149578 -69.379592)
		(end 143.480028 -67.86499)
		(width 0.12446)
		(layer "B.Cu")
		(net "PHY_DPB_TO_SCC_4_DP")
	)
	(segment
		(start 143.132302 -54.469284)
		(end 141.797278 -48.188372)
		(width 0.12446)
		(layer "B.Cu")
		(net "PHY_DPB_TO_SCC_4_DP")
	)
	(segment
		(start 142.359126 -45.377354)
		(end 142.358872 -45.377354)
		(width 0.12446)
		(layer "B.Cu")
		(net "PHY_DPB_TO_SCC_4_DP")
	)
	(segment
		(start 138.209782 -69.814186)
		(end 139.106402 -69.814186)
		(width 0.12446)
		(layer "B.Cu")
		(net "PHY_DPB_TO_SCC_4_DP")
	)
	(segment
		(start 139.106402 -69.814186)
		(end 141.149578 -69.379592)
		(width 0.12446)
		(layer "B.Cu")
		(net "PHY_DPB_TO_SCC_4_DP")
	)
	(segment
		(start 145.809208 -61.613796)
		(end 144.854422 -57.121044)
		(width 0.12446)
		(layer "B.Cu")
		(net "PHY_DPB_TO_SCC_4_DP")
	)
	(segment
		(start 139.659614 -32.67583)
		(end 142.903448 -17.413986)
		(width 0.12446)
		(layer "B.Cu")
		(net "PHY_DPB_TO_SCC_4_DP")
	)
	(segment
		(start 137.7442 -69.9008)
		(end 138.123168 -69.9008)
		(width 0.12446)
		(layer "B.Cu")
		(net "PHY_DPB_TO_SCC_4_DP")
	)
	(segment
		(start 142.358872 -45.377354)
		(end 139.659614 -32.67583)
		(width 0.12446)
		(layer "B.Cu")
		(net "PHY_DPB_TO_SCC_4_DP")
	)
	(segment
		(start 143.60017 -4.822444)
		(end 143.60017 -5.200142)
		(width 0.12446)
		(layer "B.Cu")
		(net "PHY_DPB_TO_SCC_4_DP")
	)
	(segment
		(start 142.903448 -17.413986)
		(end 142.903448 -4.93649)
		(width 0.12446)
		(layer "B.Cu")
		(net "PHY_DPB_TO_SCC_4_DP")
	)
	(segment
		(start 138.123168 -69.9008)
		(end 138.209782 -69.814186)
		(width 0.12446)
		(layer "B.Cu")
		(net "PHY_DPB_TO_SCC_4_DP")
	)
	(segment
		(start 143.13662 -4.703318)
		(end 143.481044 -4.703318)
		(width 0.12446)
		(layer "B.Cu")
		(net "PHY_DPB_TO_SCC_4_DP")
	)
	(segment
		(start 142.376906 -45.461936)
		(end 142.359126 -45.377354)
		(width 0.12446)
		(layer "B.Cu")
		(net "PHY_DPB_TO_SCC_4_DP")
	)
	(arc
		(start 142.903448 -4.93649)
		(mid 142.971742 -4.771612)
		(end 143.13662 -4.703318)
		(width 0.12446)
		(layer "B.Cu")
		(net "PHY_DPB_TO_SCC_4_DP")
	)
	(arc
		(start 143.565372 -4.73837)
		(mid 143.591146 -4.776943)
		(end 143.60017 -4.822444)
		(width 0.12446)
		(layer "B.Cu")
		(net "PHY_DPB_TO_SCC_4_DP")
	)
	(arc
		(start 143.481044 -4.703318)
		(mid 143.5267 -4.712435)
		(end 143.565372 -4.73837)
		(width 0.12446)
		(layer "B.Cu")
		(net "PHY_DPB_TO_SCC_4_DP")
	)
	(segment
		(start 142.497048 -17.37106)
		(end 142.497048 -4.93649)
		(width 0.12446)
		(layer "B.Cu")
		(net "PHY_DPB_TO_SCC_4_DN")
	)
	(segment
		(start 139.24407 -32.67583)
		(end 142.497048 -17.37106)
		(width 0.12446)
		(layer "B.Cu")
		(net "PHY_DPB_TO_SCC_4_DN")
	)
	(segment
		(start 144.585944 -65.417446)
		(end 145.393664 -61.613796)
		(width 0.12446)
		(layer "B.Cu")
		(net "PHY_DPB_TO_SCC_4_DN")
	)
	(segment
		(start 141.961362 -45.461936)
		(end 139.24407 -32.67583)
		(width 0.12446)
		(layer "B.Cu")
		(net "PHY_DPB_TO_SCC_4_DN")
	)
	(segment
		(start 143.88592 -66.49466)
		(end 144.585944 -65.417446)
		(width 0.12446)
		(layer "B.Cu")
		(net "PHY_DPB_TO_SCC_4_DN")
	)
	(segment
		(start 138.188954 -69.407786)
		(end 139.063476 -69.407786)
		(width 0.12446)
		(layer "B.Cu")
		(net "PHY_DPB_TO_SCC_4_DN")
	)
	(segment
		(start 138.123168 -69.342)
		(end 138.188954 -69.407786)
		(width 0.12446)
		(layer "B.Cu")
		(net "PHY_DPB_TO_SCC_4_DN")
	)
	(segment
		(start 144.472406 -57.279286)
		(end 142.750286 -54.627526)
		(width 0.12446)
		(layer "B.Cu")
		(net "PHY_DPB_TO_SCC_4_DN")
	)
	(segment
		(start 143.18615 -67.571112)
		(end 143.88592 -66.49466)
		(width 0.12446)
		(layer "B.Cu")
		(net "PHY_DPB_TO_SCC_4_DN")
	)
	(segment
		(start 142.750286 -54.627526)
		(end 141.381734 -48.188372)
		(width 0.12446)
		(layer "B.Cu")
		(net "PHY_DPB_TO_SCC_4_DN")
	)
	(segment
		(start 140.991336 -68.997576)
		(end 143.18615 -67.571112)
		(width 0.12446)
		(layer "B.Cu")
		(net "PHY_DPB_TO_SCC_4_DN")
	)
	(segment
		(start 143.60017 -4.177792)
		(end 143.60017 -3.800094)
		(width 0.12446)
		(layer "B.Cu")
		(net "PHY_DPB_TO_SCC_4_DN")
	)
	(segment
		(start 137.7442 -69.342)
		(end 138.123168 -69.342)
		(width 0.12446)
		(layer "B.Cu")
		(net "PHY_DPB_TO_SCC_4_DN")
	)
	(segment
		(start 145.393664 -61.613796)
		(end 144.472406 -57.279286)
		(width 0.12446)
		(layer "B.Cu")
		(net "PHY_DPB_TO_SCC_4_DN")
	)
	(segment
		(start 139.063476 -69.407786)
		(end 140.991336 -68.997576)
		(width 0.12446)
		(layer "B.Cu")
		(net "PHY_DPB_TO_SCC_4_DN")
	)
	(segment
		(start 143.13662 -4.296918)
		(end 143.481044 -4.296918)
		(width 0.12446)
		(layer "B.Cu")
		(net "PHY_DPB_TO_SCC_4_DN")
	)
	(segment
		(start 141.381734 -48.188372)
		(end 141.961362 -45.461936)
		(width 0.12446)
		(layer "B.Cu")
		(net "PHY_DPB_TO_SCC_4_DN")
	)
	(arc
		(start 143.565372 -4.261866)
		(mid 143.591146 -4.223293)
		(end 143.60017 -4.177792)
		(width 0.12446)
		(layer "B.Cu")
		(net "PHY_DPB_TO_SCC_4_DN")
	)
	(arc
		(start 142.497048 -4.93649)
		(mid 142.684374 -4.484244)
		(end 143.13662 -4.296918)
		(width 0.12446)
		(layer "B.Cu")
		(net "PHY_DPB_TO_SCC_4_DN")
	)
	(arc
		(start 143.481044 -4.296918)
		(mid 143.5267 -4.287801)
		(end 143.565372 -4.261866)
		(width 0.12446)
		(layer "B.Cu")
		(net "PHY_DPB_TO_SCC_4_DN")
	)
	(segment
		(start 128.87833 -24.852122)
		(end 128.559052 -24.644858)
		(width 0.12446)
		(layer "B.Cu")
		(net "PHY_DPB_TO_SCC_39_DP")
	)
	(segment
		(start 128.481328 -24.279606)
		(end 128.688846 -23.960328)
		(width 0.12446)
		(layer "B.Cu")
		(net "PHY_DPB_TO_SCC_39_DP")
	)
	(segment
		(start 127.366268 -39.101268)
		(end 127.366268 -32.793432)
		(width 0.12446)
		(layer "B.Cu")
		(net "PHY_DPB_TO_SCC_39_DP")
	)
	(segment
		(start 126.9365 -3.503168)
		(end 127.280924 -3.503168)
		(width 0.12446)
		(layer "B.Cu")
		(net "PHY_DPB_TO_SCC_39_DP")
	)
	(segment
		(start 128.024382 -22.130766)
		(end 126.703328 -15.918434)
		(width 0.12446)
		(layer "B.Cu")
		(net "PHY_DPB_TO_SCC_39_DP")
	)
	(segment
		(start 128.611122 -23.595076)
		(end 128.291844 -23.387812)
		(width 0.12446)
		(layer "B.Cu")
		(net "PHY_DPB_TO_SCC_39_DP")
	)
	(segment
		(start 128.21412 -23.02256)
		(end 128.421638 -22.703282)
		(width 0.12446)
		(layer "B.Cu")
		(net "PHY_DPB_TO_SCC_39_DP")
	)
	(segment
		(start 128.291844 -23.387812)
		(end 128.21412 -23.02256)
		(width 0.12446)
		(layer "B.Cu")
		(net "PHY_DPB_TO_SCC_39_DP")
	)
	(segment
		(start 127.366268 -32.793432)
		(end 128.82626 -25.901904)
		(width 0.12446)
		(layer "B.Cu")
		(net "PHY_DPB_TO_SCC_39_DP")
	)
	(segment
		(start 128.343914 -22.33803)
		(end 128.024382 -22.130766)
		(width 0.12446)
		(layer "B.Cu")
		(net "PHY_DPB_TO_SCC_39_DP")
	)
	(segment
		(start 127.4572 -39.1922)
		(end 127.366268 -39.101268)
		(width 0.12446)
		(layer "B.Cu")
		(net "PHY_DPB_TO_SCC_39_DP")
	)
	(segment
		(start 128.748536 -25.536652)
		(end 128.956054 -25.217374)
		(width 0.12446)
		(layer "B.Cu")
		(net "PHY_DPB_TO_SCC_39_DP")
	)
	(segment
		(start 128.82626 -25.901904)
		(end 128.748536 -25.536652)
		(width 0.12446)
		(layer "B.Cu")
		(net "PHY_DPB_TO_SCC_39_DP")
	)
	(segment
		(start 128.688846 -23.960328)
		(end 128.611122 -23.595076)
		(width 0.12446)
		(layer "B.Cu")
		(net "PHY_DPB_TO_SCC_39_DP")
	)
	(segment
		(start 127.40005 -3.622294)
		(end 127.40005 -3.999992)
		(width 0.12446)
		(layer "B.Cu")
		(net "PHY_DPB_TO_SCC_39_DP")
	)
	(segment
		(start 128.421638 -22.703282)
		(end 128.343914 -22.33803)
		(width 0.12446)
		(layer "B.Cu")
		(net "PHY_DPB_TO_SCC_39_DP")
	)
	(segment
		(start 128.559052 -24.644858)
		(end 128.481328 -24.279606)
		(width 0.12446)
		(layer "B.Cu")
		(net "PHY_DPB_TO_SCC_39_DP")
	)
	(segment
		(start 128.956054 -25.217374)
		(end 128.87833 -24.852122)
		(width 0.12446)
		(layer "B.Cu")
		(net "PHY_DPB_TO_SCC_39_DP")
	)
	(segment
		(start 126.703328 -15.918434)
		(end 126.703328 -3.73634)
		(width 0.12446)
		(layer "B.Cu")
		(net "PHY_DPB_TO_SCC_39_DP")
	)
	(arc
		(start 127.365252 -3.53822)
		(mid 127.391026 -3.576793)
		(end 127.40005 -3.622294)
		(width 0.12446)
		(layer "B.Cu")
		(net "PHY_DPB_TO_SCC_39_DP")
	)
	(arc
		(start 126.703328 -3.73634)
		(mid 126.771622 -3.571462)
		(end 126.9365 -3.503168)
		(width 0.12446)
		(layer "B.Cu")
		(net "PHY_DPB_TO_SCC_39_DP")
	)
	(arc
		(start 127.280924 -3.503168)
		(mid 127.32658 -3.512285)
		(end 127.365252 -3.53822)
		(width 0.12446)
		(layer "B.Cu")
		(net "PHY_DPB_TO_SCC_39_DP")
	)
	(segment
		(start 126.9365 -3.096768)
		(end 127.280924 -3.096768)
		(width 0.12446)
		(layer "B.Cu")
		(net "PHY_DPB_TO_SCC_39_DN")
	)
	(segment
		(start 126.873 -39.1922)
		(end 126.959868 -39.105332)
		(width 0.12446)
		(layer "B.Cu")
		(net "PHY_DPB_TO_SCC_39_DN")
	)
	(segment
		(start 127.40005 -2.977642)
		(end 127.40005 -2.600198)
		(width 0.12446)
		(layer "B.Cu")
		(net "PHY_DPB_TO_SCC_39_DN")
	)
	(segment
		(start 126.959868 -32.75076)
		(end 128.410716 -25.902158)
		(width 0.12446)
		(layer "B.Cu")
		(net "PHY_DPB_TO_SCC_39_DN")
	)
	(segment
		(start 126.296928 -15.96136)
		(end 126.296928 -3.73634)
		(width 0.12446)
		(layer "B.Cu")
		(net "PHY_DPB_TO_SCC_39_DN")
	)
	(segment
		(start 128.410716 -25.902158)
		(end 126.296928 -15.96136)
		(width 0.12446)
		(layer "B.Cu")
		(net "PHY_DPB_TO_SCC_39_DN")
	)
	(segment
		(start 126.959868 -39.105332)
		(end 126.959868 -32.75076)
		(width 0.12446)
		(layer "B.Cu")
		(net "PHY_DPB_TO_SCC_39_DN")
	)
	(arc
		(start 127.280924 -3.096768)
		(mid 127.32658 -3.087651)
		(end 127.365252 -3.061716)
		(width 0.12446)
		(layer "B.Cu")
		(net "PHY_DPB_TO_SCC_39_DN")
	)
	(arc
		(start 126.296928 -3.73634)
		(mid 126.484254 -3.284094)
		(end 126.9365 -3.096768)
		(width 0.12446)
		(layer "B.Cu")
		(net "PHY_DPB_TO_SCC_39_DN")
	)
	(arc
		(start 127.365252 -3.061716)
		(mid 127.391026 -3.023143)
		(end 127.40005 -2.977642)
		(width 0.12446)
		(layer "B.Cu")
		(net "PHY_DPB_TO_SCC_39_DN")
	)
	(segment
		(start 124.903484 -14.854936)
		(end 126.494794 -22.335998)
		(width 0.12446)
		(layer "B.Cu")
		(net "PHY_DPB_TO_SCC_38_DP")
	)
	(segment
		(start 126.684532 -23.228046)
		(end 126.762256 -23.593298)
		(width 0.12446)
		(layer "B.Cu")
		(net "PHY_DPB_TO_SCC_38_DP")
	)
	(segment
		(start 127.296672 -26.10739)
		(end 125.501146 -34.587688)
		(width 0.12446)
		(layer "B.Cu")
		(net "PHY_DPB_TO_SCC_38_DP")
	)
	(segment
		(start 126.814326 -22.543516)
		(end 126.89205 -22.908768)
		(width 0.12446)
		(layer "B.Cu")
		(net "PHY_DPB_TO_SCC_38_DP")
	)
	(segment
		(start 126.762256 -23.593298)
		(end 127.081534 -23.800562)
		(width 0.12446)
		(layer "B.Cu")
		(net "PHY_DPB_TO_SCC_38_DP")
	)
	(segment
		(start 126.494794 -22.335998)
		(end 126.495048 -22.336252)
		(width 0.12446)
		(layer "B.Cu")
		(net "PHY_DPB_TO_SCC_38_DP")
	)
	(segment
		(start 125.501146 -39.115746)
		(end 125.5776 -39.1922)
		(width 0.12446)
		(layer "B.Cu")
		(net "PHY_DPB_TO_SCC_38_DP")
	)
	(segment
		(start 127.426466 -25.42286)
		(end 127.218948 -25.742138)
		(width 0.12446)
		(layer "B.Cu")
		(net "PHY_DPB_TO_SCC_38_DP")
	)
	(segment
		(start 127.159258 -24.165814)
		(end 126.95174 -24.485092)
		(width 0.12446)
		(layer "B.Cu")
		(net "PHY_DPB_TO_SCC_38_DP")
	)
	(segment
		(start 126.95174 -24.485092)
		(end 127.029464 -24.850344)
		(width 0.12446)
		(layer "B.Cu")
		(net "PHY_DPB_TO_SCC_38_DP")
	)
	(segment
		(start 126.495048 -22.336252)
		(end 126.814326 -22.543516)
		(width 0.12446)
		(layer "B.Cu")
		(net "PHY_DPB_TO_SCC_38_DP")
	)
	(segment
		(start 127.029464 -24.850344)
		(end 127.348742 -25.057608)
		(width 0.12446)
		(layer "B.Cu")
		(net "PHY_DPB_TO_SCC_38_DP")
	)
	(segment
		(start 125.501146 -34.587688)
		(end 125.501146 -39.115746)
		(width 0.12446)
		(layer "B.Cu")
		(net "PHY_DPB_TO_SCC_38_DP")
	)
	(segment
		(start 125.48108 -4.703318)
		(end 125.136656 -4.703318)
		(width 0.12446)
		(layer "B.Cu")
		(net "PHY_DPB_TO_SCC_38_DP")
	)
	(segment
		(start 125.600206 -5.200142)
		(end 125.600206 -4.822444)
		(width 0.12446)
		(layer "B.Cu")
		(net "PHY_DPB_TO_SCC_38_DP")
	)
	(segment
		(start 127.348742 -25.057608)
		(end 127.426466 -25.42286)
		(width 0.12446)
		(layer "B.Cu")
		(net "PHY_DPB_TO_SCC_38_DP")
	)
	(segment
		(start 126.89205 -22.908768)
		(end 126.684532 -23.228046)
		(width 0.12446)
		(layer "B.Cu")
		(net "PHY_DPB_TO_SCC_38_DP")
	)
	(segment
		(start 124.903484 -4.93649)
		(end 124.903484 -14.854936)
		(width 0.12446)
		(layer "B.Cu")
		(net "PHY_DPB_TO_SCC_38_DP")
	)
	(segment
		(start 127.218948 -25.742138)
		(end 127.296672 -26.10739)
		(width 0.12446)
		(layer "B.Cu")
		(net "PHY_DPB_TO_SCC_38_DP")
	)
	(segment
		(start 127.081534 -23.800562)
		(end 127.159258 -24.165814)
		(width 0.12446)
		(layer "B.Cu")
		(net "PHY_DPB_TO_SCC_38_DP")
	)
	(arc
		(start 125.600206 -4.822444)
		(mid 125.591157 -4.776954)
		(end 125.565408 -4.73837)
		(width 0.12446)
		(layer "B.Cu")
		(net "PHY_DPB_TO_SCC_38_DP")
	)
	(arc
		(start 125.565408 -4.73837)
		(mid 125.526747 -4.71241)
		(end 125.48108 -4.703318)
		(width 0.12446)
		(layer "B.Cu")
		(net "PHY_DPB_TO_SCC_38_DP")
	)
	(arc
		(start 125.136656 -4.703318)
		(mid 124.971778 -4.771612)
		(end 124.903484 -4.93649)
		(width 0.12446)
		(layer "B.Cu")
		(net "PHY_DPB_TO_SCC_38_DP")
	)
	(segment
		(start 124.497084 -14.897862)
		(end 126.881128 -26.107644)
		(width 0.12446)
		(layer "B.Cu")
		(net "PHY_DPB_TO_SCC_38_DN")
	)
	(segment
		(start 126.881128 -26.107644)
		(end 125.094746 -34.545016)
		(width 0.12446)
		(layer "B.Cu")
		(net "PHY_DPB_TO_SCC_38_DN")
	)
	(segment
		(start 125.600206 -3.800094)
		(end 125.600206 -4.177792)
		(width 0.12446)
		(layer "B.Cu")
		(net "PHY_DPB_TO_SCC_38_DN")
	)
	(segment
		(start 125.094746 -34.545016)
		(end 125.094746 -39.090854)
		(width 0.12446)
		(layer "B.Cu")
		(net "PHY_DPB_TO_SCC_38_DN")
	)
	(segment
		(start 125.094746 -39.090854)
		(end 124.9934 -39.1922)
		(width 0.12446)
		(layer "B.Cu")
		(net "PHY_DPB_TO_SCC_38_DN")
	)
	(segment
		(start 125.48108 -4.296918)
		(end 125.136656 -4.296918)
		(width 0.12446)
		(layer "B.Cu")
		(net "PHY_DPB_TO_SCC_38_DN")
	)
	(segment
		(start 124.497084 -4.93649)
		(end 124.497084 -14.897862)
		(width 0.12446)
		(layer "B.Cu")
		(net "PHY_DPB_TO_SCC_38_DN")
	)
	(arc
		(start 125.600206 -4.177792)
		(mid 125.591157 -4.223282)
		(end 125.565408 -4.261866)
		(width 0.12446)
		(layer "B.Cu")
		(net "PHY_DPB_TO_SCC_38_DN")
	)
	(arc
		(start 125.565408 -4.261866)
		(mid 125.526747 -4.287826)
		(end 125.48108 -4.296918)
		(width 0.12446)
		(layer "B.Cu")
		(net "PHY_DPB_TO_SCC_38_DN")
	)
	(arc
		(start 125.136656 -4.296918)
		(mid 124.68441 -4.484244)
		(end 124.497084 -4.93649)
		(width 0.12446)
		(layer "B.Cu")
		(net "PHY_DPB_TO_SCC_38_DN")
	)
	(segment
		(start 123.71578 -35.605212)
		(end 123.71578 -39.10838)
		(width 0.12446)
		(layer "B.Cu")
		(net "PHY_DPB_TO_SCC_37_DP")
	)
	(segment
		(start 123.800108 -3.999992)
		(end 123.800108 -3.622294)
		(width 0.12446)
		(layer "B.Cu")
		(net "PHY_DPB_TO_SCC_37_DP")
	)
	(segment
		(start 125.07468 -23.941024)
		(end 125.393958 -24.148288)
		(width 0.12446)
		(layer "B.Cu")
		(net "PHY_DPB_TO_SCC_37_DP")
	)
	(segment
		(start 125.341888 -25.19807)
		(end 125.661166 -25.405588)
		(width 0.12446)
		(layer "B.Cu")
		(net "PHY_DPB_TO_SCC_37_DP")
	)
	(segment
		(start 124.996956 -23.575772)
		(end 125.07468 -23.941024)
		(width 0.12446)
		(layer "B.Cu")
		(net "PHY_DPB_TO_SCC_37_DP")
	)
	(segment
		(start 123.103386 -3.73634)
		(end 123.103386 -14.665452)
		(width 0.12446)
		(layer "B.Cu")
		(net "PHY_DPB_TO_SCC_37_DP")
	)
	(segment
		(start 123.680982 -3.503168)
		(end 123.336558 -3.503168)
		(width 0.12446)
		(layer "B.Cu")
		(net "PHY_DPB_TO_SCC_37_DP")
	)
	(segment
		(start 125.12675 -22.891242)
		(end 125.204474 -23.256494)
		(width 0.12446)
		(layer "B.Cu")
		(net "PHY_DPB_TO_SCC_37_DP")
	)
	(segment
		(start 125.264164 -24.832818)
		(end 125.341888 -25.19807)
		(width 0.12446)
		(layer "B.Cu")
		(net "PHY_DPB_TO_SCC_37_DP")
	)
	(segment
		(start 124.807472 -22.683724)
		(end 125.12675 -22.891242)
		(width 0.12446)
		(layer "B.Cu")
		(net "PHY_DPB_TO_SCC_37_DP")
	)
	(segment
		(start 125.204474 -23.256494)
		(end 124.996956 -23.575772)
		(width 0.12446)
		(layer "B.Cu")
		(net "PHY_DPB_TO_SCC_37_DP")
	)
	(segment
		(start 125.531372 -26.090118)
		(end 125.63094 -26.558748)
		(width 0.12446)
		(layer "B.Cu")
		(net "PHY_DPB_TO_SCC_37_DP")
	)
	(segment
		(start 123.103386 -14.665452)
		(end 124.807472 -22.683724)
		(width 0.12446)
		(layer "B.Cu")
		(net "PHY_DPB_TO_SCC_37_DP")
	)
	(segment
		(start 125.63094 -26.558748)
		(end 123.71578 -35.605212)
		(width 0.12446)
		(layer "B.Cu")
		(net "PHY_DPB_TO_SCC_37_DP")
	)
	(segment
		(start 125.661166 -25.405588)
		(end 125.738636 -25.77084)
		(width 0.12446)
		(layer "B.Cu")
		(net "PHY_DPB_TO_SCC_37_DP")
	)
	(segment
		(start 125.738636 -25.77084)
		(end 125.531372 -26.090118)
		(width 0.12446)
		(layer "B.Cu")
		(net "PHY_DPB_TO_SCC_37_DP")
	)
	(segment
		(start 123.71578 -39.10838)
		(end 123.7996 -39.1922)
		(width 0.12446)
		(layer "B.Cu")
		(net "PHY_DPB_TO_SCC_37_DP")
	)
	(segment
		(start 125.393958 -24.148288)
		(end 125.471682 -24.51354)
		(width 0.12446)
		(layer "B.Cu")
		(net "PHY_DPB_TO_SCC_37_DP")
	)
	(segment
		(start 125.471682 -24.51354)
		(end 125.264164 -24.832818)
		(width 0.12446)
		(layer "B.Cu")
		(net "PHY_DPB_TO_SCC_37_DP")
	)
	(arc
		(start 123.800108 -3.622294)
		(mid 123.791059 -3.576804)
		(end 123.76531 -3.53822)
		(width 0.12446)
		(layer "B.Cu")
		(net "PHY_DPB_TO_SCC_37_DP")
	)
	(arc
		(start 123.76531 -3.53822)
		(mid 123.726649 -3.51226)
		(end 123.680982 -3.503168)
		(width 0.12446)
		(layer "B.Cu")
		(net "PHY_DPB_TO_SCC_37_DP")
	)
	(arc
		(start 123.336558 -3.503168)
		(mid 123.17168 -3.571462)
		(end 123.103386 -3.73634)
		(width 0.12446)
		(layer "B.Cu")
		(net "PHY_DPB_TO_SCC_37_DP")
	)
	(segment
		(start 123.800108 -2.600198)
		(end 123.800108 -2.977642)
		(width 0.12446)
		(layer "B.Cu")
		(net "PHY_DPB_TO_SCC_37_DN")
	)
	(segment
		(start 123.30938 -39.09822)
		(end 123.2154 -39.1922)
		(width 0.12446)
		(layer "B.Cu")
		(net "PHY_DPB_TO_SCC_37_DN")
	)
	(segment
		(start 122.696986 -3.73634)
		(end 122.696986 -14.708378)
		(width 0.12446)
		(layer "B.Cu")
		(net "PHY_DPB_TO_SCC_37_DN")
	)
	(segment
		(start 123.30938 -35.56254)
		(end 123.30938 -39.09822)
		(width 0.12446)
		(layer "B.Cu")
		(net "PHY_DPB_TO_SCC_37_DN")
	)
	(segment
		(start 123.680982 -3.096768)
		(end 123.336558 -3.096768)
		(width 0.12446)
		(layer "B.Cu")
		(net "PHY_DPB_TO_SCC_37_DN")
	)
	(segment
		(start 122.696986 -14.708378)
		(end 125.215396 -26.559002)
		(width 0.12446)
		(layer "B.Cu")
		(net "PHY_DPB_TO_SCC_37_DN")
	)
	(segment
		(start 125.215396 -26.559002)
		(end 123.30938 -35.56254)
		(width 0.12446)
		(layer "B.Cu")
		(net "PHY_DPB_TO_SCC_37_DN")
	)
	(arc
		(start 123.800108 -2.977642)
		(mid 123.791059 -3.023132)
		(end 123.76531 -3.061716)
		(width 0.12446)
		(layer "B.Cu")
		(net "PHY_DPB_TO_SCC_37_DN")
	)
	(arc
		(start 123.336558 -3.096768)
		(mid 122.884312 -3.284094)
		(end 122.696986 -3.73634)
		(width 0.12446)
		(layer "B.Cu")
		(net "PHY_DPB_TO_SCC_37_DN")
	)
	(arc
		(start 123.76531 -3.061716)
		(mid 123.726649 -3.087676)
		(end 123.680982 -3.096768)
		(width 0.12446)
		(layer "B.Cu")
		(net "PHY_DPB_TO_SCC_37_DN")
	)
	(segment
		(start 122.875802 -24.103076)
		(end 123.19508 -24.310594)
		(width 0.12446)
		(layer "B.Cu")
		(net "PHY_DPB_TO_SCC_36_DP")
	)
	(segment
		(start 123.410218 -26.617422)
		(end 123.729496 -26.82494)
		(width 0.12446)
		(layer "B.Cu")
		(net "PHY_DPB_TO_SCC_36_DP")
	)
	(segment
		(start 121.303288 -16.704818)
		(end 122.875802 -24.103076)
		(width 0.12446)
		(layer "B.Cu")
		(net "PHY_DPB_TO_SCC_36_DP")
	)
	(segment
		(start 121.9327 -36.756594)
		(end 121.9327 -39.1033)
		(width 0.12446)
		(layer "B.Cu")
		(net "PHY_DPB_TO_SCC_36_DP")
	)
	(segment
		(start 123.599702 -27.50947)
		(end 123.745244 -28.194)
		(width 0.12446)
		(layer "B.Cu")
		(net "PHY_DPB_TO_SCC_36_DP")
	)
	(segment
		(start 121.303288 -4.93649)
		(end 121.303288 -16.704818)
		(width 0.12446)
		(layer "B.Cu")
		(net "PHY_DPB_TO_SCC_36_DP")
	)
	(segment
		(start 123.80722 -27.190192)
		(end 123.599702 -27.50947)
		(width 0.12446)
		(layer "B.Cu")
		(net "PHY_DPB_TO_SCC_36_DP")
	)
	(segment
		(start 121.9327 -39.1033)
		(end 122.0216 -39.1922)
		(width 0.12446)
		(layer "B.Cu")
		(net "PHY_DPB_TO_SCC_36_DP")
	)
	(segment
		(start 123.745244 -28.194)
		(end 121.9327 -36.756594)
		(width 0.12446)
		(layer "B.Cu")
		(net "PHY_DPB_TO_SCC_36_DP")
	)
	(segment
		(start 123.462288 -25.56764)
		(end 123.540012 -25.932892)
		(width 0.12446)
		(layer "B.Cu")
		(net "PHY_DPB_TO_SCC_36_DP")
	)
	(segment
		(start 122.00001 -5.200142)
		(end 122.00001 -4.822444)
		(width 0.12446)
		(layer "B.Cu")
		(net "PHY_DPB_TO_SCC_36_DP")
	)
	(segment
		(start 121.880884 -4.703318)
		(end 121.53646 -4.703318)
		(width 0.12446)
		(layer "B.Cu")
		(net "PHY_DPB_TO_SCC_36_DP")
	)
	(segment
		(start 123.272804 -24.675846)
		(end 123.065286 -24.995124)
		(width 0.12446)
		(layer "B.Cu")
		(net "PHY_DPB_TO_SCC_36_DP")
	)
	(segment
		(start 123.14301 -25.360376)
		(end 123.462288 -25.56764)
		(width 0.12446)
		(layer "B.Cu")
		(net "PHY_DPB_TO_SCC_36_DP")
	)
	(segment
		(start 123.332494 -26.25217)
		(end 123.410218 -26.617422)
		(width 0.12446)
		(layer "B.Cu")
		(net "PHY_DPB_TO_SCC_36_DP")
	)
	(segment
		(start 123.19508 -24.310594)
		(end 123.272804 -24.675846)
		(width 0.12446)
		(layer "B.Cu")
		(net "PHY_DPB_TO_SCC_36_DP")
	)
	(segment
		(start 123.729496 -26.82494)
		(end 123.80722 -27.190192)
		(width 0.12446)
		(layer "B.Cu")
		(net "PHY_DPB_TO_SCC_36_DP")
	)
	(segment
		(start 123.065286 -24.995124)
		(end 123.14301 -25.360376)
		(width 0.12446)
		(layer "B.Cu")
		(net "PHY_DPB_TO_SCC_36_DP")
	)
	(segment
		(start 123.540012 -25.932892)
		(end 123.332494 -26.25217)
		(width 0.12446)
		(layer "B.Cu")
		(net "PHY_DPB_TO_SCC_36_DP")
	)
	(arc
		(start 121.965212 -4.73837)
		(mid 121.926551 -4.71241)
		(end 121.880884 -4.703318)
		(width 0.12446)
		(layer "B.Cu")
		(net "PHY_DPB_TO_SCC_36_DP")
	)
	(arc
		(start 121.53646 -4.703318)
		(mid 121.371582 -4.771612)
		(end 121.303288 -4.93649)
		(width 0.12446)
		(layer "B.Cu")
		(net "PHY_DPB_TO_SCC_36_DP")
	)
	(arc
		(start 122.00001 -4.822444)
		(mid 121.990961 -4.776954)
		(end 121.965212 -4.73837)
		(width 0.12446)
		(layer "B.Cu")
		(net "PHY_DPB_TO_SCC_36_DP")
	)
	(segment
		(start 121.5263 -36.713922)
		(end 121.5263 -39.1033)
		(width 0.12446)
		(layer "B.Cu")
		(net "PHY_DPB_TO_SCC_36_DN")
	)
	(segment
		(start 120.896888 -4.93649)
		(end 120.896888 -16.747744)
		(width 0.12446)
		(layer "B.Cu")
		(net "PHY_DPB_TO_SCC_36_DN")
	)
	(segment
		(start 121.880884 -4.296918)
		(end 121.53646 -4.296918)
		(width 0.12446)
		(layer "B.Cu")
		(net "PHY_DPB_TO_SCC_36_DN")
	)
	(segment
		(start 123.3297 -28.194254)
		(end 121.5263 -36.713922)
		(width 0.12446)
		(layer "B.Cu")
		(net "PHY_DPB_TO_SCC_36_DN")
	)
	(segment
		(start 121.5263 -39.1033)
		(end 121.4374 -39.1922)
		(width 0.12446)
		(layer "B.Cu")
		(net "PHY_DPB_TO_SCC_36_DN")
	)
	(segment
		(start 122.00001 -3.800094)
		(end 122.00001 -4.177792)
		(width 0.12446)
		(layer "B.Cu")
		(net "PHY_DPB_TO_SCC_36_DN")
	)
	(segment
		(start 120.896888 -16.747744)
		(end 123.3297 -28.194254)
		(width 0.12446)
		(layer "B.Cu")
		(net "PHY_DPB_TO_SCC_36_DN")
	)
	(arc
		(start 121.965212 -4.261866)
		(mid 121.926551 -4.287826)
		(end 121.880884 -4.296918)
		(width 0.12446)
		(layer "B.Cu")
		(net "PHY_DPB_TO_SCC_36_DN")
	)
	(arc
		(start 121.53646 -4.296918)
		(mid 121.084214 -4.484244)
		(end 120.896888 -4.93649)
		(width 0.12446)
		(layer "B.Cu")
		(net "PHY_DPB_TO_SCC_36_DN")
	)
	(arc
		(start 122.00001 -4.177792)
		(mid 121.990961 -4.223282)
		(end 121.965212 -4.261866)
		(width 0.12446)
		(layer "B.Cu")
		(net "PHY_DPB_TO_SCC_36_DN")
	)
	(segment
		(start 121.509282 -26.391108)
		(end 121.828814 -26.598626)
		(width 0.12446)
		(layer "B.Cu")
		(net "PHY_DPB_TO_SCC_35_DP")
	)
	(segment
		(start 121.828814 -26.598626)
		(end 121.906284 -26.963878)
		(width 0.12446)
		(layer "B.Cu")
		(net "PHY_DPB_TO_SCC_35_DP")
	)
	(segment
		(start 121.431812 -26.025856)
		(end 121.509282 -26.391108)
		(width 0.12446)
		(layer "B.Cu")
		(net "PHY_DPB_TO_SCC_35_DP")
	)
	(segment
		(start 119.9896 -38.621716)
		(end 119.9896 -43.8658)
		(width 0.12446)
		(layer "B.Cu")
		(net "PHY_DPB_TO_SCC_35_DP")
	)
	(segment
		(start 121.242074 -25.134062)
		(end 121.561606 -25.341326)
		(width 0.12446)
		(layer "B.Cu")
		(net "PHY_DPB_TO_SCC_35_DP")
	)
	(segment
		(start 119.9896 -43.8658)
		(end 120.0658 -43.942)
		(width 0.12446)
		(layer "B.Cu")
		(net "PHY_DPB_TO_SCC_35_DP")
	)
	(segment
		(start 119.503444 -3.73634)
		(end 119.503444 -12.301982)
		(width 0.12446)
		(layer "B.Cu")
		(net "PHY_DPB_TO_SCC_35_DP")
	)
	(segment
		(start 121.639076 -25.706578)
		(end 121.431812 -26.025856)
		(width 0.12446)
		(layer "B.Cu")
		(net "PHY_DPB_TO_SCC_35_DP")
	)
	(segment
		(start 119.50446 -16.958564)
		(end 121.242074 -25.134062)
		(width 0.12446)
		(layer "B.Cu")
		(net "PHY_DPB_TO_SCC_35_DP")
	)
	(segment
		(start 120.08104 -3.503168)
		(end 119.736616 -3.503168)
		(width 0.12446)
		(layer "B.Cu")
		(net "PHY_DPB_TO_SCC_35_DP")
	)
	(segment
		(start 121.561606 -25.341326)
		(end 121.639076 -25.706578)
		(width 0.12446)
		(layer "B.Cu")
		(net "PHY_DPB_TO_SCC_35_DP")
	)
	(segment
		(start 120.200166 -3.999992)
		(end 120.200166 -3.622294)
		(width 0.12446)
		(layer "B.Cu")
		(net "PHY_DPB_TO_SCC_35_DP")
	)
	(segment
		(start 121.906284 -26.963878)
		(end 121.69902 -27.283156)
		(width 0.12446)
		(layer "B.Cu")
		(net "PHY_DPB_TO_SCC_35_DP")
	)
	(segment
		(start 121.966228 -28.540202)
		(end 122.045476 -28.913582)
		(width 0.12446)
		(layer "B.Cu")
		(net "PHY_DPB_TO_SCC_35_DP")
	)
	(segment
		(start 119.503444 -12.301982)
		(end 119.50446 -16.958564)
		(width 0.12446)
		(layer "B.Cu")
		(net "PHY_DPB_TO_SCC_35_DP")
	)
	(segment
		(start 121.77649 -27.648408)
		(end 122.095768 -27.855672)
		(width 0.12446)
		(layer "B.Cu")
		(net "PHY_DPB_TO_SCC_35_DP")
	)
	(segment
		(start 122.045476 -28.913582)
		(end 119.9896 -38.621716)
		(width 0.12446)
		(layer "B.Cu")
		(net "PHY_DPB_TO_SCC_35_DP")
	)
	(segment
		(start 122.173492 -28.220924)
		(end 121.966228 -28.540202)
		(width 0.12446)
		(layer "B.Cu")
		(net "PHY_DPB_TO_SCC_35_DP")
	)
	(segment
		(start 121.69902 -27.283156)
		(end 121.77649 -27.648408)
		(width 0.12446)
		(layer "B.Cu")
		(net "PHY_DPB_TO_SCC_35_DP")
	)
	(segment
		(start 122.095768 -27.855672)
		(end 122.173492 -28.220924)
		(width 0.12446)
		(layer "B.Cu")
		(net "PHY_DPB_TO_SCC_35_DP")
	)
	(arc
		(start 120.200166 -3.622294)
		(mid 120.191117 -3.576804)
		(end 120.165368 -3.53822)
		(width 0.12446)
		(layer "B.Cu")
		(net "PHY_DPB_TO_SCC_35_DP")
	)
	(arc
		(start 120.165368 -3.53822)
		(mid 120.126707 -3.51226)
		(end 120.08104 -3.503168)
		(width 0.12446)
		(layer "B.Cu")
		(net "PHY_DPB_TO_SCC_35_DP")
	)
	(arc
		(start 119.736616 -3.503168)
		(mid 119.571738 -3.571462)
		(end 119.503444 -3.73634)
		(width 0.12446)
		(layer "B.Cu")
		(net "PHY_DPB_TO_SCC_35_DP")
	)
	(segment
		(start 119.097044 -12.302236)
		(end 119.09806 -16.992854)
		(width 0.12446)
		(layer "B.Cu")
		(net "PHY_DPB_TO_SCC_35_DN")
	)
	(segment
		(start 119.097044 -3.73634)
		(end 119.097044 -12.302236)
		(width 0.12446)
		(layer "B.Cu")
		(net "PHY_DPB_TO_SCC_35_DN")
	)
	(segment
		(start 119.5832 -38.579044)
		(end 119.5832 -43.8658)
		(width 0.12446)
		(layer "B.Cu")
		(net "PHY_DPB_TO_SCC_35_DN")
	)
	(segment
		(start 119.09806 -16.992854)
		(end 119.09806 -16.994124)
		(width 0.12446)
		(layer "B.Cu")
		(net "PHY_DPB_TO_SCC_35_DN")
	)
	(segment
		(start 120.08104 -3.096768)
		(end 119.736616 -3.096768)
		(width 0.12446)
		(layer "B.Cu")
		(net "PHY_DPB_TO_SCC_35_DN")
	)
	(segment
		(start 119.09806 -16.994124)
		(end 119.09679 -16.995394)
		(width 0.12446)
		(layer "B.Cu")
		(net "PHY_DPB_TO_SCC_35_DN")
	)
	(segment
		(start 121.629932 -28.913836)
		(end 119.5832 -38.579044)
		(width 0.12446)
		(layer "B.Cu")
		(net "PHY_DPB_TO_SCC_35_DN")
	)
	(segment
		(start 119.09679 -16.995394)
		(end 121.629932 -28.913836)
		(width 0.12446)
		(layer "B.Cu")
		(net "PHY_DPB_TO_SCC_35_DN")
	)
	(segment
		(start 119.5832 -43.8658)
		(end 119.507 -43.942)
		(width 0.12446)
		(layer "B.Cu")
		(net "PHY_DPB_TO_SCC_35_DN")
	)
	(segment
		(start 120.200166 -2.600198)
		(end 120.200166 -2.977642)
		(width 0.12446)
		(layer "B.Cu")
		(net "PHY_DPB_TO_SCC_35_DN")
	)
	(arc
		(start 119.736616 -3.096768)
		(mid 119.28437 -3.284094)
		(end 119.097044 -3.73634)
		(width 0.12446)
		(layer "B.Cu")
		(net "PHY_DPB_TO_SCC_35_DN")
	)
	(arc
		(start 120.200166 -2.977642)
		(mid 120.191117 -3.023132)
		(end 120.165368 -3.061716)
		(width 0.12446)
		(layer "B.Cu")
		(net "PHY_DPB_TO_SCC_35_DN")
	)
	(arc
		(start 120.165368 -3.061716)
		(mid 120.126707 -3.087676)
		(end 120.08104 -3.096768)
		(width 0.12446)
		(layer "B.Cu")
		(net "PHY_DPB_TO_SCC_35_DN")
	)
	(segment
		(start 119.855488 -26.976832)
		(end 119.777764 -26.61158)
		(width 0.12446)
		(layer "B.Cu")
		(net "PHY_DPB_TO_SCC_34_DP")
	)
	(segment
		(start 120.2817 -30.283658)
		(end 120.18137 -29.81071)
		(width 0.12446)
		(layer "B.Cu")
		(net "PHY_DPB_TO_SCC_34_DP")
	)
	(segment
		(start 119.64797 -27.29611)
		(end 119.855488 -26.976832)
		(width 0.12446)
		(layer "B.Cu")
		(net "PHY_DPB_TO_SCC_34_DP")
	)
	(segment
		(start 120.388888 -29.491432)
		(end 120.311164 -29.12618)
		(width 0.12446)
		(layer "B.Cu")
		(net "PHY_DPB_TO_SCC_34_DP")
	)
	(segment
		(start 119.777764 -26.61158)
		(end 119.458486 -26.404062)
		(width 0.12446)
		(layer "B.Cu")
		(net "PHY_DPB_TO_SCC_34_DP")
	)
	(segment
		(start 119.91467 -28.55341)
		(end 120.122188 -28.234132)
		(width 0.12446)
		(layer "B.Cu")
		(net "PHY_DPB_TO_SCC_34_DP")
	)
	(segment
		(start 120.122188 -28.234132)
		(end 120.044464 -27.86888)
		(width 0.12446)
		(layer "B.Cu")
		(net "PHY_DPB_TO_SCC_34_DP")
	)
	(segment
		(start 119.72544 -27.661362)
		(end 119.64797 -27.29611)
		(width 0.12446)
		(layer "B.Cu")
		(net "PHY_DPB_TO_SCC_34_DP")
	)
	(segment
		(start 117.936518 -4.703318)
		(end 118.280942 -4.703318)
		(width 0.12446)
		(layer "B.Cu")
		(net "PHY_DPB_TO_SCC_34_DP")
	)
	(segment
		(start 119.99214 -28.918662)
		(end 119.91467 -28.55341)
		(width 0.12446)
		(layer "B.Cu")
		(net "PHY_DPB_TO_SCC_34_DP")
	)
	(segment
		(start 120.044464 -27.86888)
		(end 119.72544 -27.661362)
		(width 0.12446)
		(layer "B.Cu")
		(net "PHY_DPB_TO_SCC_34_DP")
	)
	(segment
		(start 118.479824 -43.880024)
		(end 118.479824 -38.759892)
		(width 0.12446)
		(layer "B.Cu")
		(net "PHY_DPB_TO_SCC_34_DP")
	)
	(segment
		(start 117.703346 -18.13433)
		(end 117.703346 -4.93649)
		(width 0.12446)
		(layer "B.Cu")
		(net "PHY_DPB_TO_SCC_34_DP")
	)
	(segment
		(start 118.5418 -43.942)
		(end 118.479824 -43.880024)
		(width 0.12446)
		(layer "B.Cu")
		(net "PHY_DPB_TO_SCC_34_DP")
	)
	(segment
		(start 120.311164 -29.12618)
		(end 119.99214 -28.918662)
		(width 0.12446)
		(layer "B.Cu")
		(net "PHY_DPB_TO_SCC_34_DP")
	)
	(segment
		(start 118.400068 -4.822444)
		(end 118.400068 -5.200142)
		(width 0.12446)
		(layer "B.Cu")
		(net "PHY_DPB_TO_SCC_34_DP")
	)
	(segment
		(start 120.18137 -29.81071)
		(end 120.388888 -29.491432)
		(width 0.12446)
		(layer "B.Cu")
		(net "PHY_DPB_TO_SCC_34_DP")
	)
	(segment
		(start 119.458486 -26.404062)
		(end 117.703346 -18.13433)
		(width 0.12446)
		(layer "B.Cu")
		(net "PHY_DPB_TO_SCC_34_DP")
	)
	(segment
		(start 118.479824 -38.759892)
		(end 120.2817 -30.283658)
		(width 0.12446)
		(layer "B.Cu")
		(net "PHY_DPB_TO_SCC_34_DP")
	)
	(arc
		(start 118.280942 -4.703318)
		(mid 118.326598 -4.712435)
		(end 118.36527 -4.73837)
		(width 0.12446)
		(layer "B.Cu")
		(net "PHY_DPB_TO_SCC_34_DP")
	)
	(arc
		(start 118.36527 -4.73837)
		(mid 118.391044 -4.776943)
		(end 118.400068 -4.822444)
		(width 0.12446)
		(layer "B.Cu")
		(net "PHY_DPB_TO_SCC_34_DP")
	)
	(arc
		(start 117.703346 -4.93649)
		(mid 117.77164 -4.771612)
		(end 117.936518 -4.703318)
		(width 0.12446)
		(layer "B.Cu")
		(net "PHY_DPB_TO_SCC_34_DP")
	)
	(segment
		(start 118.073424 -43.851576)
		(end 118.073424 -38.716966)
		(width 0.12446)
		(layer "B.Cu")
		(net "PHY_DPB_TO_SCC_34_DN")
	)
	(segment
		(start 117.296946 -18.177002)
		(end 117.296946 -4.93649)
		(width 0.12446)
		(layer "B.Cu")
		(net "PHY_DPB_TO_SCC_34_DN")
	)
	(segment
		(start 118.400068 -4.177792)
		(end 118.400068 -3.800094)
		(width 0.12446)
		(layer "B.Cu")
		(net "PHY_DPB_TO_SCC_34_DN")
	)
	(segment
		(start 118.073424 -38.716966)
		(end 119.866156 -30.283404)
		(width 0.12446)
		(layer "B.Cu")
		(net "PHY_DPB_TO_SCC_34_DN")
	)
	(segment
		(start 117.983 -43.942)
		(end 118.073424 -43.851576)
		(width 0.12446)
		(layer "B.Cu")
		(net "PHY_DPB_TO_SCC_34_DN")
	)
	(segment
		(start 119.866156 -30.283404)
		(end 117.296946 -18.177002)
		(width 0.12446)
		(layer "B.Cu")
		(net "PHY_DPB_TO_SCC_34_DN")
	)
	(segment
		(start 117.936518 -4.296918)
		(end 118.280942 -4.296918)
		(width 0.12446)
		(layer "B.Cu")
		(net "PHY_DPB_TO_SCC_34_DN")
	)
	(arc
		(start 117.296946 -4.93649)
		(mid 117.484272 -4.484244)
		(end 117.936518 -4.296918)
		(width 0.12446)
		(layer "B.Cu")
		(net "PHY_DPB_TO_SCC_34_DN")
	)
	(arc
		(start 118.36527 -4.261866)
		(mid 118.391044 -4.223293)
		(end 118.400068 -4.177792)
		(width 0.12446)
		(layer "B.Cu")
		(net "PHY_DPB_TO_SCC_34_DN")
	)
	(arc
		(start 118.280942 -4.296918)
		(mid 118.326598 -4.287801)
		(end 118.36527 -4.261866)
		(width 0.12446)
		(layer "B.Cu")
		(net "PHY_DPB_TO_SCC_34_DN")
	)
	(segment
		(start 118.33225 -29.761434)
		(end 118.542308 -29.44368)
		(width 0.12446)
		(layer "B.Cu")
		(net "PHY_DPB_TO_SCC_33_DP")
	)
	(segment
		(start 118.21033 -27.818588)
		(end 117.892576 -27.60853)
		(width 0.12446)
		(layer "B.Cu")
		(net "PHY_DPB_TO_SCC_33_DP")
	)
	(segment
		(start 118.149878 -28.867862)
		(end 118.075202 -28.502102)
		(width 0.12446)
		(layer "B.Cu")
		(net "PHY_DPB_TO_SCC_33_DP")
	)
	(segment
		(start 118.467632 -29.07792)
		(end 118.149878 -28.867862)
		(width 0.12446)
		(layer "B.Cu")
		(net "PHY_DPB_TO_SCC_33_DP")
	)
	(segment
		(start 118.542308 -29.44368)
		(end 118.467632 -29.07792)
		(width 0.12446)
		(layer "B.Cu")
		(net "PHY_DPB_TO_SCC_33_DP")
	)
	(segment
		(start 115.903248 -17.867376)
		(end 115.903248 -3.73634)
		(width 0.12446)
		(layer "B.Cu")
		(net "PHY_DPB_TO_SCC_33_DP")
	)
	(segment
		(start 118.285006 -28.184348)
		(end 118.21033 -27.818588)
		(width 0.12446)
		(layer "B.Cu")
		(net "PHY_DPB_TO_SCC_33_DP")
	)
	(segment
		(start 117.0178 -43.942)
		(end 116.926868 -43.851068)
		(width 0.12446)
		(layer "B.Cu")
		(net "PHY_DPB_TO_SCC_33_DP")
	)
	(segment
		(start 118.027704 -26.925016)
		(end 117.953028 -26.559256)
		(width 0.12446)
		(layer "B.Cu")
		(net "PHY_DPB_TO_SCC_33_DP")
	)
	(segment
		(start 117.8179 -27.24277)
		(end 118.027704 -26.925016)
		(width 0.12446)
		(layer "B.Cu")
		(net "PHY_DPB_TO_SCC_33_DP")
	)
	(segment
		(start 116.926868 -43.851068)
		(end 116.926868 -39.624)
		(width 0.12446)
		(layer "B.Cu")
		(net "PHY_DPB_TO_SCC_33_DP")
	)
	(segment
		(start 116.13642 -3.503168)
		(end 116.480844 -3.503168)
		(width 0.12446)
		(layer "B.Cu")
		(net "PHY_DPB_TO_SCC_33_DP")
	)
	(segment
		(start 116.926868 -39.624)
		(end 118.59387 -31.042102)
		(width 0.12446)
		(layer "B.Cu")
		(net "PHY_DPB_TO_SCC_33_DP")
	)
	(segment
		(start 118.075202 -28.502102)
		(end 118.285006 -28.184348)
		(width 0.12446)
		(layer "B.Cu")
		(net "PHY_DPB_TO_SCC_33_DP")
	)
	(segment
		(start 117.892576 -27.60853)
		(end 117.8179 -27.24277)
		(width 0.12446)
		(layer "B.Cu")
		(net "PHY_DPB_TO_SCC_33_DP")
	)
	(segment
		(start 117.953028 -26.559256)
		(end 117.635528 -26.349198)
		(width 0.12446)
		(layer "B.Cu")
		(net "PHY_DPB_TO_SCC_33_DP")
	)
	(segment
		(start 118.59387 -31.042102)
		(end 118.33225 -29.761434)
		(width 0.12446)
		(layer "B.Cu")
		(net "PHY_DPB_TO_SCC_33_DP")
	)
	(segment
		(start 117.635528 -26.349198)
		(end 115.903248 -17.867376)
		(width 0.12446)
		(layer "B.Cu")
		(net "PHY_DPB_TO_SCC_33_DP")
	)
	(segment
		(start 116.59997 -3.622294)
		(end 116.59997 -3.999992)
		(width 0.12446)
		(layer "B.Cu")
		(net "PHY_DPB_TO_SCC_33_DP")
	)
	(arc
		(start 116.480844 -3.503168)
		(mid 116.5265 -3.512285)
		(end 116.565172 -3.53822)
		(width 0.12446)
		(layer "B.Cu")
		(net "PHY_DPB_TO_SCC_33_DP")
	)
	(arc
		(start 116.565172 -3.53822)
		(mid 116.590946 -3.576793)
		(end 116.59997 -3.622294)
		(width 0.12446)
		(layer "B.Cu")
		(net "PHY_DPB_TO_SCC_33_DP")
	)
	(arc
		(start 115.903248 -3.73634)
		(mid 115.971542 -3.571462)
		(end 116.13642 -3.503168)
		(width 0.12446)
		(layer "B.Cu")
		(net "PHY_DPB_TO_SCC_33_DP")
	)
	(segment
		(start 115.496848 -17.908524)
		(end 115.496848 -3.73634)
		(width 0.12446)
		(layer "B.Cu")
		(net "PHY_DPB_TO_SCC_33_DN")
	)
	(segment
		(start 116.459 -43.942)
		(end 116.520468 -43.880532)
		(width 0.12446)
		(layer "B.Cu")
		(net "PHY_DPB_TO_SCC_33_DN")
	)
	(segment
		(start 116.59997 -2.977642)
		(end 116.59997 -2.600198)
		(width 0.12446)
		(layer "B.Cu")
		(net "PHY_DPB_TO_SCC_33_DN")
	)
	(segment
		(start 118.179342 -31.044134)
		(end 115.496848 -17.908524)
		(width 0.12446)
		(layer "B.Cu")
		(net "PHY_DPB_TO_SCC_33_DN")
	)
	(segment
		(start 116.520468 -39.584884)
		(end 118.179342 -31.044134)
		(width 0.12446)
		(layer "B.Cu")
		(net "PHY_DPB_TO_SCC_33_DN")
	)
	(segment
		(start 116.520468 -43.880532)
		(end 116.520468 -39.584884)
		(width 0.12446)
		(layer "B.Cu")
		(net "PHY_DPB_TO_SCC_33_DN")
	)
	(segment
		(start 116.13642 -3.096768)
		(end 116.480844 -3.096768)
		(width 0.12446)
		(layer "B.Cu")
		(net "PHY_DPB_TO_SCC_33_DN")
	)
	(arc
		(start 116.480844 -3.096768)
		(mid 116.5265 -3.087651)
		(end 116.565172 -3.061716)
		(width 0.12446)
		(layer "B.Cu")
		(net "PHY_DPB_TO_SCC_33_DN")
	)
	(arc
		(start 115.496848 -3.73634)
		(mid 115.684174 -3.284094)
		(end 116.13642 -3.096768)
		(width 0.12446)
		(layer "B.Cu")
		(net "PHY_DPB_TO_SCC_33_DN")
	)
	(arc
		(start 116.565172 -3.061716)
		(mid 116.590946 -3.023143)
		(end 116.59997 -2.977642)
		(width 0.12446)
		(layer "B.Cu")
		(net "PHY_DPB_TO_SCC_33_DN")
	)
	(segment
		(start 116.532914 -29.073348)
		(end 116.740178 -28.75407)
		(width 0.12446)
		(layer "B.Cu")
		(net "PHY_DPB_TO_SCC_32_DP")
	)
	(segment
		(start 116.610384 -29.4386)
		(end 116.532914 -29.073348)
		(width 0.12446)
		(layer "B.Cu")
		(net "PHY_DPB_TO_SCC_32_DP")
	)
	(segment
		(start 115.409726 -39.643304)
		(end 117.094508 -31.71698)
		(width 0.12446)
		(layer "B.Cu")
		(net "PHY_DPB_TO_SCC_32_DP")
	)
	(segment
		(start 116.076222 -26.924254)
		(end 114.103404 -17.639284)
		(width 0.12446)
		(layer "B.Cu")
		(net "PHY_DPB_TO_SCC_32_DP")
	)
	(segment
		(start 116.662708 -28.388818)
		(end 116.34343 -28.1813)
		(width 0.12446)
		(layer "B.Cu")
		(net "PHY_DPB_TO_SCC_32_DP")
	)
	(segment
		(start 116.799868 -30.330394)
		(end 117.007386 -30.011116)
		(width 0.12446)
		(layer "B.Cu")
		(net "PHY_DPB_TO_SCC_32_DP")
	)
	(segment
		(start 116.34343 -28.1813)
		(end 116.265706 -27.816048)
		(width 0.12446)
		(layer "B.Cu")
		(net "PHY_DPB_TO_SCC_32_DP")
	)
	(segment
		(start 115.409726 -43.857926)
		(end 115.409726 -39.643304)
		(width 0.12446)
		(layer "B.Cu")
		(net "PHY_DPB_TO_SCC_32_DP")
	)
	(segment
		(start 116.929662 -29.645864)
		(end 116.610384 -29.4386)
		(width 0.12446)
		(layer "B.Cu")
		(net "PHY_DPB_TO_SCC_32_DP")
	)
	(segment
		(start 115.4938 -43.942)
		(end 115.409726 -43.857926)
		(width 0.12446)
		(layer "B.Cu")
		(net "PHY_DPB_TO_SCC_32_DP")
	)
	(segment
		(start 116.740178 -28.75407)
		(end 116.662708 -28.388818)
		(width 0.12446)
		(layer "B.Cu")
		(net "PHY_DPB_TO_SCC_32_DP")
	)
	(segment
		(start 114.800126 -4.822444)
		(end 114.800126 -5.200142)
		(width 0.12446)
		(layer "B.Cu")
		(net "PHY_DPB_TO_SCC_32_DP")
	)
	(segment
		(start 116.265706 -27.816048)
		(end 116.473224 -27.49677)
		(width 0.12446)
		(layer "B.Cu")
		(net "PHY_DPB_TO_SCC_32_DP")
	)
	(segment
		(start 117.007386 -30.011116)
		(end 116.929662 -29.645864)
		(width 0.12446)
		(layer "B.Cu")
		(net "PHY_DPB_TO_SCC_32_DP")
	)
	(segment
		(start 114.103404 -17.639284)
		(end 114.103404 -4.93649)
		(width 0.12446)
		(layer "B.Cu")
		(net "PHY_DPB_TO_SCC_32_DP")
	)
	(segment
		(start 116.3955 -27.131518)
		(end 116.076222 -26.924254)
		(width 0.12446)
		(layer "B.Cu")
		(net "PHY_DPB_TO_SCC_32_DP")
	)
	(segment
		(start 114.336576 -4.703318)
		(end 114.681 -4.703318)
		(width 0.12446)
		(layer "B.Cu")
		(net "PHY_DPB_TO_SCC_32_DP")
	)
	(segment
		(start 117.094508 -31.71698)
		(end 116.799868 -30.330394)
		(width 0.12446)
		(layer "B.Cu")
		(net "PHY_DPB_TO_SCC_32_DP")
	)
	(segment
		(start 116.473224 -27.49677)
		(end 116.3955 -27.131518)
		(width 0.12446)
		(layer "B.Cu")
		(net "PHY_DPB_TO_SCC_32_DP")
	)
	(arc
		(start 114.765328 -4.73837)
		(mid 114.791102 -4.776943)
		(end 114.800126 -4.822444)
		(width 0.12446)
		(layer "B.Cu")
		(net "PHY_DPB_TO_SCC_32_DP")
	)
	(arc
		(start 114.681 -4.703318)
		(mid 114.726656 -4.712435)
		(end 114.765328 -4.73837)
		(width 0.12446)
		(layer "B.Cu")
		(net "PHY_DPB_TO_SCC_32_DP")
	)
	(arc
		(start 114.103404 -4.93649)
		(mid 114.171698 -4.771612)
		(end 114.336576 -4.703318)
		(width 0.12446)
		(layer "B.Cu")
		(net "PHY_DPB_TO_SCC_32_DP")
	)
	(segment
		(start 115.003326 -39.600378)
		(end 116.678964 -31.71698)
		(width 0.12446)
		(layer "B.Cu")
		(net "PHY_DPB_TO_SCC_32_DN")
	)
	(segment
		(start 115.003326 -43.873674)
		(end 115.003326 -39.600378)
		(width 0.12446)
		(layer "B.Cu")
		(net "PHY_DPB_TO_SCC_32_DN")
	)
	(segment
		(start 113.697004 -17.68221)
		(end 113.697004 -4.93649)
		(width 0.12446)
		(layer "B.Cu")
		(net "PHY_DPB_TO_SCC_32_DN")
	)
	(segment
		(start 116.678964 -31.71698)
		(end 113.697004 -17.68221)
		(width 0.12446)
		(layer "B.Cu")
		(net "PHY_DPB_TO_SCC_32_DN")
	)
	(segment
		(start 114.800126 -4.177792)
		(end 114.800126 -3.800094)
		(width 0.12446)
		(layer "B.Cu")
		(net "PHY_DPB_TO_SCC_32_DN")
	)
	(segment
		(start 114.935 -43.942)
		(end 115.003326 -43.873674)
		(width 0.12446)
		(layer "B.Cu")
		(net "PHY_DPB_TO_SCC_32_DN")
	)
	(segment
		(start 114.336576 -4.296918)
		(end 114.681 -4.296918)
		(width 0.12446)
		(layer "B.Cu")
		(net "PHY_DPB_TO_SCC_32_DN")
	)
	(arc
		(start 114.681 -4.296918)
		(mid 114.726656 -4.287801)
		(end 114.765328 -4.261866)
		(width 0.12446)
		(layer "B.Cu")
		(net "PHY_DPB_TO_SCC_32_DN")
	)
	(arc
		(start 113.697004 -4.93649)
		(mid 113.88433 -4.484244)
		(end 114.336576 -4.296918)
		(width 0.12446)
		(layer "B.Cu")
		(net "PHY_DPB_TO_SCC_32_DN")
	)
	(arc
		(start 114.765328 -4.261866)
		(mid 114.791102 -4.223293)
		(end 114.800126 -4.177792)
		(width 0.12446)
		(layer "B.Cu")
		(net "PHY_DPB_TO_SCC_32_DN")
	)
	(segment
		(start 134.600188 -3.622294)
		(end 134.600188 -3.999992)
		(width 0.12446)
		(layer "B.Cu")
		(net "PHY_DPB_TO_SCC_31_DP")
	)
	(segment
		(start 133.632702 -30.521402)
		(end 133.425438 -30.202124)
		(width 0.12446)
		(layer "B.Cu")
		(net "PHY_DPB_TO_SCC_31_DP")
	)
	(segment
		(start 133.15823 -31.45917)
		(end 133.235954 -31.093918)
		(width 0.12446)
		(layer "B.Cu")
		(net "PHY_DPB_TO_SCC_31_DP")
	)
	(segment
		(start 133.425438 -30.202124)
		(end 133.503162 -29.836872)
		(width 0.12446)
		(layer "B.Cu")
		(net "PHY_DPB_TO_SCC_31_DP")
	)
	(segment
		(start 135.405622 -55.251858)
		(end 135.686292 -53.93182)
		(width 0.12446)
		(layer "B.Cu")
		(net "PHY_DPB_TO_SCC_31_DP")
	)
	(segment
		(start 135.839962 -46.588172)
		(end 132.891022 -32.716216)
		(width 0.12446)
		(layer "B.Cu")
		(net "PHY_DPB_TO_SCC_31_DP")
	)
	(segment
		(start 132.891022 -32.716216)
		(end 132.968746 -32.350964)
		(width 0.12446)
		(layer "B.Cu")
		(net "PHY_DPB_TO_SCC_31_DP")
	)
	(segment
		(start 135.065008 -50.232818)
		(end 135.839962 -46.588172)
		(width 0.12446)
		(layer "B.Cu")
		(net "PHY_DPB_TO_SCC_31_DP")
	)
	(segment
		(start 133.82244 -29.629608)
		(end 133.89991 -29.264356)
		(width 0.12446)
		(layer "B.Cu")
		(net "PHY_DPB_TO_SCC_31_DP")
	)
	(segment
		(start 133.555232 -30.886654)
		(end 133.632702 -30.521402)
		(width 0.12446)
		(layer "B.Cu")
		(net "PHY_DPB_TO_SCC_31_DP")
	)
	(segment
		(start 135.686292 -53.154072)
		(end 135.065008 -50.232818)
		(width 0.12446)
		(layer "B.Cu")
		(net "PHY_DPB_TO_SCC_31_DP")
	)
	(segment
		(start 133.692646 -28.945078)
		(end 135.15721 -22.054566)
		(width 0.12446)
		(layer "B.Cu")
		(net "PHY_DPB_TO_SCC_31_DP")
	)
	(segment
		(start 135.686292 -53.93182)
		(end 135.686292 -53.154072)
		(width 0.12446)
		(layer "B.Cu")
		(net "PHY_DPB_TO_SCC_31_DP")
	)
	(segment
		(start 135.15721 -22.054566)
		(end 133.903466 -16.156178)
		(width 0.12446)
		(layer "B.Cu")
		(net "PHY_DPB_TO_SCC_31_DP")
	)
	(segment
		(start 133.235954 -31.093918)
		(end 133.555232 -30.886654)
		(width 0.12446)
		(layer "B.Cu")
		(net "PHY_DPB_TO_SCC_31_DP")
	)
	(segment
		(start 132.968746 -32.350964)
		(end 133.288024 -32.1437)
		(width 0.12446)
		(layer "B.Cu")
		(net "PHY_DPB_TO_SCC_31_DP")
	)
	(segment
		(start 135.405622 -56.100218)
		(end 135.405622 -55.251858)
		(width 0.12446)
		(layer "B.Cu")
		(net "PHY_DPB_TO_SCC_31_DP")
	)
	(segment
		(start 133.288024 -32.1437)
		(end 133.365494 -31.778448)
		(width 0.12446)
		(layer "B.Cu")
		(net "PHY_DPB_TO_SCC_31_DP")
	)
	(segment
		(start 134.136638 -3.503168)
		(end 134.481062 -3.503168)
		(width 0.12446)
		(layer "B.Cu")
		(net "PHY_DPB_TO_SCC_31_DP")
	)
	(segment
		(start 133.89991 -29.264356)
		(end 133.692646 -28.945078)
		(width 0.12446)
		(layer "B.Cu")
		(net "PHY_DPB_TO_SCC_31_DP")
	)
	(segment
		(start 133.903466 -16.156178)
		(end 133.903466 -3.73634)
		(width 0.12446)
		(layer "B.Cu")
		(net "PHY_DPB_TO_SCC_31_DP")
	)
	(segment
		(start 133.365494 -31.778448)
		(end 133.15823 -31.45917)
		(width 0.12446)
		(layer "B.Cu")
		(net "PHY_DPB_TO_SCC_31_DP")
	)
	(segment
		(start 133.503162 -29.836872)
		(end 133.82244 -29.629608)
		(width 0.12446)
		(layer "B.Cu")
		(net "PHY_DPB_TO_SCC_31_DP")
	)
	(arc
		(start 133.903466 -3.73634)
		(mid 133.97176 -3.571462)
		(end 134.136638 -3.503168)
		(width 0.12446)
		(layer "B.Cu")
		(net "PHY_DPB_TO_SCC_31_DP")
	)
	(arc
		(start 134.481062 -3.503168)
		(mid 134.526718 -3.512285)
		(end 134.56539 -3.53822)
		(width 0.12446)
		(layer "B.Cu")
		(net "PHY_DPB_TO_SCC_31_DP")
	)
	(arc
		(start 134.56539 -3.53822)
		(mid 134.591164 -3.576793)
		(end 134.600188 -3.622294)
		(width 0.12446)
		(layer "B.Cu")
		(net "PHY_DPB_TO_SCC_31_DP")
	)
	(segment
		(start 134.136638 -3.096768)
		(end 134.481062 -3.096768)
		(width 0.12446)
		(layer "B.Cu")
		(net "PHY_DPB_TO_SCC_31_DN")
	)
	(segment
		(start 135.279892 -53.888894)
		(end 135.279892 -53.196998)
		(width 0.12446)
		(layer "B.Cu")
		(net "PHY_DPB_TO_SCC_31_DN")
	)
	(segment
		(start 134.741666 -22.054566)
		(end 133.497066 -16.199104)
		(width 0.12446)
		(layer "B.Cu")
		(net "PHY_DPB_TO_SCC_31_DN")
	)
	(segment
		(start 135.279892 -53.196998)
		(end 134.649464 -50.232818)
		(width 0.12446)
		(layer "B.Cu")
		(net "PHY_DPB_TO_SCC_31_DN")
	)
	(segment
		(start 134.846822 -56.100218)
		(end 134.999222 -55.947818)
		(width 0.12446)
		(layer "B.Cu")
		(net "PHY_DPB_TO_SCC_31_DN")
	)
	(segment
		(start 134.999222 -55.208932)
		(end 135.279892 -53.888894)
		(width 0.12446)
		(layer "B.Cu")
		(net "PHY_DPB_TO_SCC_31_DN")
	)
	(segment
		(start 135.424418 -46.588172)
		(end 132.475478 -32.716216)
		(width 0.12446)
		(layer "B.Cu")
		(net "PHY_DPB_TO_SCC_31_DN")
	)
	(segment
		(start 134.600188 -2.977642)
		(end 134.600188 -2.600198)
		(width 0.12446)
		(layer "B.Cu")
		(net "PHY_DPB_TO_SCC_31_DN")
	)
	(segment
		(start 134.649464 -50.232818)
		(end 135.424418 -46.588172)
		(width 0.12446)
		(layer "B.Cu")
		(net "PHY_DPB_TO_SCC_31_DN")
	)
	(segment
		(start 133.497066 -16.199104)
		(end 133.497066 -3.73634)
		(width 0.12446)
		(layer "B.Cu")
		(net "PHY_DPB_TO_SCC_31_DN")
	)
	(segment
		(start 134.999222 -55.947818)
		(end 134.999222 -55.208932)
		(width 0.12446)
		(layer "B.Cu")
		(net "PHY_DPB_TO_SCC_31_DN")
	)
	(segment
		(start 132.475478 -32.716216)
		(end 133.295136 -28.860242)
		(width 0.12446)
		(layer "B.Cu")
		(net "PHY_DPB_TO_SCC_31_DN")
	)
	(segment
		(start 133.295136 -28.860242)
		(end 133.294882 -28.860242)
		(width 0.12446)
		(layer "B.Cu")
		(net "PHY_DPB_TO_SCC_31_DN")
	)
	(segment
		(start 133.294882 -28.860242)
		(end 134.741666 -22.054566)
		(width 0.12446)
		(layer "B.Cu")
		(net "PHY_DPB_TO_SCC_31_DN")
	)
	(arc
		(start 133.497066 -3.73634)
		(mid 133.684392 -3.284094)
		(end 134.136638 -3.096768)
		(width 0.12446)
		(layer "B.Cu")
		(net "PHY_DPB_TO_SCC_31_DN")
	)
	(arc
		(start 134.481062 -3.096768)
		(mid 134.526718 -3.087651)
		(end 134.56539 -3.061716)
		(width 0.12446)
		(layer "B.Cu")
		(net "PHY_DPB_TO_SCC_31_DN")
	)
	(arc
		(start 134.56539 -3.061716)
		(mid 134.591164 -3.023143)
		(end 134.600188 -2.977642)
		(width 0.12446)
		(layer "B.Cu")
		(net "PHY_DPB_TO_SCC_31_DN")
	)
	(segment
		(start 132.496306 -28.546044)
		(end 132.177028 -28.753308)
		(width 0.12446)
		(layer "B.Cu")
		(net "PHY_DPB_TO_SCC_30_DP")
	)
	(segment
		(start 131.642358 -31.267654)
		(end 131.400042 -32.407606)
		(width 0.12446)
		(layer "B.Cu")
		(net "PHY_DPB_TO_SCC_30_DP")
	)
	(segment
		(start 132.229098 -29.80309)
		(end 131.909566 -30.010608)
		(width 0.12446)
		(layer "B.Cu")
		(net "PHY_DPB_TO_SCC_30_DP")
	)
	(segment
		(start 131.832096 -30.375606)
		(end 132.03936 -30.695138)
		(width 0.12446)
		(layer "B.Cu")
		(net "PHY_DPB_TO_SCC_30_DP")
	)
	(segment
		(start 132.103368 -4.93649)
		(end 132.103368 -16.178784)
		(width 0.12446)
		(layer "B.Cu")
		(net "PHY_DPB_TO_SCC_30_DP")
	)
	(segment
		(start 133.7691 -43.55338)
		(end 133.7691 -44.0563)
		(width 0.12446)
		(layer "B.Cu")
		(net "PHY_DPB_TO_SCC_30_DP")
	)
	(segment
		(start 132.306568 -29.437838)
		(end 132.229098 -29.80309)
		(width 0.12446)
		(layer "B.Cu")
		(net "PHY_DPB_TO_SCC_30_DP")
	)
	(segment
		(start 132.573776 -28.180792)
		(end 132.496306 -28.546044)
		(width 0.12446)
		(layer "B.Cu")
		(net "PHY_DPB_TO_SCC_30_DP")
	)
	(segment
		(start 132.366512 -27.861514)
		(end 132.573776 -28.180792)
		(width 0.12446)
		(layer "B.Cu")
		(net "PHY_DPB_TO_SCC_30_DP")
	)
	(segment
		(start 133.476746 -22.63902)
		(end 132.366512 -27.861514)
		(width 0.12446)
		(layer "B.Cu")
		(net "PHY_DPB_TO_SCC_30_DP")
	)
	(segment
		(start 131.400042 -32.407606)
		(end 133.7691 -43.55338)
		(width 0.12446)
		(layer "B.Cu")
		(net "PHY_DPB_TO_SCC_30_DP")
	)
	(segment
		(start 132.03936 -30.695138)
		(end 131.961636 -31.06039)
		(width 0.12446)
		(layer "B.Cu")
		(net "PHY_DPB_TO_SCC_30_DP")
	)
	(segment
		(start 132.177028 -28.753308)
		(end 132.099304 -29.11856)
		(width 0.12446)
		(layer "B.Cu")
		(net "PHY_DPB_TO_SCC_30_DP")
	)
	(segment
		(start 132.099304 -29.11856)
		(end 132.306568 -29.437838)
		(width 0.12446)
		(layer "B.Cu")
		(net "PHY_DPB_TO_SCC_30_DP")
	)
	(segment
		(start 131.961636 -31.06039)
		(end 131.642358 -31.267654)
		(width 0.12446)
		(layer "B.Cu")
		(net "PHY_DPB_TO_SCC_30_DP")
	)
	(segment
		(start 131.909566 -30.010608)
		(end 131.832096 -30.375606)
		(width 0.12446)
		(layer "B.Cu")
		(net "PHY_DPB_TO_SCC_30_DP")
	)
	(segment
		(start 132.80009 -5.200142)
		(end 132.80009 -4.822444)
		(width 0.12446)
		(layer "B.Cu")
		(net "PHY_DPB_TO_SCC_30_DP")
	)
	(segment
		(start 132.680964 -4.703318)
		(end 132.33654 -4.703318)
		(width 0.12446)
		(layer "B.Cu")
		(net "PHY_DPB_TO_SCC_30_DP")
	)
	(segment
		(start 133.7691 -44.0563)
		(end 133.8326 -44.1198)
		(width 0.12446)
		(layer "B.Cu")
		(net "PHY_DPB_TO_SCC_30_DP")
	)
	(segment
		(start 132.103368 -16.178784)
		(end 133.476746 -22.63902)
		(width 0.12446)
		(layer "B.Cu")
		(net "PHY_DPB_TO_SCC_30_DP")
	)
	(arc
		(start 132.765292 -4.73837)
		(mid 132.726631 -4.71241)
		(end 132.680964 -4.703318)
		(width 0.12446)
		(layer "B.Cu")
		(net "PHY_DPB_TO_SCC_30_DP")
	)
	(arc
		(start 132.33654 -4.703318)
		(mid 132.171662 -4.771612)
		(end 132.103368 -4.93649)
		(width 0.12446)
		(layer "B.Cu")
		(net "PHY_DPB_TO_SCC_30_DP")
	)
	(arc
		(start 132.80009 -4.822444)
		(mid 132.791041 -4.776954)
		(end 132.765292 -4.73837)
		(width 0.12446)
		(layer "B.Cu")
		(net "PHY_DPB_TO_SCC_30_DP")
	)
	(segment
		(start 132.80009 -3.800094)
		(end 132.80009 -4.177792)
		(width 0.12446)
		(layer "B.Cu")
		(net "PHY_DPB_TO_SCC_30_DN")
	)
	(segment
		(start 133.3627 -44.0309)
		(end 133.2738 -44.1198)
		(width 0.12446)
		(layer "B.Cu")
		(net "PHY_DPB_TO_SCC_30_DN")
	)
	(segment
		(start 133.061202 -22.63902)
		(end 130.984498 -32.407606)
		(width 0.12446)
		(layer "B.Cu")
		(net "PHY_DPB_TO_SCC_30_DN")
	)
	(segment
		(start 133.3627 -43.596306)
		(end 133.3627 -44.0309)
		(width 0.12446)
		(layer "B.Cu")
		(net "PHY_DPB_TO_SCC_30_DN")
	)
	(segment
		(start 131.696968 -4.93649)
		(end 131.696968 -16.22171)
		(width 0.12446)
		(layer "B.Cu")
		(net "PHY_DPB_TO_SCC_30_DN")
	)
	(segment
		(start 131.696968 -16.22171)
		(end 133.061202 -22.63902)
		(width 0.12446)
		(layer "B.Cu")
		(net "PHY_DPB_TO_SCC_30_DN")
	)
	(segment
		(start 130.984498 -32.407606)
		(end 133.3627 -43.596306)
		(width 0.12446)
		(layer "B.Cu")
		(net "PHY_DPB_TO_SCC_30_DN")
	)
	(segment
		(start 132.680964 -4.296918)
		(end 132.33654 -4.296918)
		(width 0.12446)
		(layer "B.Cu")
		(net "PHY_DPB_TO_SCC_30_DN")
	)
	(arc
		(start 132.765292 -4.261866)
		(mid 132.726631 -4.287826)
		(end 132.680964 -4.296918)
		(width 0.12446)
		(layer "B.Cu")
		(net "PHY_DPB_TO_SCC_30_DN")
	)
	(arc
		(start 132.80009 -4.177792)
		(mid 132.791041 -4.223282)
		(end 132.765292 -4.261866)
		(width 0.12446)
		(layer "B.Cu")
		(net "PHY_DPB_TO_SCC_30_DN")
	)
	(arc
		(start 132.33654 -4.296918)
		(mid 131.884294 -4.484244)
		(end 131.696968 -4.93649)
		(width 0.12446)
		(layer "B.Cu")
		(net "PHY_DPB_TO_SCC_30_DN")
	)
	(segment
		(start 140.399262 -48.782732)
		(end 141.062202 -45.664628)
		(width 0.12446)
		(layer "B.Cu")
		(net "PHY_DPB_TO_SCC_3_DP")
	)
	(segment
		(start 141.062202 -45.664628)
		(end 138.332464 -32.822134)
		(width 0.12446)
		(layer "B.Cu")
		(net "PHY_DPB_TO_SCC_3_DP")
	)
	(segment
		(start 141.603476 -54.446932)
		(end 140.399262 -48.782732)
		(width 0.12446)
		(layer "B.Cu")
		(net "PHY_DPB_TO_SCC_3_DP")
	)
	(segment
		(start 137.7442 -68.3514)
		(end 138.123168 -68.3514)
		(width 0.12446)
		(layer "B.Cu")
		(net "PHY_DPB_TO_SCC_3_DP")
	)
	(segment
		(start 141.10335 -15.233142)
		(end 141.10335 -3.73634)
		(width 0.12446)
		(layer "B.Cu")
		(net "PHY_DPB_TO_SCC_3_DP")
	)
	(segment
		(start 138.332464 -32.822134)
		(end 141.572488 -17.579086)
		(width 0.12446)
		(layer "B.Cu")
		(net "PHY_DPB_TO_SCC_3_DP")
	)
	(segment
		(start 141.800072 -3.622294)
		(end 141.800072 -3.999992)
		(width 0.12446)
		(layer "B.Cu")
		(net "PHY_DPB_TO_SCC_3_DP")
	)
	(segment
		(start 141.572488 -17.579086)
		(end 141.10335 -15.233142)
		(width 0.12446)
		(layer "B.Cu")
		(net "PHY_DPB_TO_SCC_3_DP")
	)
	(segment
		(start 143.574008 -57.480962)
		(end 141.603476 -54.446932)
		(width 0.12446)
		(layer "B.Cu")
		(net "PHY_DPB_TO_SCC_3_DP")
	)
	(segment
		(start 138.227308 -68.24726)
		(end 139.291568 -68.24726)
		(width 0.12446)
		(layer "B.Cu")
		(net "PHY_DPB_TO_SCC_3_DP")
	)
	(segment
		(start 141.336522 -3.503168)
		(end 141.680946 -3.503168)
		(width 0.12446)
		(layer "B.Cu")
		(net "PHY_DPB_TO_SCC_3_DP")
	)
	(segment
		(start 144.503394 -61.854334)
		(end 143.574008 -57.480962)
		(width 0.12446)
		(layer "B.Cu")
		(net "PHY_DPB_TO_SCC_3_DP")
	)
	(segment
		(start 142.741396 -66.681858)
		(end 143.834358 -64.999616)
		(width 0.12446)
		(layer "B.Cu")
		(net "PHY_DPB_TO_SCC_3_DP")
	)
	(segment
		(start 143.834358 -64.999616)
		(end 144.503394 -61.854334)
		(width 0.12446)
		(layer "B.Cu")
		(net "PHY_DPB_TO_SCC_3_DP")
	)
	(segment
		(start 140.836396 -67.919092)
		(end 142.741396 -66.681858)
		(width 0.12446)
		(layer "B.Cu")
		(net "PHY_DPB_TO_SCC_3_DP")
	)
	(segment
		(start 138.123168 -68.3514)
		(end 138.227308 -68.24726)
		(width 0.12446)
		(layer "B.Cu")
		(net "PHY_DPB_TO_SCC_3_DP")
	)
	(segment
		(start 139.291568 -68.24726)
		(end 140.836396 -67.919092)
		(width 0.12446)
		(layer "B.Cu")
		(net "PHY_DPB_TO_SCC_3_DP")
	)
	(arc
		(start 141.680946 -3.503168)
		(mid 141.726602 -3.512285)
		(end 141.765274 -3.53822)
		(width 0.12446)
		(layer "B.Cu")
		(net "PHY_DPB_TO_SCC_3_DP")
	)
	(arc
		(start 141.10335 -3.73634)
		(mid 141.171644 -3.571462)
		(end 141.336522 -3.503168)
		(width 0.12446)
		(layer "B.Cu")
		(net "PHY_DPB_TO_SCC_3_DP")
	)
	(arc
		(start 141.765274 -3.53822)
		(mid 141.791048 -3.576793)
		(end 141.800072 -3.622294)
		(width 0.12446)
		(layer "B.Cu")
		(net "PHY_DPB_TO_SCC_3_DP")
	)
	(segment
		(start 141.22146 -54.605174)
		(end 139.983718 -48.782732)
		(width 0.12446)
		(layer "B.Cu")
		(net "PHY_DPB_TO_SCC_3_DN")
	)
	(segment
		(start 140.69695 -15.268448)
		(end 140.69695 -3.73634)
		(width 0.12446)
		(layer "B.Cu")
		(net "PHY_DPB_TO_SCC_3_DN")
	)
	(segment
		(start 142.949676 -65.614804)
		(end 143.452342 -64.841374)
		(width 0.12446)
		(layer "B.Cu")
		(net "PHY_DPB_TO_SCC_3_DN")
	)
	(segment
		(start 138.123168 -67.7926)
		(end 138.171428 -67.84086)
		(width 0.12446)
		(layer "B.Cu")
		(net "PHY_DPB_TO_SCC_3_DN")
	)
	(segment
		(start 140.646658 -45.664628)
		(end 137.91692 -32.822134)
		(width 0.12446)
		(layer "B.Cu")
		(net "PHY_DPB_TO_SCC_3_DN")
	)
	(segment
		(start 139.983718 -48.782732)
		(end 140.646658 -45.664628)
		(width 0.12446)
		(layer "B.Cu")
		(net "PHY_DPB_TO_SCC_3_DN")
	)
	(segment
		(start 143.452342 -64.841374)
		(end 144.08785 -61.854334)
		(width 0.12446)
		(layer "B.Cu")
		(net "PHY_DPB_TO_SCC_3_DN")
	)
	(segment
		(start 144.08785 -61.854334)
		(end 143.191992 -57.639204)
		(width 0.12446)
		(layer "B.Cu")
		(net "PHY_DPB_TO_SCC_3_DN")
	)
	(segment
		(start 139.248642 -67.84086)
		(end 140.678154 -67.537076)
		(width 0.12446)
		(layer "B.Cu")
		(net "PHY_DPB_TO_SCC_3_DN")
	)
	(segment
		(start 141.336522 -3.096768)
		(end 141.680946 -3.096768)
		(width 0.12446)
		(layer "B.Cu")
		(net "PHY_DPB_TO_SCC_3_DN")
	)
	(segment
		(start 138.171428 -67.84086)
		(end 139.248642 -67.84086)
		(width 0.12446)
		(layer "B.Cu")
		(net "PHY_DPB_TO_SCC_3_DN")
	)
	(segment
		(start 141.157452 -17.576546)
		(end 140.695934 -15.269464)
		(width 0.12446)
		(layer "B.Cu")
		(net "PHY_DPB_TO_SCC_3_DN")
	)
	(segment
		(start 137.91692 -32.822134)
		(end 141.157452 -17.576546)
		(width 0.12446)
		(layer "B.Cu")
		(net "PHY_DPB_TO_SCC_3_DN")
	)
	(segment
		(start 143.191992 -57.639204)
		(end 141.22146 -54.605174)
		(width 0.12446)
		(layer "B.Cu")
		(net "PHY_DPB_TO_SCC_3_DN")
	)
	(segment
		(start 141.800072 -2.977642)
		(end 141.800072 -2.600198)
		(width 0.12446)
		(layer "B.Cu")
		(net "PHY_DPB_TO_SCC_3_DN")
	)
	(segment
		(start 140.678154 -67.537076)
		(end 142.447518 -66.38798)
		(width 0.12446)
		(layer "B.Cu")
		(net "PHY_DPB_TO_SCC_3_DN")
	)
	(segment
		(start 140.695934 -15.269464)
		(end 140.69695 -15.268448)
		(width 0.12446)
		(layer "B.Cu")
		(net "PHY_DPB_TO_SCC_3_DN")
	)
	(segment
		(start 137.7442 -67.7926)
		(end 138.123168 -67.7926)
		(width 0.12446)
		(layer "B.Cu")
		(net "PHY_DPB_TO_SCC_3_DN")
	)
	(segment
		(start 142.447518 -66.38798)
		(end 142.949676 -65.614804)
		(width 0.12446)
		(layer "B.Cu")
		(net "PHY_DPB_TO_SCC_3_DN")
	)
	(arc
		(start 141.680946 -3.096768)
		(mid 141.726602 -3.087651)
		(end 141.765274 -3.061716)
		(width 0.12446)
		(layer "B.Cu")
		(net "PHY_DPB_TO_SCC_3_DN")
	)
	(arc
		(start 140.69695 -3.73634)
		(mid 140.884276 -3.284094)
		(end 141.336522 -3.096768)
		(width 0.12446)
		(layer "B.Cu")
		(net "PHY_DPB_TO_SCC_3_DN")
	)
	(arc
		(start 141.765274 -3.061716)
		(mid 141.791048 -3.023143)
		(end 141.800072 -2.977642)
		(width 0.12446)
		(layer "B.Cu")
		(net "PHY_DPB_TO_SCC_3_DN")
	)
	(segment
		(start 131.949444 -21.36902)
		(end 131.741926 -21.688552)
		(width 0.12446)
		(layer "B.Cu")
		(net "PHY_DPB_TO_SCC_29_DP")
	)
	(segment
		(start 131.604766 -19.746722)
		(end 131.682236 -20.111974)
		(width 0.12446)
		(layer "B.Cu")
		(net "PHY_DPB_TO_SCC_29_DP")
	)
	(segment
		(start 131.2926 -44.009818)
		(end 131.38277 -44.099988)
		(width 0.12446)
		(layer "B.Cu")
		(net "PHY_DPB_TO_SCC_29_DP")
	)
	(segment
		(start 130.880866 -3.503168)
		(end 130.536442 -3.503168)
		(width 0.12446)
		(layer "B.Cu")
		(net "PHY_DPB_TO_SCC_29_DP")
	)
	(segment
		(start 131.819396 -22.05355)
		(end 132.138928 -22.261068)
		(width 0.12446)
		(layer "B.Cu")
		(net "PHY_DPB_TO_SCC_29_DP")
	)
	(segment
		(start 131.682236 -20.111974)
		(end 131.474718 -20.431252)
		(width 0.12446)
		(layer "B.Cu")
		(net "PHY_DPB_TO_SCC_29_DP")
	)
	(segment
		(start 132.009134 -22.945598)
		(end 132.086604 -23.31085)
		(width 0.12446)
		(layer "B.Cu")
		(net "PHY_DPB_TO_SCC_29_DP")
	)
	(segment
		(start 131.552442 -20.796504)
		(end 131.87172 -21.004022)
		(width 0.12446)
		(layer "B.Cu")
		(net "PHY_DPB_TO_SCC_29_DP")
	)
	(segment
		(start 132.086604 -23.31085)
		(end 130.005582 -33.104074)
		(width 0.12446)
		(layer "B.Cu")
		(net "PHY_DPB_TO_SCC_29_DP")
	)
	(segment
		(start 131.87172 -21.004022)
		(end 131.949444 -21.36902)
		(width 0.12446)
		(layer "B.Cu")
		(net "PHY_DPB_TO_SCC_29_DP")
	)
	(segment
		(start 130.58521 -16.244062)
		(end 131.285234 -19.539204)
		(width 0.12446)
		(layer "B.Cu")
		(net "PHY_DPB_TO_SCC_29_DP")
	)
	(segment
		(start 130.548634 -16.07185)
		(end 130.58521 -16.244062)
		(width 0.12446)
		(layer "B.Cu")
		(net "PHY_DPB_TO_SCC_29_DP")
	)
	(segment
		(start 131.741926 -21.688552)
		(end 131.819396 -22.05355)
		(width 0.12446)
		(layer "B.Cu")
		(net "PHY_DPB_TO_SCC_29_DP")
	)
	(segment
		(start 132.216398 -22.62632)
		(end 132.009134 -22.945598)
		(width 0.12446)
		(layer "B.Cu")
		(net "PHY_DPB_TO_SCC_29_DP")
	)
	(segment
		(start 131.2926 -43.44035)
		(end 131.2926 -44.009818)
		(width 0.12446)
		(layer "B.Cu")
		(net "PHY_DPB_TO_SCC_29_DP")
	)
	(segment
		(start 130.30327 -14.916912)
		(end 130.48742 -15.783052)
		(width 0.12446)
		(layer "B.Cu")
		(net "PHY_DPB_TO_SCC_29_DP")
	)
	(segment
		(start 130.999992 -3.999992)
		(end 130.999992 -3.622294)
		(width 0.12446)
		(layer "B.Cu")
		(net "PHY_DPB_TO_SCC_29_DP")
	)
	(segment
		(start 130.48742 -15.783052)
		(end 130.548888 -16.07185)
		(width 0.12446)
		(layer "B.Cu")
		(net "PHY_DPB_TO_SCC_29_DP")
	)
	(segment
		(start 131.285234 -19.539204)
		(end 131.604766 -19.746722)
		(width 0.12446)
		(layer "B.Cu")
		(net "PHY_DPB_TO_SCC_29_DP")
	)
	(segment
		(start 130.005582 -33.104074)
		(end 131.747514 -41.299892)
		(width 0.12446)
		(layer "B.Cu")
		(net "PHY_DPB_TO_SCC_29_DP")
	)
	(segment
		(start 131.474718 -20.431252)
		(end 131.552442 -20.796504)
		(width 0.12446)
		(layer "B.Cu")
		(net "PHY_DPB_TO_SCC_29_DP")
	)
	(segment
		(start 131.747514 -41.299892)
		(end 131.2926 -43.44035)
		(width 0.12446)
		(layer "B.Cu")
		(net "PHY_DPB_TO_SCC_29_DP")
	)
	(segment
		(start 132.138928 -22.261068)
		(end 132.216398 -22.62632)
		(width 0.12446)
		(layer "B.Cu")
		(net "PHY_DPB_TO_SCC_29_DP")
	)
	(segment
		(start 130.30327 -3.73634)
		(end 130.30327 -14.916912)
		(width 0.12446)
		(layer "B.Cu")
		(net "PHY_DPB_TO_SCC_29_DP")
	)
	(segment
		(start 130.548888 -16.07185)
		(end 130.548634 -16.07185)
		(width 0.12446)
		(layer "B.Cu")
		(net "PHY_DPB_TO_SCC_29_DP")
	)
	(arc
		(start 130.965194 -3.53822)
		(mid 130.926533 -3.51226)
		(end 130.880866 -3.503168)
		(width 0.12446)
		(layer "B.Cu")
		(net "PHY_DPB_TO_SCC_29_DP")
	)
	(arc
		(start 130.999992 -3.622294)
		(mid 130.990943 -3.576804)
		(end 130.965194 -3.53822)
		(width 0.12446)
		(layer "B.Cu")
		(net "PHY_DPB_TO_SCC_29_DP")
	)
	(arc
		(start 130.536442 -3.503168)
		(mid 130.371564 -3.571462)
		(end 130.30327 -3.73634)
		(width 0.12446)
		(layer "B.Cu")
		(net "PHY_DPB_TO_SCC_29_DP")
	)
	(segment
		(start 129.89687 -14.959584)
		(end 130.396488 -17.31264)
		(width 0.12446)
		(layer "B.Cu")
		(net "PHY_DPB_TO_SCC_29_DN")
	)
	(segment
		(start 129.590038 -33.104074)
		(end 131.33197 -41.299892)
		(width 0.12446)
		(layer "B.Cu")
		(net "PHY_DPB_TO_SCC_29_DN")
	)
	(segment
		(start 130.8862 -43.397424)
		(end 130.8862 -44.037758)
		(width 0.12446)
		(layer "B.Cu")
		(net "PHY_DPB_TO_SCC_29_DN")
	)
	(segment
		(start 131.67106 -23.31085)
		(end 129.590038 -33.104074)
		(width 0.12446)
		(layer "B.Cu")
		(net "PHY_DPB_TO_SCC_29_DN")
	)
	(segment
		(start 130.801618 -19.21891)
		(end 131.67106 -23.31085)
		(width 0.12446)
		(layer "B.Cu")
		(net "PHY_DPB_TO_SCC_29_DN")
	)
	(segment
		(start 130.396488 -17.31264)
		(end 130.801618 -19.21891)
		(width 0.12446)
		(layer "B.Cu")
		(net "PHY_DPB_TO_SCC_29_DN")
	)
	(segment
		(start 130.880866 -3.096768)
		(end 130.536442 -3.096768)
		(width 0.12446)
		(layer "B.Cu")
		(net "PHY_DPB_TO_SCC_29_DN")
	)
	(segment
		(start 131.33197 -41.299892)
		(end 130.8862 -43.397424)
		(width 0.12446)
		(layer "B.Cu")
		(net "PHY_DPB_TO_SCC_29_DN")
	)
	(segment
		(start 129.89687 -3.73634)
		(end 129.89687 -14.959584)
		(width 0.12446)
		(layer "B.Cu")
		(net "PHY_DPB_TO_SCC_29_DN")
	)
	(segment
		(start 130.999992 -2.600198)
		(end 130.999992 -2.977642)
		(width 0.12446)
		(layer "B.Cu")
		(net "PHY_DPB_TO_SCC_29_DN")
	)
	(segment
		(start 130.8862 -44.037758)
		(end 130.82397 -44.099988)
		(width 0.12446)
		(layer "B.Cu")
		(net "PHY_DPB_TO_SCC_29_DN")
	)
	(arc
		(start 130.999992 -2.977642)
		(mid 130.990943 -3.023132)
		(end 130.965194 -3.061716)
		(width 0.12446)
		(layer "B.Cu")
		(net "PHY_DPB_TO_SCC_29_DN")
	)
	(arc
		(start 130.536442 -3.096768)
		(mid 130.084196 -3.284094)
		(end 129.89687 -3.73634)
		(width 0.12446)
		(layer "B.Cu")
		(net "PHY_DPB_TO_SCC_29_DN")
	)
	(arc
		(start 130.965194 -3.061716)
		(mid 130.926533 -3.087676)
		(end 130.880866 -3.096768)
		(width 0.12446)
		(layer "B.Cu")
		(net "PHY_DPB_TO_SCC_29_DN")
	)
	(segment
		(start 130.394456 -24.970486)
		(end 128.665224 -33.134808)
		(width 0.12446)
		(layer "B.Cu")
		(net "PHY_DPB_TO_SCC_28_DP")
	)
	(segment
		(start 130.311906 -24.582628)
		(end 130.394456 -24.970486)
		(width 0.12446)
		(layer "B.Cu")
		(net "PHY_DPB_TO_SCC_28_DP")
	)
	(segment
		(start 128.665224 -33.134808)
		(end 129.415032 -36.662106)
		(width 0.12446)
		(layer "B.Cu")
		(net "PHY_DPB_TO_SCC_28_DP")
	)
	(segment
		(start 129.200148 -5.200142)
		(end 129.200148 -4.822444)
		(width 0.12446)
		(layer "B.Cu")
		(net "PHY_DPB_TO_SCC_28_DP")
	)
	(segment
		(start 129.588006 -21.176488)
		(end 129.907284 -21.383752)
		(width 0.12446)
		(layer "B.Cu")
		(net "PHY_DPB_TO_SCC_28_DP")
	)
	(segment
		(start 128.503426 -16.073374)
		(end 129.588006 -21.176488)
		(width 0.12446)
		(layer "B.Cu")
		(net "PHY_DPB_TO_SCC_28_DP")
	)
	(segment
		(start 129.415032 -36.662106)
		(end 128.721612 -39.92372)
		(width 0.12446)
		(layer "B.Cu")
		(net "PHY_DPB_TO_SCC_28_DP")
	)
	(segment
		(start 130.252216 -23.006304)
		(end 130.044952 -23.325582)
		(width 0.12446)
		(layer "B.Cu")
		(net "PHY_DPB_TO_SCC_28_DP")
	)
	(segment
		(start 130.122422 -23.690834)
		(end 130.4417 -23.898098)
		(width 0.12446)
		(layer "B.Cu")
		(net "PHY_DPB_TO_SCC_28_DP")
	)
	(segment
		(start 130.044952 -23.325582)
		(end 130.122422 -23.690834)
		(width 0.12446)
		(layer "B.Cu")
		(net "PHY_DPB_TO_SCC_28_DP")
	)
	(segment
		(start 129.777744 -22.068282)
		(end 129.855214 -22.433534)
		(width 0.12446)
		(layer "B.Cu")
		(net "PHY_DPB_TO_SCC_28_DP")
	)
	(segment
		(start 129.907284 -21.383752)
		(end 129.985008 -21.749004)
		(width 0.12446)
		(layer "B.Cu")
		(net "PHY_DPB_TO_SCC_28_DP")
	)
	(segment
		(start 129.855214 -22.433534)
		(end 130.174492 -22.641052)
		(width 0.12446)
		(layer "B.Cu")
		(net "PHY_DPB_TO_SCC_28_DP")
	)
	(segment
		(start 129.985008 -21.749004)
		(end 129.777744 -22.068282)
		(width 0.12446)
		(layer "B.Cu")
		(net "PHY_DPB_TO_SCC_28_DP")
	)
	(segment
		(start 128.721612 -40.507412)
		(end 128.8034 -40.5892)
		(width 0.12446)
		(layer "B.Cu")
		(net "PHY_DPB_TO_SCC_28_DP")
	)
	(segment
		(start 130.519424 -24.26335)
		(end 130.311906 -24.582628)
		(width 0.12446)
		(layer "B.Cu")
		(net "PHY_DPB_TO_SCC_28_DP")
	)
	(segment
		(start 128.721612 -39.92372)
		(end 128.721612 -40.507412)
		(width 0.12446)
		(layer "B.Cu")
		(net "PHY_DPB_TO_SCC_28_DP")
	)
	(segment
		(start 130.4417 -23.898098)
		(end 130.519424 -24.26335)
		(width 0.12446)
		(layer "B.Cu")
		(net "PHY_DPB_TO_SCC_28_DP")
	)
	(segment
		(start 128.503426 -4.93649)
		(end 128.503426 -16.073374)
		(width 0.12446)
		(layer "B.Cu")
		(net "PHY_DPB_TO_SCC_28_DP")
	)
	(segment
		(start 130.174492 -22.641052)
		(end 130.252216 -23.006304)
		(width 0.12446)
		(layer "B.Cu")
		(net "PHY_DPB_TO_SCC_28_DP")
	)
	(segment
		(start 129.081022 -4.703318)
		(end 128.736598 -4.703318)
		(width 0.12446)
		(layer "B.Cu")
		(net "PHY_DPB_TO_SCC_28_DP")
	)
	(arc
		(start 129.200148 -4.822444)
		(mid 129.191099 -4.776954)
		(end 129.16535 -4.73837)
		(width 0.12446)
		(layer "B.Cu")
		(net "PHY_DPB_TO_SCC_28_DP")
	)
	(arc
		(start 129.16535 -4.73837)
		(mid 129.126689 -4.71241)
		(end 129.081022 -4.703318)
		(width 0.12446)
		(layer "B.Cu")
		(net "PHY_DPB_TO_SCC_28_DP")
	)
	(arc
		(start 128.736598 -4.703318)
		(mid 128.57172 -4.771612)
		(end 128.503426 -4.93649)
		(width 0.12446)
		(layer "B.Cu")
		(net "PHY_DPB_TO_SCC_28_DP")
	)
	(segment
		(start 129.200148 -3.800094)
		(end 129.200148 -4.177792)
		(width 0.12446)
		(layer "B.Cu")
		(net "PHY_DPB_TO_SCC_28_DN")
	)
	(segment
		(start 129.081022 -4.296918)
		(end 128.736598 -4.296918)
		(width 0.12446)
		(layer "B.Cu")
		(net "PHY_DPB_TO_SCC_28_DN")
	)
	(segment
		(start 129.978912 -24.97074)
		(end 128.24968 -33.135062)
		(width 0.12446)
		(layer "B.Cu")
		(net "PHY_DPB_TO_SCC_28_DN")
	)
	(segment
		(start 128.999488 -36.662106)
		(end 128.315212 -39.880794)
		(width 0.12446)
		(layer "B.Cu")
		(net "PHY_DPB_TO_SCC_28_DN")
	)
	(segment
		(start 128.315212 -39.880794)
		(end 128.315212 -40.493188)
		(width 0.12446)
		(layer "B.Cu")
		(net "PHY_DPB_TO_SCC_28_DN")
	)
	(segment
		(start 128.315212 -40.493188)
		(end 128.2192 -40.5892)
		(width 0.12446)
		(layer "B.Cu")
		(net "PHY_DPB_TO_SCC_28_DN")
	)
	(segment
		(start 128.24968 -33.135062)
		(end 128.999488 -36.662106)
		(width 0.12446)
		(layer "B.Cu")
		(net "PHY_DPB_TO_SCC_28_DN")
	)
	(segment
		(start 128.097026 -4.93649)
		(end 128.097026 -16.1163)
		(width 0.12446)
		(layer "B.Cu")
		(net "PHY_DPB_TO_SCC_28_DN")
	)
	(segment
		(start 128.097026 -16.1163)
		(end 129.978912 -24.97074)
		(width 0.12446)
		(layer "B.Cu")
		(net "PHY_DPB_TO_SCC_28_DN")
	)
	(arc
		(start 129.200148 -4.177792)
		(mid 129.191099 -4.223282)
		(end 129.16535 -4.261866)
		(width 0.12446)
		(layer "B.Cu")
		(net "PHY_DPB_TO_SCC_28_DN")
	)
	(arc
		(start 129.16535 -4.261866)
		(mid 129.126689 -4.287826)
		(end 129.081022 -4.296918)
		(width 0.12446)
		(layer "B.Cu")
		(net "PHY_DPB_TO_SCC_28_DN")
	)
	(arc
		(start 128.736598 -4.296918)
		(mid 128.284352 -4.484244)
		(end 128.097026 -4.93649)
		(width 0.12446)
		(layer "B.Cu")
		(net "PHY_DPB_TO_SCC_28_DN")
	)
	(segment
		(start 113.881154 -43.853354)
		(end 113.881154 -39.50589)
		(width 0.12446)
		(layer "B.Cu")
		(net "PHY_DPB_TO_SCC_27_DP")
	)
	(segment
		(start 113.881154 -39.50589)
		(end 115.554252 -31.633414)
		(width 0.12446)
		(layer "B.Cu")
		(net "PHY_DPB_TO_SCC_27_DP")
	)
	(segment
		(start 114.887502 -28.496514)
		(end 115.09502 -28.177236)
		(width 0.12446)
		(layer "B.Cu")
		(net "PHY_DPB_TO_SCC_27_DP")
	)
	(segment
		(start 113.9698 -43.942)
		(end 113.881154 -43.853354)
		(width 0.12446)
		(layer "B.Cu")
		(net "PHY_DPB_TO_SCC_27_DP")
	)
	(segment
		(start 115.017296 -27.811984)
		(end 114.698018 -27.604466)
		(width 0.12446)
		(layer "B.Cu")
		(net "PHY_DPB_TO_SCC_27_DP")
	)
	(segment
		(start 115.09502 -28.177236)
		(end 115.017296 -27.811984)
		(width 0.12446)
		(layer "B.Cu")
		(net "PHY_DPB_TO_SCC_27_DP")
	)
	(segment
		(start 115.629436 -30.691582)
		(end 115.551712 -30.32633)
		(width 0.12446)
		(layer "B.Cu")
		(net "PHY_DPB_TO_SCC_27_DP")
	)
	(segment
		(start 115.284504 -29.06903)
		(end 114.965226 -28.861766)
		(width 0.12446)
		(layer "B.Cu")
		(net "PHY_DPB_TO_SCC_27_DP")
	)
	(segment
		(start 115.421918 -31.01086)
		(end 115.629436 -30.691582)
		(width 0.12446)
		(layer "B.Cu")
		(net "PHY_DPB_TO_SCC_27_DP")
	)
	(segment
		(start 115.362228 -29.434282)
		(end 115.284504 -29.06903)
		(width 0.12446)
		(layer "B.Cu")
		(net "PHY_DPB_TO_SCC_27_DP")
	)
	(segment
		(start 113.000028 -3.622294)
		(end 113.000028 -3.999992)
		(width 0.12446)
		(layer "B.Cu")
		(net "PHY_DPB_TO_SCC_27_DP")
	)
	(segment
		(start 115.554252 -31.633414)
		(end 115.421918 -31.01086)
		(width 0.12446)
		(layer "B.Cu")
		(net "PHY_DPB_TO_SCC_27_DP")
	)
	(segment
		(start 115.551712 -30.32633)
		(end 115.232434 -30.118812)
		(width 0.12446)
		(layer "B.Cu")
		(net "PHY_DPB_TO_SCC_27_DP")
	)
	(segment
		(start 114.965226 -28.861766)
		(end 114.887502 -28.496514)
		(width 0.12446)
		(layer "B.Cu")
		(net "PHY_DPB_TO_SCC_27_DP")
	)
	(segment
		(start 112.536478 -3.503168)
		(end 112.880902 -3.503168)
		(width 0.12446)
		(layer "B.Cu")
		(net "PHY_DPB_TO_SCC_27_DP")
	)
	(segment
		(start 115.232434 -30.118812)
		(end 115.15471 -29.75356)
		(width 0.12446)
		(layer "B.Cu")
		(net "PHY_DPB_TO_SCC_27_DP")
	)
	(segment
		(start 112.303306 -16.337788)
		(end 112.303306 -3.73634)
		(width 0.12446)
		(layer "B.Cu")
		(net "PHY_DPB_TO_SCC_27_DP")
	)
	(segment
		(start 114.698018 -27.604466)
		(end 112.303306 -16.337788)
		(width 0.12446)
		(layer "B.Cu")
		(net "PHY_DPB_TO_SCC_27_DP")
	)
	(segment
		(start 115.15471 -29.75356)
		(end 115.362228 -29.434282)
		(width 0.12446)
		(layer "B.Cu")
		(net "PHY_DPB_TO_SCC_27_DP")
	)
	(arc
		(start 112.96523 -3.53822)
		(mid 112.991004 -3.576793)
		(end 113.000028 -3.622294)
		(width 0.12446)
		(layer "B.Cu")
		(net "PHY_DPB_TO_SCC_27_DP")
	)
	(arc
		(start 112.880902 -3.503168)
		(mid 112.926558 -3.512285)
		(end 112.96523 -3.53822)
		(width 0.12446)
		(layer "B.Cu")
		(net "PHY_DPB_TO_SCC_27_DP")
	)
	(arc
		(start 112.303306 -3.73634)
		(mid 112.3716 -3.571462)
		(end 112.536478 -3.503168)
		(width 0.12446)
		(layer "B.Cu")
		(net "PHY_DPB_TO_SCC_27_DP")
	)
	(segment
		(start 115.024408 -31.095442)
		(end 115.024408 -31.095696)
		(width 0.12446)
		(layer "B.Cu")
		(net "PHY_DPB_TO_SCC_27_DN")
	)
	(segment
		(start 111.896906 -16.380714)
		(end 111.896906 -3.73634)
		(width 0.12446)
		(layer "B.Cu")
		(net "PHY_DPB_TO_SCC_27_DN")
	)
	(segment
		(start 115.024408 -31.095696)
		(end 111.896906 -16.380714)
		(width 0.12446)
		(layer "B.Cu")
		(net "PHY_DPB_TO_SCC_27_DN")
	)
	(segment
		(start 113.474754 -39.462964)
		(end 115.138708 -31.633414)
		(width 0.12446)
		(layer "B.Cu")
		(net "PHY_DPB_TO_SCC_27_DN")
	)
	(segment
		(start 115.138708 -31.633414)
		(end 115.024408 -31.095442)
		(width 0.12446)
		(layer "B.Cu")
		(net "PHY_DPB_TO_SCC_27_DN")
	)
	(segment
		(start 112.536478 -3.096768)
		(end 112.880902 -3.096768)
		(width 0.12446)
		(layer "B.Cu")
		(net "PHY_DPB_TO_SCC_27_DN")
	)
	(segment
		(start 113.000028 -2.977642)
		(end 113.000028 -2.600198)
		(width 0.12446)
		(layer "B.Cu")
		(net "PHY_DPB_TO_SCC_27_DN")
	)
	(segment
		(start 113.474754 -43.878246)
		(end 113.474754 -39.462964)
		(width 0.12446)
		(layer "B.Cu")
		(net "PHY_DPB_TO_SCC_27_DN")
	)
	(segment
		(start 113.411 -43.942)
		(end 113.474754 -43.878246)
		(width 0.12446)
		(layer "B.Cu")
		(net "PHY_DPB_TO_SCC_27_DN")
	)
	(arc
		(start 111.896906 -3.73634)
		(mid 112.084232 -3.284094)
		(end 112.536478 -3.096768)
		(width 0.12446)
		(layer "B.Cu")
		(net "PHY_DPB_TO_SCC_27_DN")
	)
	(arc
		(start 112.880902 -3.096768)
		(mid 112.926558 -3.087651)
		(end 112.96523 -3.061716)
		(width 0.12446)
		(layer "B.Cu")
		(net "PHY_DPB_TO_SCC_27_DN")
	)
	(arc
		(start 112.96523 -3.061716)
		(mid 112.991004 -3.023143)
		(end 113.000028 -2.977642)
		(width 0.12446)
		(layer "B.Cu")
		(net "PHY_DPB_TO_SCC_27_DN")
	)
	(segment
		(start 114.180112 -31.396178)
		(end 113.972594 -31.715456)
		(width 0.12446)
		(layer "B.Cu")
		(net "PHY_DPB_TO_SCC_26_DP")
	)
	(segment
		(start 113.78311 -30.823662)
		(end 114.102388 -31.030926)
		(width 0.12446)
		(layer "B.Cu")
		(net "PHY_DPB_TO_SCC_26_DP")
	)
	(segment
		(start 114.11839 -32.401256)
		(end 112.366552 -40.644064)
		(width 0.12446)
		(layer "B.Cu")
		(net "PHY_DPB_TO_SCC_26_DP")
	)
	(segment
		(start 113.248694 -28.30957)
		(end 113.567972 -28.516834)
		(width 0.12446)
		(layer "B.Cu")
		(net "PHY_DPB_TO_SCC_26_DP")
	)
	(segment
		(start 113.567972 -28.516834)
		(end 113.645696 -28.882086)
		(width 0.12446)
		(layer "B.Cu")
		(net "PHY_DPB_TO_SCC_26_DP")
	)
	(segment
		(start 113.972594 -31.715456)
		(end 114.11839 -32.401256)
		(width 0.12446)
		(layer "B.Cu")
		(net "PHY_DPB_TO_SCC_26_DP")
	)
	(segment
		(start 111.200184 -5.200142)
		(end 111.200184 -4.822444)
		(width 0.12446)
		(layer "B.Cu")
		(net "PHY_DPB_TO_SCC_26_DP")
	)
	(segment
		(start 113.515902 -29.566616)
		(end 113.83518 -29.77388)
		(width 0.12446)
		(layer "B.Cu")
		(net "PHY_DPB_TO_SCC_26_DP")
	)
	(segment
		(start 113.83518 -29.77388)
		(end 113.912904 -30.139132)
		(width 0.12446)
		(layer "B.Cu")
		(net "PHY_DPB_TO_SCC_26_DP")
	)
	(segment
		(start 112.366552 -40.644064)
		(end 112.366552 -43.862752)
		(width 0.12446)
		(layer "B.Cu")
		(net "PHY_DPB_TO_SCC_26_DP")
	)
	(segment
		(start 113.438178 -29.201364)
		(end 113.515902 -29.566616)
		(width 0.12446)
		(layer "B.Cu")
		(net "PHY_DPB_TO_SCC_26_DP")
	)
	(segment
		(start 110.503462 -4.93649)
		(end 110.503462 -15.393924)
		(width 0.12446)
		(layer "B.Cu")
		(net "PHY_DPB_TO_SCC_26_DP")
	)
	(segment
		(start 111.081058 -4.703318)
		(end 110.736634 -4.703318)
		(width 0.12446)
		(layer "B.Cu")
		(net "PHY_DPB_TO_SCC_26_DP")
	)
	(segment
		(start 114.102388 -31.030926)
		(end 114.180112 -31.396178)
		(width 0.12446)
		(layer "B.Cu")
		(net "PHY_DPB_TO_SCC_26_DP")
	)
	(segment
		(start 113.912904 -30.139132)
		(end 113.705386 -30.45841)
		(width 0.12446)
		(layer "B.Cu")
		(net "PHY_DPB_TO_SCC_26_DP")
	)
	(segment
		(start 113.705386 -30.45841)
		(end 113.78311 -30.823662)
		(width 0.12446)
		(layer "B.Cu")
		(net "PHY_DPB_TO_SCC_26_DP")
	)
	(segment
		(start 112.366552 -43.862752)
		(end 112.4458 -43.942)
		(width 0.12446)
		(layer "B.Cu")
		(net "PHY_DPB_TO_SCC_26_DP")
	)
	(segment
		(start 110.503462 -15.393924)
		(end 113.248694 -28.30957)
		(width 0.12446)
		(layer "B.Cu")
		(net "PHY_DPB_TO_SCC_26_DP")
	)
	(segment
		(start 113.645696 -28.882086)
		(end 113.438178 -29.201364)
		(width 0.12446)
		(layer "B.Cu")
		(net "PHY_DPB_TO_SCC_26_DP")
	)
	(arc
		(start 110.736634 -4.703318)
		(mid 110.571756 -4.771612)
		(end 110.503462 -4.93649)
		(width 0.12446)
		(layer "B.Cu")
		(net "PHY_DPB_TO_SCC_26_DP")
	)
	(arc
		(start 111.200184 -4.822444)
		(mid 111.191135 -4.776954)
		(end 111.165386 -4.73837)
		(width 0.12446)
		(layer "B.Cu")
		(net "PHY_DPB_TO_SCC_26_DP")
	)
	(arc
		(start 111.165386 -4.73837)
		(mid 111.126725 -4.71241)
		(end 111.081058 -4.703318)
		(width 0.12446)
		(layer "B.Cu")
		(net "PHY_DPB_TO_SCC_26_DP")
	)
	(segment
		(start 111.960152 -40.601138)
		(end 113.702846 -32.40151)
		(width 0.12446)
		(layer "B.Cu")
		(net "PHY_DPB_TO_SCC_26_DN")
	)
	(segment
		(start 110.097062 -15.43685)
		(end 110.097062 -4.93649)
		(width 0.12446)
		(layer "B.Cu")
		(net "PHY_DPB_TO_SCC_26_DN")
	)
	(segment
		(start 111.887 -43.942)
		(end 111.960152 -43.868848)
		(width 0.12446)
		(layer "B.Cu")
		(net "PHY_DPB_TO_SCC_26_DN")
	)
	(segment
		(start 111.200184 -4.177792)
		(end 111.200184 -3.800094)
		(width 0.12446)
		(layer "B.Cu")
		(net "PHY_DPB_TO_SCC_26_DN")
	)
	(segment
		(start 113.702846 -32.40151)
		(end 110.097062 -15.43685)
		(width 0.12446)
		(layer "B.Cu")
		(net "PHY_DPB_TO_SCC_26_DN")
	)
	(segment
		(start 111.960152 -43.868848)
		(end 111.960152 -40.601138)
		(width 0.12446)
		(layer "B.Cu")
		(net "PHY_DPB_TO_SCC_26_DN")
	)
	(segment
		(start 110.736634 -4.296918)
		(end 111.081058 -4.296918)
		(width 0.12446)
		(layer "B.Cu")
		(net "PHY_DPB_TO_SCC_26_DN")
	)
	(arc
		(start 111.165386 -4.261866)
		(mid 111.19116 -4.223293)
		(end 111.200184 -4.177792)
		(width 0.12446)
		(layer "B.Cu")
		(net "PHY_DPB_TO_SCC_26_DN")
	)
	(arc
		(start 111.081058 -4.296918)
		(mid 111.126714 -4.287801)
		(end 111.165386 -4.261866)
		(width 0.12446)
		(layer "B.Cu")
		(net "PHY_DPB_TO_SCC_26_DN")
	)
	(arc
		(start 110.097062 -4.93649)
		(mid 110.284388 -4.484244)
		(end 110.736634 -4.296918)
		(width 0.12446)
		(layer "B.Cu")
		(net "PHY_DPB_TO_SCC_26_DN")
	)
	(segment
		(start 112.693704 -31.58871)
		(end 112.616234 -31.223458)
		(width 0.12446)
		(layer "B.Cu")
		(net "PHY_DPB_TO_SCC_25_DP")
	)
	(segment
		(start 112.219232 -30.650942)
		(end 112.42675 -30.33141)
		(width 0.12446)
		(layer "B.Cu")
		(net "PHY_DPB_TO_SCC_25_DP")
	)
	(segment
		(start 110.833408 -43.853608)
		(end 110.833408 -41.696894)
		(width 0.12446)
		(layer "B.Cu")
		(net "PHY_DPB_TO_SCC_25_DP")
	)
	(segment
		(start 111.952024 -29.393642)
		(end 112.159542 -29.074364)
		(width 0.12446)
		(layer "B.Cu")
		(net "PHY_DPB_TO_SCC_25_DP")
	)
	(segment
		(start 112.159542 -29.074364)
		(end 112.081818 -28.709112)
		(width 0.12446)
		(layer "B.Cu")
		(net "PHY_DPB_TO_SCC_25_DP")
	)
	(segment
		(start 112.616234 -31.223458)
		(end 112.296956 -31.01594)
		(width 0.12446)
		(layer "B.Cu")
		(net "PHY_DPB_TO_SCC_25_DP")
	)
	(segment
		(start 109.400086 -3.622294)
		(end 109.400086 -3.999992)
		(width 0.12446)
		(layer "B.Cu")
		(net "PHY_DPB_TO_SCC_25_DP")
	)
	(segment
		(start 112.700308 -32.91459)
		(end 112.486948 -31.910528)
		(width 0.12446)
		(layer "B.Cu")
		(net "PHY_DPB_TO_SCC_25_DP")
	)
	(segment
		(start 112.48644 -31.907988)
		(end 112.693704 -31.58871)
		(width 0.12446)
		(layer "B.Cu")
		(net "PHY_DPB_TO_SCC_25_DP")
	)
	(segment
		(start 108.703364 -14.106398)
		(end 108.703364 -3.73634)
		(width 0.12446)
		(layer "B.Cu")
		(net "PHY_DPB_TO_SCC_25_DP")
	)
	(segment
		(start 112.486948 -31.910528)
		(end 112.48644 -31.907988)
		(width 0.12446)
		(layer "B.Cu")
		(net "PHY_DPB_TO_SCC_25_DP")
	)
	(segment
		(start 110.833408 -41.696894)
		(end 112.700308 -32.91459)
		(width 0.12446)
		(layer "B.Cu")
		(net "PHY_DPB_TO_SCC_25_DP")
	)
	(segment
		(start 112.081818 -28.709112)
		(end 111.76254 -28.501848)
		(width 0.12446)
		(layer "B.Cu")
		(net "PHY_DPB_TO_SCC_25_DP")
	)
	(segment
		(start 112.349026 -29.966412)
		(end 112.029748 -29.758894)
		(width 0.12446)
		(layer "B.Cu")
		(net "PHY_DPB_TO_SCC_25_DP")
	)
	(segment
		(start 112.296956 -31.01594)
		(end 112.219232 -30.650942)
		(width 0.12446)
		(layer "B.Cu")
		(net "PHY_DPB_TO_SCC_25_DP")
	)
	(segment
		(start 112.42675 -30.33141)
		(end 112.349026 -29.966412)
		(width 0.12446)
		(layer "B.Cu")
		(net "PHY_DPB_TO_SCC_25_DP")
	)
	(segment
		(start 110.9218 -43.942)
		(end 110.833408 -43.853608)
		(width 0.12446)
		(layer "B.Cu")
		(net "PHY_DPB_TO_SCC_25_DP")
	)
	(segment
		(start 111.76254 -28.501848)
		(end 108.703364 -14.106398)
		(width 0.12446)
		(layer "B.Cu")
		(net "PHY_DPB_TO_SCC_25_DP")
	)
	(segment
		(start 108.936536 -3.503168)
		(end 109.28096 -3.503168)
		(width 0.12446)
		(layer "B.Cu")
		(net "PHY_DPB_TO_SCC_25_DP")
	)
	(segment
		(start 112.029748 -29.758894)
		(end 111.952024 -29.393642)
		(width 0.12446)
		(layer "B.Cu")
		(net "PHY_DPB_TO_SCC_25_DP")
	)
	(arc
		(start 109.28096 -3.503168)
		(mid 109.326616 -3.512285)
		(end 109.365288 -3.53822)
		(width 0.12446)
		(layer "B.Cu")
		(net "PHY_DPB_TO_SCC_25_DP")
	)
	(arc
		(start 109.365288 -3.53822)
		(mid 109.391062 -3.576793)
		(end 109.400086 -3.622294)
		(width 0.12446)
		(layer "B.Cu")
		(net "PHY_DPB_TO_SCC_25_DP")
	)
	(arc
		(start 108.703364 -3.73634)
		(mid 108.771658 -3.571462)
		(end 108.936536 -3.503168)
		(width 0.12446)
		(layer "B.Cu")
		(net "PHY_DPB_TO_SCC_25_DP")
	)
	(segment
		(start 110.427008 -43.877992)
		(end 110.427008 -41.653968)
		(width 0.12446)
		(layer "B.Cu")
		(net "PHY_DPB_TO_SCC_25_DN")
	)
	(segment
		(start 108.296964 -14.149324)
		(end 108.296964 -3.73634)
		(width 0.12446)
		(layer "B.Cu")
		(net "PHY_DPB_TO_SCC_25_DN")
	)
	(segment
		(start 112.284764 -32.91459)
		(end 108.296964 -14.149324)
		(width 0.12446)
		(layer "B.Cu")
		(net "PHY_DPB_TO_SCC_25_DN")
	)
	(segment
		(start 110.427008 -41.653968)
		(end 112.284764 -32.91459)
		(width 0.12446)
		(layer "B.Cu")
		(net "PHY_DPB_TO_SCC_25_DN")
	)
	(segment
		(start 108.936536 -3.096768)
		(end 109.28096 -3.096768)
		(width 0.12446)
		(layer "B.Cu")
		(net "PHY_DPB_TO_SCC_25_DN")
	)
	(segment
		(start 109.400086 -2.977642)
		(end 109.400086 -2.600198)
		(width 0.12446)
		(layer "B.Cu")
		(net "PHY_DPB_TO_SCC_25_DN")
	)
	(segment
		(start 110.363 -43.942)
		(end 110.427008 -43.877992)
		(width 0.12446)
		(layer "B.Cu")
		(net "PHY_DPB_TO_SCC_25_DN")
	)
	(arc
		(start 108.296964 -3.73634)
		(mid 108.48429 -3.284094)
		(end 108.936536 -3.096768)
		(width 0.12446)
		(layer "B.Cu")
		(net "PHY_DPB_TO_SCC_25_DN")
	)
	(arc
		(start 109.28096 -3.096768)
		(mid 109.326616 -3.087651)
		(end 109.365288 -3.061716)
		(width 0.12446)
		(layer "B.Cu")
		(net "PHY_DPB_TO_SCC_25_DN")
	)
	(arc
		(start 109.365288 -3.061716)
		(mid 109.391062 -3.023143)
		(end 109.400086 -2.977642)
		(width 0.12446)
		(layer "B.Cu")
		(net "PHY_DPB_TO_SCC_25_DN")
	)
	(segment
		(start 111.030004 -31.625794)
		(end 110.952534 -31.260542)
		(width 0.12446)
		(layer "B.Cu")
		(net "PHY_DPB_TO_SCC_24_DP")
	)
	(segment
		(start 110.495842 -29.111194)
		(end 110.418118 -28.746196)
		(width 0.12446)
		(layer "B.Cu")
		(net "PHY_DPB_TO_SCC_24_DP")
	)
	(segment
		(start 110.366048 -29.795978)
		(end 110.288324 -29.430726)
		(width 0.12446)
		(layer "B.Cu")
		(net "PHY_DPB_TO_SCC_24_DP")
	)
	(segment
		(start 109.310678 -41.953434)
		(end 109.310932 -41.953434)
		(width 0.12446)
		(layer "B.Cu")
		(net "PHY_DPB_TO_SCC_24_DP")
	)
	(segment
		(start 110.09884 -28.538678)
		(end 106.903266 -13.49883)
		(width 0.12446)
		(layer "B.Cu")
		(net "PHY_DPB_TO_SCC_24_DP")
	)
	(segment
		(start 109.310932 -41.953434)
		(end 111.130334 -33.39338)
		(width 0.12446)
		(layer "B.Cu")
		(net "PHY_DPB_TO_SCC_24_DP")
	)
	(segment
		(start 107.599988 -4.822444)
		(end 107.599988 -5.200142)
		(width 0.12446)
		(layer "B.Cu")
		(net "PHY_DPB_TO_SCC_24_DP")
	)
	(segment
		(start 110.633256 -31.053278)
		(end 110.555532 -30.688026)
		(width 0.12446)
		(layer "B.Cu")
		(net "PHY_DPB_TO_SCC_24_DP")
	)
	(segment
		(start 110.952534 -31.260542)
		(end 110.633256 -31.053278)
		(width 0.12446)
		(layer "B.Cu")
		(net "PHY_DPB_TO_SCC_24_DP")
	)
	(segment
		(start 110.288324 -29.430726)
		(end 110.495842 -29.111194)
		(width 0.12446)
		(layer "B.Cu")
		(net "PHY_DPB_TO_SCC_24_DP")
	)
	(segment
		(start 110.685326 -30.003242)
		(end 110.366048 -29.795978)
		(width 0.12446)
		(layer "B.Cu")
		(net "PHY_DPB_TO_SCC_24_DP")
	)
	(segment
		(start 109.310678 -43.854878)
		(end 109.310678 -41.953434)
		(width 0.12446)
		(layer "B.Cu")
		(net "PHY_DPB_TO_SCC_24_DP")
	)
	(segment
		(start 111.130334 -33.39338)
		(end 110.82274 -31.945326)
		(width 0.12446)
		(layer "B.Cu")
		(net "PHY_DPB_TO_SCC_24_DP")
	)
	(segment
		(start 110.555532 -30.688026)
		(end 110.762796 -30.368494)
		(width 0.12446)
		(layer "B.Cu")
		(net "PHY_DPB_TO_SCC_24_DP")
	)
	(segment
		(start 107.136438 -4.703318)
		(end 107.480862 -4.703318)
		(width 0.12446)
		(layer "B.Cu")
		(net "PHY_DPB_TO_SCC_24_DP")
	)
	(segment
		(start 110.418118 -28.746196)
		(end 110.09884 -28.538678)
		(width 0.12446)
		(layer "B.Cu")
		(net "PHY_DPB_TO_SCC_24_DP")
	)
	(segment
		(start 110.82274 -31.945326)
		(end 111.030004 -31.625794)
		(width 0.12446)
		(layer "B.Cu")
		(net "PHY_DPB_TO_SCC_24_DP")
	)
	(segment
		(start 106.903266 -13.49883)
		(end 106.903266 -4.93649)
		(width 0.12446)
		(layer "B.Cu")
		(net "PHY_DPB_TO_SCC_24_DP")
	)
	(segment
		(start 110.762796 -30.368494)
		(end 110.685326 -30.003242)
		(width 0.12446)
		(layer "B.Cu")
		(net "PHY_DPB_TO_SCC_24_DP")
	)
	(segment
		(start 109.3978 -43.942)
		(end 109.310678 -43.854878)
		(width 0.12446)
		(layer "B.Cu")
		(net "PHY_DPB_TO_SCC_24_DP")
	)
	(arc
		(start 107.480862 -4.703318)
		(mid 107.526518 -4.712435)
		(end 107.56519 -4.73837)
		(width 0.12446)
		(layer "B.Cu")
		(net "PHY_DPB_TO_SCC_24_DP")
	)
	(arc
		(start 107.56519 -4.73837)
		(mid 107.590964 -4.776943)
		(end 107.599988 -4.822444)
		(width 0.12446)
		(layer "B.Cu")
		(net "PHY_DPB_TO_SCC_24_DP")
	)
	(arc
		(start 106.903266 -4.93649)
		(mid 106.97156 -4.771612)
		(end 107.136438 -4.703318)
		(width 0.12446)
		(layer "B.Cu")
		(net "PHY_DPB_TO_SCC_24_DP")
	)
	(segment
		(start 106.496866 -13.541756)
		(end 106.496866 -4.93649)
		(width 0.12446)
		(layer "B.Cu")
		(net "PHY_DPB_TO_SCC_24_DN")
	)
	(segment
		(start 107.599988 -4.177792)
		(end 107.599988 -3.800094)
		(width 0.12446)
		(layer "B.Cu")
		(net "PHY_DPB_TO_SCC_24_DN")
	)
	(segment
		(start 108.904278 -41.910762)
		(end 110.71479 -33.39338)
		(width 0.12446)
		(layer "B.Cu")
		(net "PHY_DPB_TO_SCC_24_DN")
	)
	(segment
		(start 108.839 -43.942)
		(end 108.904278 -43.876722)
		(width 0.12446)
		(layer "B.Cu")
		(net "PHY_DPB_TO_SCC_24_DN")
	)
	(segment
		(start 108.904278 -43.876722)
		(end 108.904278 -41.910762)
		(width 0.12446)
		(layer "B.Cu")
		(net "PHY_DPB_TO_SCC_24_DN")
	)
	(segment
		(start 107.136438 -4.296918)
		(end 107.480862 -4.296918)
		(width 0.12446)
		(layer "B.Cu")
		(net "PHY_DPB_TO_SCC_24_DN")
	)
	(segment
		(start 110.71479 -33.39338)
		(end 106.496866 -13.541756)
		(width 0.12446)
		(layer "B.Cu")
		(net "PHY_DPB_TO_SCC_24_DN")
	)
	(arc
		(start 107.480862 -4.296918)
		(mid 107.526518 -4.287801)
		(end 107.56519 -4.261866)
		(width 0.12446)
		(layer "B.Cu")
		(net "PHY_DPB_TO_SCC_24_DN")
	)
	(arc
		(start 106.496866 -4.93649)
		(mid 106.684192 -4.484244)
		(end 107.136438 -4.296918)
		(width 0.12446)
		(layer "B.Cu")
		(net "PHY_DPB_TO_SCC_24_DN")
	)
	(arc
		(start 107.56519 -4.261866)
		(mid 107.590964 -4.223293)
		(end 107.599988 -4.177792)
		(width 0.12446)
		(layer "B.Cu")
		(net "PHY_DPB_TO_SCC_24_DN")
	)
	(segment
		(start 109.13491 -31.218378)
		(end 109.212634 -31.58363)
		(width 0.12446)
		(layer "B.Cu")
		(net "PHY_DPB_TO_SCC_23_DP")
	)
	(segment
		(start 105.103422 -3.73634)
		(end 105.103422 -12.25931)
		(width 0.12446)
		(layer "B.Cu")
		(net "PHY_DPB_TO_SCC_23_DP")
	)
	(segment
		(start 108.997242 -29.276548)
		(end 109.074966 -29.6418)
		(width 0.12446)
		(layer "B.Cu")
		(net "PHY_DPB_TO_SCC_23_DP")
	)
	(segment
		(start 108.677964 -29.069284)
		(end 108.997242 -29.276548)
		(width 0.12446)
		(layer "B.Cu")
		(net "PHY_DPB_TO_SCC_23_DP")
	)
	(segment
		(start 109.609636 -32.156146)
		(end 109.402118 -32.475424)
		(width 0.12446)
		(layer "B.Cu")
		(net "PHY_DPB_TO_SCC_23_DP")
	)
	(segment
		(start 109.402118 -32.475424)
		(end 109.712506 -33.934908)
		(width 0.12446)
		(layer "B.Cu")
		(net "PHY_DPB_TO_SCC_23_DP")
	)
	(segment
		(start 105.681018 -3.503168)
		(end 105.336594 -3.503168)
		(width 0.12446)
		(layer "B.Cu")
		(net "PHY_DPB_TO_SCC_23_DP")
	)
	(segment
		(start 107.809284 -42.891456)
		(end 107.809284 -43.877484)
		(width 0.12446)
		(layer "B.Cu")
		(net "PHY_DPB_TO_SCC_23_DP")
	)
	(segment
		(start 105.103422 -12.25931)
		(end 108.677964 -29.069284)
		(width 0.12446)
		(layer "B.Cu")
		(net "PHY_DPB_TO_SCC_23_DP")
	)
	(segment
		(start 109.531912 -31.790894)
		(end 109.609636 -32.156146)
		(width 0.12446)
		(layer "B.Cu")
		(net "PHY_DPB_TO_SCC_23_DP")
	)
	(segment
		(start 107.809284 -43.877484)
		(end 107.8738 -43.942)
		(width 0.12446)
		(layer "B.Cu")
		(net "PHY_DPB_TO_SCC_23_DP")
	)
	(segment
		(start 108.867448 -29.961078)
		(end 108.945172 -30.32633)
		(width 0.12446)
		(layer "B.Cu")
		(net "PHY_DPB_TO_SCC_23_DP")
	)
	(segment
		(start 109.26445 -30.533594)
		(end 109.342174 -30.898846)
		(width 0.12446)
		(layer "B.Cu")
		(net "PHY_DPB_TO_SCC_23_DP")
	)
	(segment
		(start 109.074966 -29.6418)
		(end 108.867448 -29.961078)
		(width 0.12446)
		(layer "B.Cu")
		(net "PHY_DPB_TO_SCC_23_DP")
	)
	(segment
		(start 108.945172 -30.32633)
		(end 109.26445 -30.533594)
		(width 0.12446)
		(layer "B.Cu")
		(net "PHY_DPB_TO_SCC_23_DP")
	)
	(segment
		(start 109.712506 -33.934908)
		(end 107.809284 -42.891456)
		(width 0.12446)
		(layer "B.Cu")
		(net "PHY_DPB_TO_SCC_23_DP")
	)
	(segment
		(start 109.342174 -30.898846)
		(end 109.13491 -31.218378)
		(width 0.12446)
		(layer "B.Cu")
		(net "PHY_DPB_TO_SCC_23_DP")
	)
	(segment
		(start 109.212634 -31.58363)
		(end 109.531912 -31.790894)
		(width 0.12446)
		(layer "B.Cu")
		(net "PHY_DPB_TO_SCC_23_DP")
	)
	(segment
		(start 105.800144 -3.999992)
		(end 105.800144 -3.622294)
		(width 0.12446)
		(layer "B.Cu")
		(net "PHY_DPB_TO_SCC_23_DP")
	)
	(arc
		(start 105.336594 -3.503168)
		(mid 105.171716 -3.571462)
		(end 105.103422 -3.73634)
		(width 0.12446)
		(layer "B.Cu")
		(net "PHY_DPB_TO_SCC_23_DP")
	)
	(arc
		(start 105.800144 -3.622294)
		(mid 105.791095 -3.576804)
		(end 105.765346 -3.53822)
		(width 0.12446)
		(layer "B.Cu")
		(net "PHY_DPB_TO_SCC_23_DP")
	)
	(arc
		(start 105.765346 -3.53822)
		(mid 105.726685 -3.51226)
		(end 105.681018 -3.503168)
		(width 0.12446)
		(layer "B.Cu")
		(net "PHY_DPB_TO_SCC_23_DP")
	)
	(segment
		(start 105.336594 -3.096768)
		(end 105.681018 -3.096768)
		(width 0.12446)
		(layer "B.Cu")
		(net "PHY_DPB_TO_SCC_23_DN")
	)
	(segment
		(start 104.697022 -12.302236)
		(end 104.697022 -3.73634)
		(width 0.12446)
		(layer "B.Cu")
		(net "PHY_DPB_TO_SCC_23_DN")
	)
	(segment
		(start 109.296962 -33.935162)
		(end 104.697022 -12.302236)
		(width 0.12446)
		(layer "B.Cu")
		(net "PHY_DPB_TO_SCC_23_DN")
	)
	(segment
		(start 105.800144 -2.977642)
		(end 105.800144 -2.600198)
		(width 0.12446)
		(layer "B.Cu")
		(net "PHY_DPB_TO_SCC_23_DN")
	)
	(segment
		(start 107.315 -43.942)
		(end 107.402884 -43.854116)
		(width 0.12446)
		(layer "B.Cu")
		(net "PHY_DPB_TO_SCC_23_DN")
	)
	(segment
		(start 107.402884 -43.854116)
		(end 107.402884 -42.84853)
		(width 0.12446)
		(layer "B.Cu")
		(net "PHY_DPB_TO_SCC_23_DN")
	)
	(segment
		(start 107.402884 -42.84853)
		(end 109.296962 -33.935162)
		(width 0.12446)
		(layer "B.Cu")
		(net "PHY_DPB_TO_SCC_23_DN")
	)
	(arc
		(start 104.697022 -3.73634)
		(mid 104.884348 -3.284094)
		(end 105.336594 -3.096768)
		(width 0.12446)
		(layer "B.Cu")
		(net "PHY_DPB_TO_SCC_23_DN")
	)
	(arc
		(start 105.681018 -3.096768)
		(mid 105.726674 -3.087651)
		(end 105.765346 -3.061716)
		(width 0.12446)
		(layer "B.Cu")
		(net "PHY_DPB_TO_SCC_23_DN")
	)
	(arc
		(start 105.765346 -3.061716)
		(mid 105.79112 -3.023143)
		(end 105.800144 -2.977642)
		(width 0.12446)
		(layer "B.Cu")
		(net "PHY_DPB_TO_SCC_23_DN")
	)
	(segment
		(start 103.536496 -4.703318)
		(end 103.88092 -4.703318)
		(width 0.12446)
		(layer "B.Cu")
		(net "PHY_DPB_TO_SCC_22_DP")
	)
	(segment
		(start 106.3498 -43.942)
		(end 106.3498 -43.829478)
		(width 0.12446)
		(layer "B.Cu")
		(net "PHY_DPB_TO_SCC_22_DP")
	)
	(segment
		(start 108.01096 -33.193482)
		(end 107.933236 -32.82823)
		(width 0.12446)
		(layer "B.Cu")
		(net "PHY_DPB_TO_SCC_22_DP")
	)
	(segment
		(start 107.666028 -31.571184)
		(end 107.873292 -31.251652)
		(width 0.12446)
		(layer "B.Cu")
		(net "PHY_DPB_TO_SCC_22_DP")
	)
	(segment
		(start 108.407708 -33.765998)
		(end 108.330238 -33.400746)
		(width 0.12446)
		(layer "B.Cu")
		(net "PHY_DPB_TO_SCC_22_DP")
	)
	(segment
		(start 108.200444 -34.085276)
		(end 108.407708 -33.765998)
		(width 0.12446)
		(layer "B.Cu")
		(net "PHY_DPB_TO_SCC_22_DP")
	)
	(segment
		(start 106.462322 -43.36415)
		(end 108.317284 -34.63544)
		(width 0.12446)
		(layer "B.Cu")
		(net "PHY_DPB_TO_SCC_22_DP")
	)
	(segment
		(start 104.000046 -4.822444)
		(end 104.000046 -5.200142)
		(width 0.12446)
		(layer "B.Cu")
		(net "PHY_DPB_TO_SCC_22_DP")
	)
	(segment
		(start 103.303324 -13.001498)
		(end 103.303324 -4.93649)
		(width 0.12446)
		(layer "B.Cu")
		(net "PHY_DPB_TO_SCC_22_DP")
	)
	(segment
		(start 108.1405 -32.508952)
		(end 108.06303 -32.1437)
		(width 0.12446)
		(layer "B.Cu")
		(net "PHY_DPB_TO_SCC_22_DP")
	)
	(segment
		(start 106.2736 -43.552872)
		(end 106.462322 -43.36415)
		(width 0.12446)
		(layer "B.Cu")
		(net "PHY_DPB_TO_SCC_22_DP")
	)
	(segment
		(start 108.06303 -32.1437)
		(end 107.743752 -31.936436)
		(width 0.12446)
		(layer "B.Cu")
		(net "PHY_DPB_TO_SCC_22_DP")
	)
	(segment
		(start 103.493062 -13.919708)
		(end 103.303324 -13.001498)
		(width 0.12446)
		(layer "B.Cu")
		(net "PHY_DPB_TO_SCC_22_DP")
	)
	(segment
		(start 107.933236 -32.82823)
		(end 108.1405 -32.508952)
		(width 0.12446)
		(layer "B.Cu")
		(net "PHY_DPB_TO_SCC_22_DP")
	)
	(segment
		(start 104.118664 -14.882368)
		(end 103.493062 -13.919708)
		(width 0.12446)
		(layer "B.Cu")
		(net "PHY_DPB_TO_SCC_22_DP")
	)
	(segment
		(start 107.743752 -31.936436)
		(end 107.666028 -31.571184)
		(width 0.12446)
		(layer "B.Cu")
		(net "PHY_DPB_TO_SCC_22_DP")
	)
	(segment
		(start 106.2736 -43.753278)
		(end 106.2736 -43.552872)
		(width 0.12446)
		(layer "B.Cu")
		(net "PHY_DPB_TO_SCC_22_DP")
	)
	(segment
		(start 108.317284 -34.63544)
		(end 108.200444 -34.085276)
		(width 0.12446)
		(layer "B.Cu")
		(net "PHY_DPB_TO_SCC_22_DP")
	)
	(segment
		(start 107.795822 -30.8864)
		(end 107.476544 -30.679136)
		(width 0.12446)
		(layer "B.Cu")
		(net "PHY_DPB_TO_SCC_22_DP")
	)
	(segment
		(start 107.873292 -31.251652)
		(end 107.795822 -30.8864)
		(width 0.12446)
		(layer "B.Cu")
		(net "PHY_DPB_TO_SCC_22_DP")
	)
	(segment
		(start 106.3498 -43.829478)
		(end 106.2736 -43.753278)
		(width 0.12446)
		(layer "B.Cu")
		(net "PHY_DPB_TO_SCC_22_DP")
	)
	(segment
		(start 108.330238 -33.400746)
		(end 108.01096 -33.193482)
		(width 0.12446)
		(layer "B.Cu")
		(net "PHY_DPB_TO_SCC_22_DP")
	)
	(segment
		(start 107.476544 -30.679136)
		(end 104.118664 -14.882368)
		(width 0.12446)
		(layer "B.Cu")
		(net "PHY_DPB_TO_SCC_22_DP")
	)
	(arc
		(start 103.88092 -4.703318)
		(mid 103.926576 -4.712435)
		(end 103.965248 -4.73837)
		(width 0.12446)
		(layer "B.Cu")
		(net "PHY_DPB_TO_SCC_22_DP")
	)
	(arc
		(start 103.965248 -4.73837)
		(mid 103.991022 -4.776943)
		(end 104.000046 -4.822444)
		(width 0.12446)
		(layer "B.Cu")
		(net "PHY_DPB_TO_SCC_22_DP")
	)
	(arc
		(start 103.303324 -4.93649)
		(mid 103.371618 -4.771612)
		(end 103.536496 -4.703318)
		(width 0.12446)
		(layer "B.Cu")
		(net "PHY_DPB_TO_SCC_22_DP")
	)
	(segment
		(start 104.000046 -4.177792)
		(end 104.000046 -3.800094)
		(width 0.12446)
		(layer "B.Cu")
		(net "PHY_DPB_TO_SCC_22_DN")
	)
	(segment
		(start 105.407714 -22.902164)
		(end 103.736648 -15.04061)
		(width 0.12446)
		(layer "B.Cu")
		(net "PHY_DPB_TO_SCC_22_DN")
	)
	(segment
		(start 103.000048 -13.542772)
		(end 102.896924 -13.043154)
		(width 0.12446)
		(layer "B.Cu")
		(net "PHY_DPB_TO_SCC_22_DN")
	)
	(segment
		(start 107.802934 -34.169858)
		(end 107.80268 -34.16935)
		(width 0.12446)
		(layer "B.Cu")
		(net "PHY_DPB_TO_SCC_22_DN")
	)
	(segment
		(start 107.90174 -34.63544)
		(end 107.802934 -34.169858)
		(width 0.12446)
		(layer "B.Cu")
		(net "PHY_DPB_TO_SCC_22_DN")
	)
	(segment
		(start 106.089704 -43.161966)
		(end 107.90174 -34.63544)
		(width 0.12446)
		(layer "B.Cu")
		(net "PHY_DPB_TO_SCC_22_DN")
	)
	(segment
		(start 103.536496 -4.296918)
		(end 103.88092 -4.296918)
		(width 0.12446)
		(layer "B.Cu")
		(net "PHY_DPB_TO_SCC_22_DN")
	)
	(segment
		(start 103.095044 -14.002004)
		(end 103.000048 -13.542772)
		(width 0.12446)
		(layer "B.Cu")
		(net "PHY_DPB_TO_SCC_22_DN")
	)
	(segment
		(start 105.791 -43.942)
		(end 105.791 -43.812968)
		(width 0.12446)
		(layer "B.Cu")
		(net "PHY_DPB_TO_SCC_22_DN")
	)
	(segment
		(start 105.791 -43.812968)
		(end 105.8672 -43.736768)
		(width 0.12446)
		(layer "B.Cu")
		(net "PHY_DPB_TO_SCC_22_DN")
	)
	(segment
		(start 102.896924 -13.043154)
		(end 102.896924 -4.93649)
		(width 0.12446)
		(layer "B.Cu")
		(net "PHY_DPB_TO_SCC_22_DN")
	)
	(segment
		(start 105.8672 -43.736768)
		(end 105.8672 -43.38447)
		(width 0.12446)
		(layer "B.Cu")
		(net "PHY_DPB_TO_SCC_22_DN")
	)
	(segment
		(start 107.80268 -34.16935)
		(end 105.407714 -22.902164)
		(width 0.12446)
		(layer "B.Cu")
		(net "PHY_DPB_TO_SCC_22_DN")
	)
	(segment
		(start 105.8672 -43.38447)
		(end 106.089704 -43.161966)
		(width 0.12446)
		(layer "B.Cu")
		(net "PHY_DPB_TO_SCC_22_DN")
	)
	(segment
		(start 103.110538 -14.076934)
		(end 103.095044 -14.002004)
		(width 0.12446)
		(layer "B.Cu")
		(net "PHY_DPB_TO_SCC_22_DN")
	)
	(segment
		(start 103.736648 -15.04061)
		(end 103.110538 -14.076934)
		(width 0.12446)
		(layer "B.Cu")
		(net "PHY_DPB_TO_SCC_22_DN")
	)
	(arc
		(start 103.965248 -4.261866)
		(mid 103.991022 -4.223293)
		(end 104.000046 -4.177792)
		(width 0.12446)
		(layer "B.Cu")
		(net "PHY_DPB_TO_SCC_22_DN")
	)
	(arc
		(start 103.88092 -4.296918)
		(mid 103.926576 -4.287801)
		(end 103.965248 -4.261866)
		(width 0.12446)
		(layer "B.Cu")
		(net "PHY_DPB_TO_SCC_22_DN")
	)
	(arc
		(start 102.896924 -4.93649)
		(mid 103.08425 -4.484244)
		(end 103.536496 -4.296918)
		(width 0.12446)
		(layer "B.Cu")
		(net "PHY_DPB_TO_SCC_22_DN")
	)
	(segment
		(start 102.200202 -3.999992)
		(end 102.200202 -3.622294)
		(width 0.12446)
		(layer "B.Cu")
		(net "PHY_DPB_TO_SCC_21_DP")
	)
	(segment
		(start 106.378248 -32.814514)
		(end 106.455718 -33.179766)
		(width 0.12446)
		(layer "B.Cu")
		(net "PHY_DPB_TO_SCC_21_DP")
	)
	(segment
		(start 106.825542 -34.919412)
		(end 105.021126 -43.41622)
		(width 0.12446)
		(layer "B.Cu")
		(net "PHY_DPB_TO_SCC_21_DP")
	)
	(segment
		(start 106.18851 -31.92272)
		(end 106.507788 -32.129984)
		(width 0.12446)
		(layer "B.Cu")
		(net "PHY_DPB_TO_SCC_21_DP")
	)
	(segment
		(start 101.50348 -3.73634)
		(end 101.50348 -12.409678)
		(width 0.12446)
		(layer "B.Cu")
		(net "PHY_DPB_TO_SCC_21_DP")
	)
	(segment
		(start 105.021126 -43.41622)
		(end 104.7623 -43.675046)
		(width 0.12446)
		(layer "B.Cu")
		(net "PHY_DPB_TO_SCC_21_DP")
	)
	(segment
		(start 101.50348 -12.409678)
		(end 101.820218 -13.899896)
		(width 0.12446)
		(layer "B.Cu")
		(net "PHY_DPB_TO_SCC_21_DP")
	)
	(segment
		(start 106.24058 -30.872938)
		(end 106.318304 -31.23819)
		(width 0.12446)
		(layer "B.Cu")
		(net "PHY_DPB_TO_SCC_21_DP")
	)
	(segment
		(start 105.921302 -30.66542)
		(end 106.24058 -30.872938)
		(width 0.12446)
		(layer "B.Cu")
		(net "PHY_DPB_TO_SCC_21_DP")
	)
	(segment
		(start 106.507788 -32.129984)
		(end 106.585512 -32.495236)
		(width 0.12446)
		(layer "B.Cu")
		(net "PHY_DPB_TO_SCC_21_DP")
	)
	(segment
		(start 102.081076 -3.503168)
		(end 101.736652 -3.503168)
		(width 0.12446)
		(layer "B.Cu")
		(net "PHY_DPB_TO_SCC_21_DP")
	)
	(segment
		(start 106.455718 -33.179766)
		(end 106.774996 -33.387284)
		(width 0.12446)
		(layer "B.Cu")
		(net "PHY_DPB_TO_SCC_21_DP")
	)
	(segment
		(start 106.11104 -31.557468)
		(end 106.18851 -31.92272)
		(width 0.12446)
		(layer "B.Cu")
		(net "PHY_DPB_TO_SCC_21_DP")
	)
	(segment
		(start 104.7623 -43.8785)
		(end 104.8258 -43.942)
		(width 0.12446)
		(layer "B.Cu")
		(net "PHY_DPB_TO_SCC_21_DP")
	)
	(segment
		(start 106.645456 -34.071814)
		(end 106.825542 -34.919412)
		(width 0.12446)
		(layer "B.Cu")
		(net "PHY_DPB_TO_SCC_21_DP")
	)
	(segment
		(start 106.585512 -32.495236)
		(end 106.378248 -32.814514)
		(width 0.12446)
		(layer "B.Cu")
		(net "PHY_DPB_TO_SCC_21_DP")
	)
	(segment
		(start 101.820218 -13.899896)
		(end 102.619302 -15.130526)
		(width 0.12446)
		(layer "B.Cu")
		(net "PHY_DPB_TO_SCC_21_DP")
	)
	(segment
		(start 106.774996 -33.387284)
		(end 106.85272 -33.752536)
		(width 0.12446)
		(layer "B.Cu")
		(net "PHY_DPB_TO_SCC_21_DP")
	)
	(segment
		(start 104.7623 -43.675046)
		(end 104.7623 -43.8785)
		(width 0.12446)
		(layer "B.Cu")
		(net "PHY_DPB_TO_SCC_21_DP")
	)
	(segment
		(start 106.85272 -33.752536)
		(end 106.645456 -34.071814)
		(width 0.12446)
		(layer "B.Cu")
		(net "PHY_DPB_TO_SCC_21_DP")
	)
	(segment
		(start 106.318304 -31.23819)
		(end 106.11104 -31.557468)
		(width 0.12446)
		(layer "B.Cu")
		(net "PHY_DPB_TO_SCC_21_DP")
	)
	(segment
		(start 102.619302 -15.130526)
		(end 105.921302 -30.66542)
		(width 0.12446)
		(layer "B.Cu")
		(net "PHY_DPB_TO_SCC_21_DP")
	)
	(arc
		(start 102.165404 -3.53822)
		(mid 102.126743 -3.51226)
		(end 102.081076 -3.503168)
		(width 0.12446)
		(layer "B.Cu")
		(net "PHY_DPB_TO_SCC_21_DP")
	)
	(arc
		(start 101.736652 -3.503168)
		(mid 101.571774 -3.571462)
		(end 101.50348 -3.73634)
		(width 0.12446)
		(layer "B.Cu")
		(net "PHY_DPB_TO_SCC_21_DP")
	)
	(arc
		(start 102.200202 -3.622294)
		(mid 102.191153 -3.576804)
		(end 102.165404 -3.53822)
		(width 0.12446)
		(layer "B.Cu")
		(net "PHY_DPB_TO_SCC_21_DP")
	)
	(segment
		(start 104.3559 -43.506644)
		(end 104.3559 -43.8531)
		(width 0.12446)
		(layer "B.Cu")
		(net "PHY_DPB_TO_SCC_21_DN")
	)
	(segment
		(start 101.09708 -12.452604)
		(end 101.438202 -14.058138)
		(width 0.12446)
		(layer "B.Cu")
		(net "PHY_DPB_TO_SCC_21_DN")
	)
	(segment
		(start 101.438202 -14.058138)
		(end 102.237286 -15.288768)
		(width 0.12446)
		(layer "B.Cu")
		(net "PHY_DPB_TO_SCC_21_DN")
	)
	(segment
		(start 102.237286 -15.288768)
		(end 106.409998 -34.919412)
		(width 0.12446)
		(layer "B.Cu")
		(net "PHY_DPB_TO_SCC_21_DN")
	)
	(segment
		(start 102.200202 -2.600198)
		(end 102.200202 -2.977642)
		(width 0.12446)
		(layer "B.Cu")
		(net "PHY_DPB_TO_SCC_21_DN")
	)
	(segment
		(start 104.648508 -43.214036)
		(end 104.3559 -43.506644)
		(width 0.12446)
		(layer "B.Cu")
		(net "PHY_DPB_TO_SCC_21_DN")
	)
	(segment
		(start 106.409998 -34.919412)
		(end 104.648508 -43.214036)
		(width 0.12446)
		(layer "B.Cu")
		(net "PHY_DPB_TO_SCC_21_DN")
	)
	(segment
		(start 102.081076 -3.096768)
		(end 101.736652 -3.096768)
		(width 0.12446)
		(layer "B.Cu")
		(net "PHY_DPB_TO_SCC_21_DN")
	)
	(segment
		(start 104.3559 -43.8531)
		(end 104.267 -43.942)
		(width 0.12446)
		(layer "B.Cu")
		(net "PHY_DPB_TO_SCC_21_DN")
	)
	(segment
		(start 101.09708 -3.73634)
		(end 101.09708 -12.452604)
		(width 0.12446)
		(layer "B.Cu")
		(net "PHY_DPB_TO_SCC_21_DN")
	)
	(arc
		(start 102.165404 -3.061716)
		(mid 102.126743 -3.087676)
		(end 102.081076 -3.096768)
		(width 0.12446)
		(layer "B.Cu")
		(net "PHY_DPB_TO_SCC_21_DN")
	)
	(arc
		(start 101.736652 -3.096768)
		(mid 101.284406 -3.284094)
		(end 101.09708 -3.73634)
		(width 0.12446)
		(layer "B.Cu")
		(net "PHY_DPB_TO_SCC_21_DN")
	)
	(arc
		(start 102.200202 -2.977642)
		(mid 102.191153 -3.023132)
		(end 102.165404 -3.061716)
		(width 0.12446)
		(layer "B.Cu")
		(net "PHY_DPB_TO_SCC_21_DN")
	)
	(segment
		(start 100.400104 -4.822444)
		(end 100.400104 -5.200142)
		(width 0.12446)
		(layer "B.Cu")
		(net "PHY_DPB_TO_SCC_20_DP")
	)
	(segment
		(start 99.876864 -14.20749)
		(end 99.703382 -13.391896)
		(width 0.12446)
		(layer "B.Cu")
		(net "PHY_DPB_TO_SCC_20_DP")
	)
	(segment
		(start 103.233474 -43.477688)
		(end 103.86568 -42.845482)
		(width 0.12446)
		(layer "B.Cu")
		(net "PHY_DPB_TO_SCC_20_DP")
	)
	(segment
		(start 104.911144 -31.853886)
		(end 104.833674 -31.488634)
		(width 0.12446)
		(layer "B.Cu")
		(net "PHY_DPB_TO_SCC_20_DP")
	)
	(segment
		(start 103.86568 -42.845482)
		(end 105.418382 -35.53587)
		(width 0.12446)
		(layer "B.Cu")
		(net "PHY_DPB_TO_SCC_20_DP")
	)
	(segment
		(start 103.3018 -43.942)
		(end 103.233474 -43.873674)
		(width 0.12446)
		(layer "B.Cu")
		(net "PHY_DPB_TO_SCC_20_DP")
	)
	(segment
		(start 105.185972 -34.440876)
		(end 104.971088 -33.430464)
		(width 0.12446)
		(layer "B.Cu")
		(net "PHY_DPB_TO_SCC_20_DP")
	)
	(segment
		(start 101.376734 -16.517112)
		(end 99.876864 -14.20749)
		(width 0.12446)
		(layer "B.Cu")
		(net "PHY_DPB_TO_SCC_20_DP")
	)
	(segment
		(start 103.233474 -43.873674)
		(end 103.233474 -43.477688)
		(width 0.12446)
		(layer "B.Cu")
		(net "PHY_DPB_TO_SCC_20_DP")
	)
	(segment
		(start 104.833674 -31.488634)
		(end 104.514396 -31.28137)
		(width 0.12446)
		(layer "B.Cu")
		(net "PHY_DPB_TO_SCC_20_DP")
	)
	(segment
		(start 104.566466 -30.231588)
		(end 104.247188 -30.02407)
		(width 0.12446)
		(layer "B.Cu")
		(net "PHY_DPB_TO_SCC_20_DP")
	)
	(segment
		(start 99.703382 -13.391896)
		(end 99.703382 -4.93649)
		(width 0.12446)
		(layer "B.Cu")
		(net "PHY_DPB_TO_SCC_20_DP")
	)
	(segment
		(start 105.178352 -33.111186)
		(end 105.100628 -32.745934)
		(width 0.12446)
		(layer "B.Cu")
		(net "PHY_DPB_TO_SCC_20_DP")
	)
	(segment
		(start 104.64419 -30.59684)
		(end 104.566466 -30.231588)
		(width 0.12446)
		(layer "B.Cu")
		(net "PHY_DPB_TO_SCC_20_DP")
	)
	(segment
		(start 99.936554 -4.703318)
		(end 100.280978 -4.703318)
		(width 0.12446)
		(layer "B.Cu")
		(net "PHY_DPB_TO_SCC_20_DP")
	)
	(segment
		(start 104.78135 -32.538416)
		(end 104.70388 -32.173164)
		(width 0.12446)
		(layer "B.Cu")
		(net "PHY_DPB_TO_SCC_20_DP")
	)
	(segment
		(start 104.436672 -30.916118)
		(end 104.64419 -30.59684)
		(width 0.12446)
		(layer "B.Cu")
		(net "PHY_DPB_TO_SCC_20_DP")
	)
	(segment
		(start 105.418382 -35.53587)
		(end 105.185718 -34.440876)
		(width 0.12446)
		(layer "B.Cu")
		(net "PHY_DPB_TO_SCC_20_DP")
	)
	(segment
		(start 105.185718 -34.440876)
		(end 105.185972 -34.440876)
		(width 0.12446)
		(layer "B.Cu")
		(net "PHY_DPB_TO_SCC_20_DP")
	)
	(segment
		(start 104.70388 -32.173164)
		(end 104.911144 -31.853886)
		(width 0.12446)
		(layer "B.Cu")
		(net "PHY_DPB_TO_SCC_20_DP")
	)
	(segment
		(start 104.514396 -31.28137)
		(end 104.436672 -30.916118)
		(width 0.12446)
		(layer "B.Cu")
		(net "PHY_DPB_TO_SCC_20_DP")
	)
	(segment
		(start 105.100628 -32.745934)
		(end 104.78135 -32.538416)
		(width 0.12446)
		(layer "B.Cu")
		(net "PHY_DPB_TO_SCC_20_DP")
	)
	(segment
		(start 104.247188 -30.02407)
		(end 101.376734 -16.517112)
		(width 0.12446)
		(layer "B.Cu")
		(net "PHY_DPB_TO_SCC_20_DP")
	)
	(segment
		(start 104.971088 -33.430464)
		(end 105.178352 -33.111186)
		(width 0.12446)
		(layer "B.Cu")
		(net "PHY_DPB_TO_SCC_20_DP")
	)
	(arc
		(start 99.703382 -4.93649)
		(mid 99.771676 -4.771612)
		(end 99.936554 -4.703318)
		(width 0.12446)
		(layer "B.Cu")
		(net "PHY_DPB_TO_SCC_20_DP")
	)
	(arc
		(start 100.365306 -4.73837)
		(mid 100.39108 -4.776943)
		(end 100.400104 -4.822444)
		(width 0.12446)
		(layer "B.Cu")
		(net "PHY_DPB_TO_SCC_20_DP")
	)
	(arc
		(start 100.280978 -4.703318)
		(mid 100.326634 -4.712435)
		(end 100.365306 -4.73837)
		(width 0.12446)
		(layer "B.Cu")
		(net "PHY_DPB_TO_SCC_20_DP")
	)
	(segment
		(start 105.002838 -35.53587)
		(end 100.994718 -16.675354)
		(width 0.12446)
		(layer "B.Cu")
		(net "PHY_DPB_TO_SCC_20_DN")
	)
	(segment
		(start 102.743 -43.942)
		(end 102.827074 -43.857926)
		(width 0.12446)
		(layer "B.Cu")
		(net "PHY_DPB_TO_SCC_20_DN")
	)
	(segment
		(start 103.493062 -42.643298)
		(end 105.002838 -35.53587)
		(width 0.12446)
		(layer "B.Cu")
		(net "PHY_DPB_TO_SCC_20_DN")
	)
	(segment
		(start 99.296982 -13.434822)
		(end 99.296982 -4.93649)
		(width 0.12446)
		(layer "B.Cu")
		(net "PHY_DPB_TO_SCC_20_DN")
	)
	(segment
		(start 99.494848 -14.365732)
		(end 99.296982 -13.434822)
		(width 0.12446)
		(layer "B.Cu")
		(net "PHY_DPB_TO_SCC_20_DN")
	)
	(segment
		(start 99.936554 -4.296918)
		(end 100.280978 -4.296918)
		(width 0.12446)
		(layer "B.Cu")
		(net "PHY_DPB_TO_SCC_20_DN")
	)
	(segment
		(start 102.827074 -43.309286)
		(end 103.493062 -42.643298)
		(width 0.12446)
		(layer "B.Cu")
		(net "PHY_DPB_TO_SCC_20_DN")
	)
	(segment
		(start 100.994718 -16.675354)
		(end 99.494848 -14.365732)
		(width 0.12446)
		(layer "B.Cu")
		(net "PHY_DPB_TO_SCC_20_DN")
	)
	(segment
		(start 102.827074 -43.857926)
		(end 102.827074 -43.309286)
		(width 0.12446)
		(layer "B.Cu")
		(net "PHY_DPB_TO_SCC_20_DN")
	)
	(segment
		(start 100.400104 -4.177792)
		(end 100.400104 -3.800094)
		(width 0.12446)
		(layer "B.Cu")
		(net "PHY_DPB_TO_SCC_20_DN")
	)
	(arc
		(start 99.296982 -4.93649)
		(mid 99.484308 -4.484244)
		(end 99.936554 -4.296918)
		(width 0.12446)
		(layer "B.Cu")
		(net "PHY_DPB_TO_SCC_20_DN")
	)
	(arc
		(start 100.280978 -4.296918)
		(mid 100.326634 -4.287801)
		(end 100.365306 -4.261866)
		(width 0.12446)
		(layer "B.Cu")
		(net "PHY_DPB_TO_SCC_20_DN")
	)
	(arc
		(start 100.365306 -4.261866)
		(mid 100.39108 -4.223293)
		(end 100.400104 -4.177792)
		(width 0.12446)
		(layer "B.Cu")
		(net "PHY_DPB_TO_SCC_20_DN")
	)
	(segment
		(start 139.406122 -66.726308)
		(end 140.857986 -66.391282)
		(width 0.12446)
		(layer "B.Cu")
		(net "PHY_DPB_TO_SCC_2_DP")
	)
	(segment
		(start 140.024104 -54.347618)
		(end 138.987022 -49.466754)
		(width 0.12446)
		(layer "B.Cu")
		(net "PHY_DPB_TO_SCC_2_DP")
	)
	(segment
		(start 142.641828 -64.52489)
		(end 143.190214 -61.94298)
		(width 0.12446)
		(layer "B.Cu")
		(net "PHY_DPB_TO_SCC_2_DP")
	)
	(segment
		(start 137.024872 -32.936434)
		(end 139.98702 -18.99793)
		(width 0.12446)
		(layer "B.Cu")
		(net "PHY_DPB_TO_SCC_2_DP")
	)
	(segment
		(start 138.123168 -66.8274)
		(end 138.22426 -66.726308)
		(width 0.12446)
		(layer "B.Cu")
		(net "PHY_DPB_TO_SCC_2_DP")
	)
	(segment
		(start 139.999974 -4.822444)
		(end 139.999974 -5.200142)
		(width 0.12446)
		(layer "B.Cu")
		(net "PHY_DPB_TO_SCC_2_DP")
	)
	(segment
		(start 140.857986 -66.391282)
		(end 141.847824 -65.748408)
		(width 0.12446)
		(layer "B.Cu")
		(net "PHY_DPB_TO_SCC_2_DP")
	)
	(segment
		(start 143.190214 -61.94298)
		(end 142.33017 -57.897776)
		(width 0.12446)
		(layer "B.Cu")
		(net "PHY_DPB_TO_SCC_2_DP")
	)
	(segment
		(start 139.762738 -45.81779)
		(end 137.024872 -32.936434)
		(width 0.12446)
		(layer "B.Cu")
		(net "PHY_DPB_TO_SCC_2_DP")
	)
	(segment
		(start 142.33017 -57.897776)
		(end 140.024104 -54.347618)
		(width 0.12446)
		(layer "B.Cu")
		(net "PHY_DPB_TO_SCC_2_DP")
	)
	(segment
		(start 141.847824 -65.748408)
		(end 142.641828 -64.52489)
		(width 0.12446)
		(layer "B.Cu")
		(net "PHY_DPB_TO_SCC_2_DP")
	)
	(segment
		(start 139.98702 -18.99793)
		(end 139.303252 -15.775432)
		(width 0.12446)
		(layer "B.Cu")
		(net "PHY_DPB_TO_SCC_2_DP")
	)
	(segment
		(start 138.22426 -66.726308)
		(end 139.406122 -66.726308)
		(width 0.12446)
		(layer "B.Cu")
		(net "PHY_DPB_TO_SCC_2_DP")
	)
	(segment
		(start 139.303252 -15.775432)
		(end 139.303252 -4.93649)
		(width 0.12446)
		(layer "B.Cu")
		(net "PHY_DPB_TO_SCC_2_DP")
	)
	(segment
		(start 138.987022 -49.466754)
		(end 139.762738 -45.81779)
		(width 0.12446)
		(layer "B.Cu")
		(net "PHY_DPB_TO_SCC_2_DP")
	)
	(segment
		(start 137.7442 -66.8274)
		(end 138.123168 -66.8274)
		(width 0.12446)
		(layer "B.Cu")
		(net "PHY_DPB_TO_SCC_2_DP")
	)
	(segment
		(start 139.536424 -4.703318)
		(end 139.880848 -4.703318)
		(width 0.12446)
		(layer "B.Cu")
		(net "PHY_DPB_TO_SCC_2_DP")
	)
	(arc
		(start 139.303252 -4.93649)
		(mid 139.371546 -4.771612)
		(end 139.536424 -4.703318)
		(width 0.12446)
		(layer "B.Cu")
		(net "PHY_DPB_TO_SCC_2_DP")
	)
	(arc
		(start 139.880848 -4.703318)
		(mid 139.926504 -4.712435)
		(end 139.965176 -4.73837)
		(width 0.12446)
		(layer "B.Cu")
		(net "PHY_DPB_TO_SCC_2_DP")
	)
	(arc
		(start 139.965176 -4.73837)
		(mid 139.99095 -4.776943)
		(end 139.999974 -4.822444)
		(width 0.12446)
		(layer "B.Cu")
		(net "PHY_DPB_TO_SCC_2_DP")
	)
	(segment
		(start 139.571476 -18.99793)
		(end 138.896852 -15.818104)
		(width 0.12446)
		(layer "B.Cu")
		(net "PHY_DPB_TO_SCC_2_DN")
	)
	(segment
		(start 138.123168 -66.2686)
		(end 138.174476 -66.319908)
		(width 0.12446)
		(layer "B.Cu")
		(net "PHY_DPB_TO_SCC_2_DN")
	)
	(segment
		(start 138.174476 -66.319908)
		(end 139.35964 -66.319908)
		(width 0.12446)
		(layer "B.Cu")
		(net "PHY_DPB_TO_SCC_2_DN")
	)
	(segment
		(start 138.571478 -49.466754)
		(end 139.347194 -45.81779)
		(width 0.12446)
		(layer "B.Cu")
		(net "PHY_DPB_TO_SCC_2_DN")
	)
	(segment
		(start 139.999974 -4.177792)
		(end 139.999974 -3.800094)
		(width 0.12446)
		(layer "B.Cu")
		(net "PHY_DPB_TO_SCC_2_DN")
	)
	(segment
		(start 141.7955 -65.082166)
		(end 142.259812 -64.366648)
		(width 0.12446)
		(layer "B.Cu")
		(net "PHY_DPB_TO_SCC_2_DN")
	)
	(segment
		(start 138.896852 -15.818104)
		(end 138.896852 -4.93649)
		(width 0.12446)
		(layer "B.Cu")
		(net "PHY_DPB_TO_SCC_2_DN")
	)
	(segment
		(start 140.696696 -66.011298)
		(end 141.553692 -65.45453)
		(width 0.12446)
		(layer "B.Cu")
		(net "PHY_DPB_TO_SCC_2_DN")
	)
	(segment
		(start 137.7442 -66.2686)
		(end 138.123168 -66.2686)
		(width 0.12446)
		(layer "B.Cu")
		(net "PHY_DPB_TO_SCC_2_DN")
	)
	(segment
		(start 142.259812 -64.366648)
		(end 142.77467 -61.94298)
		(width 0.12446)
		(layer "B.Cu")
		(net "PHY_DPB_TO_SCC_2_DN")
	)
	(segment
		(start 139.35964 -66.319908)
		(end 140.696696 -66.011298)
		(width 0.12446)
		(layer "B.Cu")
		(net "PHY_DPB_TO_SCC_2_DN")
	)
	(segment
		(start 141.553692 -65.45453)
		(end 141.7955 -65.082166)
		(width 0.12446)
		(layer "B.Cu")
		(net "PHY_DPB_TO_SCC_2_DN")
	)
	(segment
		(start 139.347194 -45.81779)
		(end 136.609328 -32.936434)
		(width 0.12446)
		(layer "B.Cu")
		(net "PHY_DPB_TO_SCC_2_DN")
	)
	(segment
		(start 139.642088 -54.50586)
		(end 138.571478 -49.466754)
		(width 0.12446)
		(layer "B.Cu")
		(net "PHY_DPB_TO_SCC_2_DN")
	)
	(segment
		(start 142.77467 -61.94298)
		(end 141.948154 -58.056018)
		(width 0.12446)
		(layer "B.Cu")
		(net "PHY_DPB_TO_SCC_2_DN")
	)
	(segment
		(start 141.948154 -58.056018)
		(end 139.642088 -54.50586)
		(width 0.12446)
		(layer "B.Cu")
		(net "PHY_DPB_TO_SCC_2_DN")
	)
	(segment
		(start 136.609328 -32.936434)
		(end 139.571476 -18.99793)
		(width 0.12446)
		(layer "B.Cu")
		(net "PHY_DPB_TO_SCC_2_DN")
	)
	(segment
		(start 139.536424 -4.296918)
		(end 139.880848 -4.296918)
		(width 0.12446)
		(layer "B.Cu")
		(net "PHY_DPB_TO_SCC_2_DN")
	)
	(arc
		(start 139.880848 -4.296918)
		(mid 139.926504 -4.287801)
		(end 139.965176 -4.261866)
		(width 0.12446)
		(layer "B.Cu")
		(net "PHY_DPB_TO_SCC_2_DN")
	)
	(arc
		(start 139.965176 -4.261866)
		(mid 139.99095 -4.223293)
		(end 139.999974 -4.177792)
		(width 0.12446)
		(layer "B.Cu")
		(net "PHY_DPB_TO_SCC_2_DN")
	)
	(arc
		(start 138.896852 -4.93649)
		(mid 139.084178 -4.484244)
		(end 139.536424 -4.296918)
		(width 0.12446)
		(layer "B.Cu")
		(net "PHY_DPB_TO_SCC_2_DN")
	)
	(segment
		(start 103.539036 -32.703262)
		(end 103.461566 -32.33801)
		(width 0.12446)
		(layer "B.Cu")
		(net "PHY_DPB_TO_SCC_19_DP")
	)
	(segment
		(start 101.709982 -43.874182)
		(end 101.709982 -43.274234)
		(width 0.12446)
		(layer "B.Cu")
		(net "PHY_DPB_TO_SCC_19_DP")
	)
	(segment
		(start 99.972368 -17.213326)
		(end 98.413824 -14.814296)
		(width 0.12446)
		(layer "B.Cu")
		(net "PHY_DPB_TO_SCC_19_DP")
	)
	(segment
		(start 102.87508 -30.8737)
		(end 99.972368 -17.213326)
		(width 0.12446)
		(layer "B.Cu")
		(net "PHY_DPB_TO_SCC_19_DP")
	)
	(segment
		(start 103.461566 -32.33801)
		(end 103.142288 -32.130746)
		(width 0.12446)
		(layer "B.Cu")
		(net "PHY_DPB_TO_SCC_19_DP")
	)
	(segment
		(start 98.600006 -3.622294)
		(end 98.600006 -3.999992)
		(width 0.12446)
		(layer "B.Cu")
		(net "PHY_DPB_TO_SCC_19_DP")
	)
	(segment
		(start 103.142288 -32.130746)
		(end 103.064564 -31.765494)
		(width 0.12446)
		(layer "B.Cu")
		(net "PHY_DPB_TO_SCC_19_DP")
	)
	(segment
		(start 103.806244 -33.960562)
		(end 103.728774 -33.59531)
		(width 0.12446)
		(layer "B.Cu")
		(net "PHY_DPB_TO_SCC_19_DP")
	)
	(segment
		(start 101.7778 -43.942)
		(end 101.709982 -43.874182)
		(width 0.12446)
		(layer "B.Cu")
		(net "PHY_DPB_TO_SCC_19_DP")
	)
	(segment
		(start 103.59898 -34.280094)
		(end 103.806244 -33.960562)
		(width 0.12446)
		(layer "B.Cu")
		(net "PHY_DPB_TO_SCC_19_DP")
	)
	(segment
		(start 103.331772 -33.022794)
		(end 103.539036 -32.703262)
		(width 0.12446)
		(layer "B.Cu")
		(net "PHY_DPB_TO_SCC_19_DP")
	)
	(segment
		(start 102.616 -42.368216)
		(end 103.966772 -36.011358)
		(width 0.12446)
		(layer "B.Cu")
		(net "PHY_DPB_TO_SCC_19_DP")
	)
	(segment
		(start 101.709982 -43.274234)
		(end 102.616 -42.368216)
		(width 0.12446)
		(layer "B.Cu")
		(net "PHY_DPB_TO_SCC_19_DP")
	)
	(segment
		(start 98.413824 -14.814296)
		(end 97.903284 -12.413742)
		(width 0.12446)
		(layer "B.Cu")
		(net "PHY_DPB_TO_SCC_19_DP")
	)
	(segment
		(start 103.966772 -36.011358)
		(end 103.773986 -35.103562)
		(width 0.12446)
		(layer "B.Cu")
		(net "PHY_DPB_TO_SCC_19_DP")
	)
	(segment
		(start 103.272082 -31.446216)
		(end 103.194358 -31.080964)
		(width 0.12446)
		(layer "B.Cu")
		(net "PHY_DPB_TO_SCC_19_DP")
	)
	(segment
		(start 103.728774 -33.59531)
		(end 103.409496 -33.388046)
		(width 0.12446)
		(layer "B.Cu")
		(net "PHY_DPB_TO_SCC_19_DP")
	)
	(segment
		(start 97.903284 -12.413742)
		(end 97.903284 -3.73634)
		(width 0.12446)
		(layer "B.Cu")
		(net "PHY_DPB_TO_SCC_19_DP")
	)
	(segment
		(start 103.409496 -33.388046)
		(end 103.331772 -33.022794)
		(width 0.12446)
		(layer "B.Cu")
		(net "PHY_DPB_TO_SCC_19_DP")
	)
	(segment
		(start 103.064564 -31.765494)
		(end 103.272082 -31.446216)
		(width 0.12446)
		(layer "B.Cu")
		(net "PHY_DPB_TO_SCC_19_DP")
	)
	(segment
		(start 103.773986 -35.103562)
		(end 103.59898 -34.280094)
		(width 0.12446)
		(layer "B.Cu")
		(net "PHY_DPB_TO_SCC_19_DP")
	)
	(segment
		(start 98.136456 -3.503168)
		(end 98.48088 -3.503168)
		(width 0.12446)
		(layer "B.Cu")
		(net "PHY_DPB_TO_SCC_19_DP")
	)
	(segment
		(start 103.194358 -31.080964)
		(end 102.87508 -30.8737)
		(width 0.12446)
		(layer "B.Cu")
		(net "PHY_DPB_TO_SCC_19_DP")
	)
	(arc
		(start 97.903284 -3.73634)
		(mid 97.971578 -3.571462)
		(end 98.136456 -3.503168)
		(width 0.12446)
		(layer "B.Cu")
		(net "PHY_DPB_TO_SCC_19_DP")
	)
	(arc
		(start 98.565208 -3.53822)
		(mid 98.590982 -3.576793)
		(end 98.600006 -3.622294)
		(width 0.12446)
		(layer "B.Cu")
		(net "PHY_DPB_TO_SCC_19_DP")
	)
	(arc
		(start 98.48088 -3.503168)
		(mid 98.526536 -3.512285)
		(end 98.565208 -3.53822)
		(width 0.12446)
		(layer "B.Cu")
		(net "PHY_DPB_TO_SCC_19_DP")
	)
	(segment
		(start 97.496884 -12.456668)
		(end 97.496884 -3.73634)
		(width 0.12446)
		(layer "B.Cu")
		(net "PHY_DPB_TO_SCC_19_DN")
	)
	(segment
		(start 99.590352 -17.371568)
		(end 98.031808 -14.972538)
		(width 0.12446)
		(layer "B.Cu")
		(net "PHY_DPB_TO_SCC_19_DN")
	)
	(segment
		(start 102.243382 -42.166032)
		(end 103.551228 -36.011358)
		(width 0.12446)
		(layer "B.Cu")
		(net "PHY_DPB_TO_SCC_19_DN")
	)
	(segment
		(start 98.031808 -14.972538)
		(end 97.496884 -12.456668)
		(width 0.12446)
		(layer "B.Cu")
		(net "PHY_DPB_TO_SCC_19_DN")
	)
	(segment
		(start 98.600006 -2.977642)
		(end 98.600006 -2.600198)
		(width 0.12446)
		(layer "B.Cu")
		(net "PHY_DPB_TO_SCC_19_DN")
	)
	(segment
		(start 103.551228 -36.011358)
		(end 99.590352 -17.371568)
		(width 0.12446)
		(layer "B.Cu")
		(net "PHY_DPB_TO_SCC_19_DN")
	)
	(segment
		(start 101.219 -43.942)
		(end 101.303582 -43.857418)
		(width 0.12446)
		(layer "B.Cu")
		(net "PHY_DPB_TO_SCC_19_DN")
	)
	(segment
		(start 101.303582 -43.105832)
		(end 102.243382 -42.166032)
		(width 0.12446)
		(layer "B.Cu")
		(net "PHY_DPB_TO_SCC_19_DN")
	)
	(segment
		(start 98.136456 -3.096768)
		(end 98.48088 -3.096768)
		(width 0.12446)
		(layer "B.Cu")
		(net "PHY_DPB_TO_SCC_19_DN")
	)
	(segment
		(start 101.303582 -43.857418)
		(end 101.303582 -43.105832)
		(width 0.12446)
		(layer "B.Cu")
		(net "PHY_DPB_TO_SCC_19_DN")
	)
	(arc
		(start 97.496884 -3.73634)
		(mid 97.68421 -3.284094)
		(end 98.136456 -3.096768)
		(width 0.12446)
		(layer "B.Cu")
		(net "PHY_DPB_TO_SCC_19_DN")
	)
	(arc
		(start 98.565208 -3.061716)
		(mid 98.590982 -3.023143)
		(end 98.600006 -2.977642)
		(width 0.12446)
		(layer "B.Cu")
		(net "PHY_DPB_TO_SCC_19_DN")
	)
	(arc
		(start 98.48088 -3.096768)
		(mid 98.526536 -3.087651)
		(end 98.565208 -3.061716)
		(width 0.12446)
		(layer "B.Cu")
		(net "PHY_DPB_TO_SCC_19_DN")
	)
	(segment
		(start 101.767132 -39.13251)
		(end 101.844602 -38.767258)
		(width 0.12446)
		(layer "B.Cu")
		(net "PHY_DPB_TO_SCC_18_DP")
	)
	(segment
		(start 100.188776 -43.876976)
		(end 100.188776 -43.424094)
		(width 0.12446)
		(layer "B.Cu")
		(net "PHY_DPB_TO_SCC_18_DP")
	)
	(segment
		(start 101.844602 -38.767258)
		(end 102.16388 -38.55974)
		(width 0.12446)
		(layer "B.Cu")
		(net "PHY_DPB_TO_SCC_18_DP")
	)
	(segment
		(start 102.034086 -37.87521)
		(end 102.478332 -35.783774)
		(width 0.12446)
		(layer "B.Cu")
		(net "PHY_DPB_TO_SCC_18_DP")
	)
	(segment
		(start 101.23297 -41.646856)
		(end 101.263958 -41.500298)
		(width 0.12446)
		(layer "B.Cu")
		(net "PHY_DPB_TO_SCC_18_DP")
	)
	(segment
		(start 100.2538 -43.942)
		(end 100.188776 -43.876976)
		(width 0.12446)
		(layer "B.Cu")
		(net "PHY_DPB_TO_SCC_18_DP")
	)
	(segment
		(start 96.098614 -13.041884)
		(end 96.098614 -4.941316)
		(width 0.12446)
		(layer "B.Cu")
		(net "PHY_DPB_TO_SCC_18_DP")
	)
	(segment
		(start 96.336612 -4.703318)
		(end 96.681036 -4.703318)
		(width 0.12446)
		(layer "B.Cu")
		(net "PHY_DPB_TO_SCC_18_DP")
	)
	(segment
		(start 102.478332 -35.783774)
		(end 98.721164 -18.104612)
		(width 0.12446)
		(layer "B.Cu")
		(net "PHY_DPB_TO_SCC_18_DP")
	)
	(segment
		(start 101.499924 -40.389556)
		(end 101.577648 -40.024558)
		(width 0.12446)
		(layer "B.Cu")
		(net "PHY_DPB_TO_SCC_18_DP")
	)
	(segment
		(start 101.974396 -39.451788)
		(end 101.767132 -39.13251)
		(width 0.12446)
		(layer "B.Cu")
		(net "PHY_DPB_TO_SCC_18_DP")
	)
	(segment
		(start 102.241604 -38.194488)
		(end 102.034086 -37.87521)
		(width 0.12446)
		(layer "B.Cu")
		(net "PHY_DPB_TO_SCC_18_DP")
	)
	(segment
		(start 96.422718 -14.56563)
		(end 96.098614 -13.041884)
		(width 0.12446)
		(layer "B.Cu")
		(net "PHY_DPB_TO_SCC_18_DP")
	)
	(segment
		(start 101.31044 -41.281604)
		(end 101.629972 -41.074086)
		(width 0.12446)
		(layer "B.Cu")
		(net "PHY_DPB_TO_SCC_18_DP")
	)
	(segment
		(start 101.896926 -39.81704)
		(end 101.974396 -39.451788)
		(width 0.12446)
		(layer "B.Cu")
		(net "PHY_DPB_TO_SCC_18_DP")
	)
	(segment
		(start 101.577648 -40.024558)
		(end 101.896926 -39.81704)
		(width 0.12446)
		(layer "B.Cu")
		(net "PHY_DPB_TO_SCC_18_DP")
	)
	(segment
		(start 100.24237 -43.171872)
		(end 101.23297 -41.646856)
		(width 0.12446)
		(layer "B.Cu")
		(net "PHY_DPB_TO_SCC_18_DP")
	)
	(segment
		(start 101.707442 -40.709088)
		(end 101.499924 -40.389556)
		(width 0.12446)
		(layer "B.Cu")
		(net "PHY_DPB_TO_SCC_18_DP")
	)
	(segment
		(start 96.800162 -4.822444)
		(end 96.800162 -5.200142)
		(width 0.12446)
		(layer "B.Cu")
		(net "PHY_DPB_TO_SCC_18_DP")
	)
	(segment
		(start 102.16388 -38.55974)
		(end 102.241604 -38.194488)
		(width 0.12446)
		(layer "B.Cu")
		(net "PHY_DPB_TO_SCC_18_DP")
	)
	(segment
		(start 100.188776 -43.424094)
		(end 100.24237 -43.171872)
		(width 0.12446)
		(layer "B.Cu")
		(net "PHY_DPB_TO_SCC_18_DP")
	)
	(segment
		(start 98.721164 -18.104612)
		(end 96.422718 -14.56563)
		(width 0.12446)
		(layer "B.Cu")
		(net "PHY_DPB_TO_SCC_18_DP")
	)
	(segment
		(start 101.629972 -41.074086)
		(end 101.707442 -40.709088)
		(width 0.12446)
		(layer "B.Cu")
		(net "PHY_DPB_TO_SCC_18_DP")
	)
	(segment
		(start 101.263958 -41.500298)
		(end 101.31044 -41.281604)
		(width 0.12446)
		(layer "B.Cu")
		(net "PHY_DPB_TO_SCC_18_DP")
	)
	(arc
		(start 96.098614 -4.941316)
		(mid 96.168322 -4.773026)
		(end 96.336612 -4.703318)
		(width 0.12446)
		(layer "B.Cu")
		(net "PHY_DPB_TO_SCC_18_DP")
	)
	(arc
		(start 96.765364 -4.73837)
		(mid 96.791138 -4.776943)
		(end 96.800162 -4.822444)
		(width 0.12446)
		(layer "B.Cu")
		(net "PHY_DPB_TO_SCC_18_DP")
	)
	(arc
		(start 96.681036 -4.703318)
		(mid 96.726692 -4.712435)
		(end 96.765364 -4.73837)
		(width 0.12446)
		(layer "B.Cu")
		(net "PHY_DPB_TO_SCC_18_DP")
	)
	(segment
		(start 96.800162 -4.177792)
		(end 96.800162 -3.800094)
		(width 0.12446)
		(layer "B.Cu")
		(net "PHY_DPB_TO_SCC_18_DN")
	)
	(segment
		(start 102.062788 -35.783774)
		(end 98.339148 -18.262854)
		(width 0.12446)
		(layer "B.Cu")
		(net "PHY_DPB_TO_SCC_18_DN")
	)
	(segment
		(start 99.860354 -43.013884)
		(end 100.850954 -41.488614)
		(width 0.12446)
		(layer "B.Cu")
		(net "PHY_DPB_TO_SCC_18_DN")
	)
	(segment
		(start 95.692214 -13.08481)
		(end 95.692214 -4.941316)
		(width 0.12446)
		(layer "B.Cu")
		(net "PHY_DPB_TO_SCC_18_DN")
	)
	(segment
		(start 99.782376 -43.381422)
		(end 99.860354 -43.013884)
		(width 0.12446)
		(layer "B.Cu")
		(net "PHY_DPB_TO_SCC_18_DN")
	)
	(segment
		(start 99.782376 -43.854624)
		(end 99.782376 -43.381422)
		(width 0.12446)
		(layer "B.Cu")
		(net "PHY_DPB_TO_SCC_18_DN")
	)
	(segment
		(start 98.339148 -18.262854)
		(end 96.040702 -14.723872)
		(width 0.12446)
		(layer "B.Cu")
		(net "PHY_DPB_TO_SCC_18_DN")
	)
	(segment
		(start 96.040702 -14.723872)
		(end 95.692214 -13.08481)
		(width 0.12446)
		(layer "B.Cu")
		(net "PHY_DPB_TO_SCC_18_DN")
	)
	(segment
		(start 100.850954 -41.488614)
		(end 102.062788 -35.783774)
		(width 0.12446)
		(layer "B.Cu")
		(net "PHY_DPB_TO_SCC_18_DN")
	)
	(segment
		(start 99.695 -43.942)
		(end 99.782376 -43.854624)
		(width 0.12446)
		(layer "B.Cu")
		(net "PHY_DPB_TO_SCC_18_DN")
	)
	(segment
		(start 96.336612 -4.296918)
		(end 96.681036 -4.296918)
		(width 0.12446)
		(layer "B.Cu")
		(net "PHY_DPB_TO_SCC_18_DN")
	)
	(arc
		(start 96.681036 -4.296918)
		(mid 96.726692 -4.287801)
		(end 96.765364 -4.261866)
		(width 0.12446)
		(layer "B.Cu")
		(net "PHY_DPB_TO_SCC_18_DN")
	)
	(arc
		(start 96.765364 -4.261866)
		(mid 96.791138 -4.223293)
		(end 96.800162 -4.177792)
		(width 0.12446)
		(layer "B.Cu")
		(net "PHY_DPB_TO_SCC_18_DN")
	)
	(arc
		(start 95.692214 -4.941316)
		(mid 95.880954 -4.485658)
		(end 96.336612 -4.296918)
		(width 0.12446)
		(layer "B.Cu")
		(net "PHY_DPB_TO_SCC_18_DN")
	)
	(segment
		(start 96.77273 -18.01495)
		(end 96.400366 -17.935956)
		(width 0.12446)
		(layer "B.Cu")
		(net "PHY_DPB_TO_SCC_17_DP")
	)
	(segment
		(start 99.288092 -27.734768)
		(end 99.288346 -27.734768)
		(width 0.12446)
		(layer "B.Cu")
		(net "PHY_DPB_TO_SCC_17_DP")
	)
	(segment
		(start 95.700342 -16.85798)
		(end 94.882208 -15.59814)
		(width 0.12446)
		(layer "B.Cu")
		(net "PHY_DPB_TO_SCC_17_DP")
	)
	(segment
		(start 97.10039 -19.013678)
		(end 96.896936 -18.70075)
		(width 0.12446)
		(layer "B.Cu")
		(net "PHY_DPB_TO_SCC_17_DP")
	)
	(segment
		(start 96.400366 -17.935956)
		(end 96.196912 -17.622774)
		(width 0.12446)
		(layer "B.Cu")
		(net "PHY_DPB_TO_SCC_17_DP")
	)
	(segment
		(start 96.896936 -18.70075)
		(end 96.976184 -18.328132)
		(width 0.12446)
		(layer "B.Cu")
		(net "PHY_DPB_TO_SCC_17_DP")
	)
	(segment
		(start 98.663252 -43.27271)
		(end 99.715574 -41.652698)
		(width 0.12446)
		(layer "B.Cu")
		(net "PHY_DPB_TO_SCC_17_DP")
	)
	(segment
		(start 97.676208 -19.406108)
		(end 97.472754 -19.092926)
		(width 0.12446)
		(layer "B.Cu")
		(net "PHY_DPB_TO_SCC_17_DP")
	)
	(segment
		(start 96.07296 -16.937228)
		(end 95.700342 -16.85798)
		(width 0.12446)
		(layer "B.Cu")
		(net "PHY_DPB_TO_SCC_17_DP")
	)
	(segment
		(start 94.882208 -15.59814)
		(end 94.303342 -12.872466)
		(width 0.12446)
		(layer "B.Cu")
		(net "PHY_DPB_TO_SCC_17_DP")
	)
	(segment
		(start 99.288346 -27.734768)
		(end 97.59696 -19.778472)
		(width 0.12446)
		(layer "B.Cu")
		(net "PHY_DPB_TO_SCC_17_DP")
	)
	(segment
		(start 96.27616 -17.25041)
		(end 96.07296 -16.937228)
		(width 0.12446)
		(layer "B.Cu")
		(net "PHY_DPB_TO_SCC_17_DP")
	)
	(segment
		(start 96.196912 -17.622774)
		(end 96.27616 -17.25041)
		(width 0.12446)
		(layer "B.Cu")
		(net "PHY_DPB_TO_SCC_17_DP")
	)
	(segment
		(start 97.59696 -19.778472)
		(end 97.676208 -19.406108)
		(width 0.12446)
		(layer "B.Cu")
		(net "PHY_DPB_TO_SCC_17_DP")
	)
	(segment
		(start 99.715574 -41.652698)
		(end 100.981256 -35.700716)
		(width 0.12446)
		(layer "B.Cu")
		(net "PHY_DPB_TO_SCC_17_DP")
	)
	(segment
		(start 94.303342 -12.872466)
		(end 94.303342 -3.73634)
		(width 0.12446)
		(layer "B.Cu")
		(net "PHY_DPB_TO_SCC_17_DP")
	)
	(segment
		(start 95.000064 -3.622294)
		(end 95.000064 -3.999992)
		(width 0.12446)
		(layer "B.Cu")
		(net "PHY_DPB_TO_SCC_17_DP")
	)
	(segment
		(start 94.536514 -3.503168)
		(end 94.880938 -3.503168)
		(width 0.12446)
		(layer "B.Cu")
		(net "PHY_DPB_TO_SCC_17_DP")
	)
	(segment
		(start 98.663252 -43.875452)
		(end 98.663252 -43.27271)
		(width 0.12446)
		(layer "B.Cu")
		(net "PHY_DPB_TO_SCC_17_DP")
	)
	(segment
		(start 97.472754 -19.092926)
		(end 97.10039 -19.013678)
		(width 0.12446)
		(layer "B.Cu")
		(net "PHY_DPB_TO_SCC_17_DP")
	)
	(segment
		(start 98.7298 -43.942)
		(end 98.663252 -43.875452)
		(width 0.12446)
		(layer "B.Cu")
		(net "PHY_DPB_TO_SCC_17_DP")
	)
	(segment
		(start 100.981256 -35.700716)
		(end 99.288092 -27.734768)
		(width 0.12446)
		(layer "B.Cu")
		(net "PHY_DPB_TO_SCC_17_DP")
	)
	(segment
		(start 96.976184 -18.328132)
		(end 96.77273 -18.01495)
		(width 0.12446)
		(layer "B.Cu")
		(net "PHY_DPB_TO_SCC_17_DP")
	)
	(arc
		(start 94.303342 -3.73634)
		(mid 94.371636 -3.571462)
		(end 94.536514 -3.503168)
		(width 0.12446)
		(layer "B.Cu")
		(net "PHY_DPB_TO_SCC_17_DP")
	)
	(arc
		(start 94.880938 -3.503168)
		(mid 94.926594 -3.512285)
		(end 94.965266 -3.53822)
		(width 0.12446)
		(layer "B.Cu")
		(net "PHY_DPB_TO_SCC_17_DP")
	)
	(arc
		(start 94.965266 -3.53822)
		(mid 94.99104 -3.576793)
		(end 95.000064 -3.622294)
		(width 0.12446)
		(layer "B.Cu")
		(net "PHY_DPB_TO_SCC_17_DP")
	)
	(segment
		(start 94.500192 -15.756382)
		(end 93.896942 -12.915392)
		(width 0.12446)
		(layer "B.Cu")
		(net "PHY_DPB_TO_SCC_17_DN")
	)
	(segment
		(start 97.215198 -19.937984)
		(end 94.500192 -15.756382)
		(width 0.12446)
		(layer "B.Cu")
		(net "PHY_DPB_TO_SCC_17_DN")
	)
	(segment
		(start 99.333558 -41.494456)
		(end 100.565712 -35.700716)
		(width 0.12446)
		(layer "B.Cu")
		(net "PHY_DPB_TO_SCC_17_DN")
	)
	(segment
		(start 98.256852 -43.15206)
		(end 99.333558 -41.494456)
		(width 0.12446)
		(layer "B.Cu")
		(net "PHY_DPB_TO_SCC_17_DN")
	)
	(segment
		(start 95.000064 -2.977642)
		(end 95.000064 -2.600198)
		(width 0.12446)
		(layer "B.Cu")
		(net "PHY_DPB_TO_SCC_17_DN")
	)
	(segment
		(start 100.565712 -35.700716)
		(end 97.215198 -19.937984)
		(width 0.12446)
		(layer "B.Cu")
		(net "PHY_DPB_TO_SCC_17_DN")
	)
	(segment
		(start 94.536514 -3.096768)
		(end 94.880938 -3.096768)
		(width 0.12446)
		(layer "B.Cu")
		(net "PHY_DPB_TO_SCC_17_DN")
	)
	(segment
		(start 98.256852 -43.856148)
		(end 98.256852 -43.15206)
		(width 0.12446)
		(layer "B.Cu")
		(net "PHY_DPB_TO_SCC_17_DN")
	)
	(segment
		(start 98.171 -43.942)
		(end 98.256852 -43.856148)
		(width 0.12446)
		(layer "B.Cu")
		(net "PHY_DPB_TO_SCC_17_DN")
	)
	(segment
		(start 93.896942 -12.915392)
		(end 93.896942 -3.73634)
		(width 0.12446)
		(layer "B.Cu")
		(net "PHY_DPB_TO_SCC_17_DN")
	)
	(arc
		(start 94.965266 -3.061716)
		(mid 94.99104 -3.023143)
		(end 95.000064 -2.977642)
		(width 0.12446)
		(layer "B.Cu")
		(net "PHY_DPB_TO_SCC_17_DN")
	)
	(arc
		(start 94.880938 -3.096768)
		(mid 94.926594 -3.087651)
		(end 94.965266 -3.061716)
		(width 0.12446)
		(layer "B.Cu")
		(net "PHY_DPB_TO_SCC_17_DN")
	)
	(arc
		(start 93.896942 -3.73634)
		(mid 94.084268 -3.284094)
		(end 94.536514 -3.096768)
		(width 0.12446)
		(layer "B.Cu")
		(net "PHY_DPB_TO_SCC_17_DN")
	)
	(segment
		(start 99.658932 -35.972242)
		(end 98.235008 -29.27223)
		(width 0.12446)
		(layer "B.Cu")
		(net "PHY_DPB_TO_SCC_16_DP")
	)
	(segment
		(start 97.13722 -43.87342)
		(end 97.13722 -43.373802)
		(width 0.12446)
		(layer "B.Cu")
		(net "PHY_DPB_TO_SCC_16_DP")
	)
	(segment
		(start 97.2058 -43.942)
		(end 97.13722 -43.87342)
		(width 0.12446)
		(layer "B.Cu")
		(net "PHY_DPB_TO_SCC_16_DP")
	)
	(segment
		(start 92.503244 -13.28674)
		(end 92.503244 -4.93649)
		(width 0.12446)
		(layer "B.Cu")
		(net "PHY_DPB_TO_SCC_16_DP")
	)
	(segment
		(start 96.813116 -22.582378)
		(end 96.609662 -22.268688)
		(width 0.12446)
		(layer "B.Cu")
		(net "PHY_DPB_TO_SCC_16_DP")
	)
	(segment
		(start 93.34246 -17.238726)
		(end 92.503244 -13.28674)
		(width 0.12446)
		(layer "B.Cu")
		(net "PHY_DPB_TO_SCC_16_DP")
	)
	(segment
		(start 95.209614 -20.11299)
		(end 95.288608 -19.740626)
		(width 0.12446)
		(layer "B.Cu")
		(net "PHY_DPB_TO_SCC_16_DP")
	)
	(segment
		(start 95.785432 -20.50542)
		(end 95.412814 -20.426172)
		(width 0.12446)
		(layer "B.Cu")
		(net "PHY_DPB_TO_SCC_16_DP")
	)
	(segment
		(start 94.71279 -19.34845)
		(end 93.34246 -17.238726)
		(width 0.12446)
		(layer "B.Cu")
		(net "PHY_DPB_TO_SCC_16_DP")
	)
	(segment
		(start 96.68891 -21.896324)
		(end 96.485456 -21.583142)
		(width 0.12446)
		(layer "B.Cu")
		(net "PHY_DPB_TO_SCC_16_DP")
	)
	(segment
		(start 96.485456 -21.583142)
		(end 96.113092 -21.504148)
		(width 0.12446)
		(layer "B.Cu")
		(net "PHY_DPB_TO_SCC_16_DP")
	)
	(segment
		(start 96.609662 -22.268688)
		(end 96.68891 -21.896324)
		(width 0.12446)
		(layer "B.Cu")
		(net "PHY_DPB_TO_SCC_16_DP")
	)
	(segment
		(start 95.909638 -21.190966)
		(end 95.988632 -20.818602)
		(width 0.12446)
		(layer "B.Cu")
		(net "PHY_DPB_TO_SCC_16_DP")
	)
	(segment
		(start 93.199966 -4.822444)
		(end 93.199966 -5.200142)
		(width 0.12446)
		(layer "B.Cu")
		(net "PHY_DPB_TO_SCC_16_DP")
	)
	(segment
		(start 95.085154 -19.427444)
		(end 94.71279 -19.34845)
		(width 0.12446)
		(layer "B.Cu")
		(net "PHY_DPB_TO_SCC_16_DP")
	)
	(segment
		(start 92.736416 -4.703318)
		(end 93.08084 -4.703318)
		(width 0.12446)
		(layer "B.Cu")
		(net "PHY_DPB_TO_SCC_16_DP")
	)
	(segment
		(start 98.235008 -29.27223)
		(end 96.813116 -22.582378)
		(width 0.12446)
		(layer "B.Cu")
		(net "PHY_DPB_TO_SCC_16_DP")
	)
	(segment
		(start 97.13722 -43.373802)
		(end 98.547428 -41.202102)
		(width 0.12446)
		(layer "B.Cu")
		(net "PHY_DPB_TO_SCC_16_DP")
	)
	(segment
		(start 95.412814 -20.426172)
		(end 95.209614 -20.11299)
		(width 0.12446)
		(layer "B.Cu")
		(net "PHY_DPB_TO_SCC_16_DP")
	)
	(segment
		(start 96.113092 -21.504148)
		(end 95.909638 -21.190966)
		(width 0.12446)
		(layer "B.Cu")
		(net "PHY_DPB_TO_SCC_16_DP")
	)
	(segment
		(start 95.988632 -20.818602)
		(end 95.785432 -20.50542)
		(width 0.12446)
		(layer "B.Cu")
		(net "PHY_DPB_TO_SCC_16_DP")
	)
	(segment
		(start 98.547428 -41.202102)
		(end 99.658932 -35.972242)
		(width 0.12446)
		(layer "B.Cu")
		(net "PHY_DPB_TO_SCC_16_DP")
	)
	(segment
		(start 95.288608 -19.740626)
		(end 95.085154 -19.427444)
		(width 0.12446)
		(layer "B.Cu")
		(net "PHY_DPB_TO_SCC_16_DP")
	)
	(arc
		(start 93.08084 -4.703318)
		(mid 93.126496 -4.712435)
		(end 93.165168 -4.73837)
		(width 0.12446)
		(layer "B.Cu")
		(net "PHY_DPB_TO_SCC_16_DP")
	)
	(arc
		(start 92.503244 -4.93649)
		(mid 92.571538 -4.771612)
		(end 92.736416 -4.703318)
		(width 0.12446)
		(layer "B.Cu")
		(net "PHY_DPB_TO_SCC_16_DP")
	)
	(arc
		(start 93.165168 -4.73837)
		(mid 93.190942 -4.776943)
		(end 93.199966 -4.822444)
		(width 0.12446)
		(layer "B.Cu")
		(net "PHY_DPB_TO_SCC_16_DP")
	)
	(segment
		(start 96.73082 -43.85818)
		(end 96.73082 -43.253406)
		(width 0.12446)
		(layer "B.Cu")
		(net "PHY_DPB_TO_SCC_16_DN")
	)
	(segment
		(start 92.736416 -4.296918)
		(end 93.08084 -4.296918)
		(width 0.12446)
		(layer "B.Cu")
		(net "PHY_DPB_TO_SCC_16_DN")
	)
	(segment
		(start 96.647 -43.942)
		(end 96.73082 -43.85818)
		(width 0.12446)
		(layer "B.Cu")
		(net "PHY_DPB_TO_SCC_16_DN")
	)
	(segment
		(start 99.243388 -35.972242)
		(end 96.4311 -22.74062)
		(width 0.12446)
		(layer "B.Cu")
		(net "PHY_DPB_TO_SCC_16_DN")
	)
	(segment
		(start 98.165412 -41.04386)
		(end 99.243388 -35.972242)
		(width 0.12446)
		(layer "B.Cu")
		(net "PHY_DPB_TO_SCC_16_DN")
	)
	(segment
		(start 96.4311 -22.74062)
		(end 92.960444 -17.396968)
		(width 0.12446)
		(layer "B.Cu")
		(net "PHY_DPB_TO_SCC_16_DN")
	)
	(segment
		(start 92.960444 -17.396968)
		(end 92.096844 -13.329412)
		(width 0.12446)
		(layer "B.Cu")
		(net "PHY_DPB_TO_SCC_16_DN")
	)
	(segment
		(start 93.199966 -4.177792)
		(end 93.199966 -3.800094)
		(width 0.12446)
		(layer "B.Cu")
		(net "PHY_DPB_TO_SCC_16_DN")
	)
	(segment
		(start 96.73082 -43.253406)
		(end 98.165412 -41.04386)
		(width 0.12446)
		(layer "B.Cu")
		(net "PHY_DPB_TO_SCC_16_DN")
	)
	(segment
		(start 92.096844 -13.329412)
		(end 92.096844 -4.93649)
		(width 0.12446)
		(layer "B.Cu")
		(net "PHY_DPB_TO_SCC_16_DN")
	)
	(arc
		(start 92.096844 -4.93649)
		(mid 92.28417 -4.484244)
		(end 92.736416 -4.296918)
		(width 0.12446)
		(layer "B.Cu")
		(net "PHY_DPB_TO_SCC_16_DN")
	)
	(arc
		(start 93.08084 -4.296918)
		(mid 93.126496 -4.287801)
		(end 93.165168 -4.261866)
		(width 0.12446)
		(layer "B.Cu")
		(net "PHY_DPB_TO_SCC_16_DN")
	)
	(arc
		(start 93.165168 -4.261866)
		(mid 93.190942 -4.223293)
		(end 93.199966 -4.177792)
		(width 0.12446)
		(layer "B.Cu")
		(net "PHY_DPB_TO_SCC_16_DN")
	)
	(segment
		(start 136.139428 -64.47663)
		(end 136.764776 -63.51397)
		(width 0.12446)
		(layer "B.Cu")
		(net "PHY_DPB_TO_SCC_1_DP")
	)
	(segment
		(start 138.396472 -20.381214)
		(end 137.503408 -16.1798)
		(width 0.12446)
		(layer "B.Cu")
		(net "PHY_DPB_TO_SCC_1_DP")
	)
	(segment
		(start 135.637524 -33.360106)
		(end 138.396472 -20.381214)
		(width 0.12446)
		(layer "B.Cu")
		(net "PHY_DPB_TO_SCC_1_DP")
	)
	(segment
		(start 137.503408 -16.1798)
		(end 137.503408 -3.73634)
		(width 0.12446)
		(layer "B.Cu")
		(net "PHY_DPB_TO_SCC_1_DP")
	)
	(segment
		(start 137.887202 -48.717708)
		(end 138.044174 -47.978822)
		(width 0.12446)
		(layer "B.Cu")
		(net "PHY_DPB_TO_SCC_1_DP")
	)
	(segment
		(start 137.729976 -49.456594)
		(end 137.887202 -48.717708)
		(width 0.12446)
		(layer "B.Cu")
		(net "PHY_DPB_TO_SCC_1_DP")
	)
	(segment
		(start 135.081264 -64.994536)
		(end 135.621776 -64.994536)
		(width 0.12446)
		(layer "B.Cu")
		(net "PHY_DPB_TO_SCC_1_DP")
	)
	(segment
		(start 134.772654 -65.066418)
		(end 135.009382 -65.066418)
		(width 0.12446)
		(layer "B.Cu")
		(net "PHY_DPB_TO_SCC_1_DP")
	)
	(segment
		(start 137.73658 -3.503168)
		(end 138.081004 -3.503168)
		(width 0.12446)
		(layer "B.Cu")
		(net "PHY_DPB_TO_SCC_1_DP")
	)
	(segment
		(start 138.39444 -46.331886)
		(end 135.637524 -33.360106)
		(width 0.12446)
		(layer "B.Cu")
		(net "PHY_DPB_TO_SCC_1_DP")
	)
	(segment
		(start 138.044174 -47.978822)
		(end 138.39444 -46.331886)
		(width 0.12446)
		(layer "B.Cu")
		(net "PHY_DPB_TO_SCC_1_DP")
	)
	(segment
		(start 136.764776 -63.51397)
		(end 138.74115 -54.212236)
		(width 0.12446)
		(layer "B.Cu")
		(net "PHY_DPB_TO_SCC_1_DP")
	)
	(segment
		(start 138.74115 -54.212236)
		(end 137.729976 -49.456594)
		(width 0.12446)
		(layer "B.Cu")
		(net "PHY_DPB_TO_SCC_1_DP")
	)
	(segment
		(start 138.20013 -3.622294)
		(end 138.20013 -3.999992)
		(width 0.12446)
		(layer "B.Cu")
		(net "PHY_DPB_TO_SCC_1_DP")
	)
	(segment
		(start 135.009382 -65.066418)
		(end 135.081264 -64.994536)
		(width 0.12446)
		(layer "B.Cu")
		(net "PHY_DPB_TO_SCC_1_DP")
	)
	(segment
		(start 135.621776 -64.994536)
		(end 136.139428 -64.47663)
		(width 0.12446)
		(layer "B.Cu")
		(net "PHY_DPB_TO_SCC_1_DP")
	)
	(arc
		(start 137.503408 -3.73634)
		(mid 137.571702 -3.571462)
		(end 137.73658 -3.503168)
		(width 0.12446)
		(layer "B.Cu")
		(net "PHY_DPB_TO_SCC_1_DP")
	)
	(arc
		(start 138.081004 -3.503168)
		(mid 138.12666 -3.512285)
		(end 138.165332 -3.53822)
		(width 0.12446)
		(layer "B.Cu")
		(net "PHY_DPB_TO_SCC_1_DP")
	)
	(arc
		(start 138.165332 -3.53822)
		(mid 138.191106 -3.576793)
		(end 138.20013 -3.622294)
		(width 0.12446)
		(layer "B.Cu")
		(net "PHY_DPB_TO_SCC_1_DP")
	)
	(segment
		(start 136.38276 -63.355728)
		(end 138.325606 -54.212236)
		(width 0.12446)
		(layer "B.Cu")
		(net "PHY_DPB_TO_SCC_1_DN")
	)
	(segment
		(start 137.097008 -16.222726)
		(end 137.097008 -3.73634)
		(width 0.12446)
		(layer "B.Cu")
		(net "PHY_DPB_TO_SCC_1_DN")
	)
	(segment
		(start 138.325606 -54.212236)
		(end 137.314432 -49.456594)
		(width 0.12446)
		(layer "B.Cu")
		(net "PHY_DPB_TO_SCC_1_DN")
	)
	(segment
		(start 135.45312 -64.588136)
		(end 135.821674 -64.219328)
		(width 0.12446)
		(layer "B.Cu")
		(net "PHY_DPB_TO_SCC_1_DN")
	)
	(segment
		(start 137.314432 -49.456594)
		(end 137.978896 -46.331886)
		(width 0.12446)
		(layer "B.Cu")
		(net "PHY_DPB_TO_SCC_1_DN")
	)
	(segment
		(start 135.073136 -64.588136)
		(end 135.45312 -64.588136)
		(width 0.12446)
		(layer "B.Cu")
		(net "PHY_DPB_TO_SCC_1_DN")
	)
	(segment
		(start 135.821674 -64.219328)
		(end 136.38276 -63.355728)
		(width 0.12446)
		(layer "B.Cu")
		(net "PHY_DPB_TO_SCC_1_DN")
	)
	(segment
		(start 138.20013 -2.977642)
		(end 138.20013 -2.600198)
		(width 0.12446)
		(layer "B.Cu")
		(net "PHY_DPB_TO_SCC_1_DN")
	)
	(segment
		(start 135.22198 -33.360106)
		(end 137.980928 -20.381214)
		(width 0.12446)
		(layer "B.Cu")
		(net "PHY_DPB_TO_SCC_1_DN")
	)
	(segment
		(start 137.73658 -3.096768)
		(end 138.081004 -3.096768)
		(width 0.12446)
		(layer "B.Cu")
		(net "PHY_DPB_TO_SCC_1_DN")
	)
	(segment
		(start 134.772654 -64.507618)
		(end 134.992618 -64.507618)
		(width 0.12446)
		(layer "B.Cu")
		(net "PHY_DPB_TO_SCC_1_DN")
	)
	(segment
		(start 134.992618 -64.507618)
		(end 135.073136 -64.588136)
		(width 0.12446)
		(layer "B.Cu")
		(net "PHY_DPB_TO_SCC_1_DN")
	)
	(segment
		(start 137.980928 -20.381214)
		(end 137.097008 -16.222726)
		(width 0.12446)
		(layer "B.Cu")
		(net "PHY_DPB_TO_SCC_1_DN")
	)
	(segment
		(start 137.978896 -46.331886)
		(end 135.22198 -33.360106)
		(width 0.12446)
		(layer "B.Cu")
		(net "PHY_DPB_TO_SCC_1_DN")
	)
	(arc
		(start 137.097008 -3.73634)
		(mid 137.284334 -3.284094)
		(end 137.73658 -3.096768)
		(width 0.12446)
		(layer "B.Cu")
		(net "PHY_DPB_TO_SCC_1_DN")
	)
	(arc
		(start 138.081004 -3.096768)
		(mid 138.12666 -3.087651)
		(end 138.165332 -3.061716)
		(width 0.12446)
		(layer "B.Cu")
		(net "PHY_DPB_TO_SCC_1_DN")
	)
	(arc
		(start 138.165332 -3.061716)
		(mid 138.191106 -3.023143)
		(end 138.20013 -2.977642)
		(width 0.12446)
		(layer "B.Cu")
		(net "PHY_DPB_TO_SCC_1_DN")
	)
	(segment
		(start 135.936482 -4.703318)
		(end 136.280906 -4.703318)
		(width 0.12446)
		(layer "B.Cu")
		(net "PHY_DPB_TO_SCC_0_DP")
	)
	(segment
		(start 137.239502 -53.26507)
		(end 136.920224 -53.057552)
		(width 0.12446)
		(layer "B.Cu")
		(net "PHY_DPB_TO_SCC_0_DP")
	)
	(segment
		(start 136.972548 -52.00777)
		(end 136.65327 -51.800252)
		(width 0.12446)
		(layer "B.Cu")
		(net "PHY_DPB_TO_SCC_0_DP")
	)
	(segment
		(start 137.316972 -53.630322)
		(end 137.239502 -53.26507)
		(width 0.12446)
		(layer "B.Cu")
		(net "PHY_DPB_TO_SCC_0_DP")
	)
	(segment
		(start 137.107676 -46.522386)
		(end 134.330694 -33.458658)
		(width 0.12446)
		(layer "B.Cu")
		(net "PHY_DPB_TO_SCC_0_DP")
	)
	(segment
		(start 135.70331 -17.179544)
		(end 135.70331 -4.93649)
		(width 0.12446)
		(layer "B.Cu")
		(net "PHY_DPB_TO_SCC_0_DP")
	)
	(segment
		(start 136.319768 -50.230278)
		(end 137.107676 -46.522386)
		(width 0.12446)
		(layer "B.Cu")
		(net "PHY_DPB_TO_SCC_0_DP")
	)
	(segment
		(start 136.746996 -22.091396)
		(end 135.70331 -17.179544)
		(width 0.12446)
		(layer "B.Cu")
		(net "PHY_DPB_TO_SCC_0_DP")
	)
	(segment
		(start 136.386316 -50.542952)
		(end 136.319768 -50.230278)
		(width 0.12446)
		(layer "B.Cu")
		(net "PHY_DPB_TO_SCC_0_DP")
	)
	(segment
		(start 136.783064 -51.115722)
		(end 136.705594 -50.75047)
		(width 0.12446)
		(layer "B.Cu")
		(net "PHY_DPB_TO_SCC_0_DP")
	)
	(segment
		(start 137.329418 -54.986174)
		(end 137.109708 -53.9496)
		(width 0.12446)
		(layer "B.Cu")
		(net "PHY_DPB_TO_SCC_0_DP")
	)
	(segment
		(start 137.109708 -53.9496)
		(end 137.316972 -53.630322)
		(width 0.12446)
		(layer "B.Cu")
		(net "PHY_DPB_TO_SCC_0_DP")
	)
	(segment
		(start 136.920224 -53.057552)
		(end 136.842754 -52.6923)
		(width 0.12446)
		(layer "B.Cu")
		(net "PHY_DPB_TO_SCC_0_DP")
	)
	(segment
		(start 136.65327 -51.800252)
		(end 136.5758 -51.435)
		(width 0.12446)
		(layer "B.Cu")
		(net "PHY_DPB_TO_SCC_0_DP")
	)
	(segment
		(start 136.5758 -51.435)
		(end 136.783064 -51.115722)
		(width 0.12446)
		(layer "B.Cu")
		(net "PHY_DPB_TO_SCC_0_DP")
	)
	(segment
		(start 135.66648 -61.025278)
		(end 135.649462 -61.00826)
		(width 0.12446)
		(layer "B.Cu")
		(net "PHY_DPB_TO_SCC_0_DP")
	)
	(segment
		(start 136.705594 -50.75047)
		(end 136.386316 -50.542952)
		(width 0.12446)
		(layer "B.Cu")
		(net "PHY_DPB_TO_SCC_0_DP")
	)
	(segment
		(start 136.842754 -52.6923)
		(end 137.050018 -52.373022)
		(width 0.12446)
		(layer "B.Cu")
		(net "PHY_DPB_TO_SCC_0_DP")
	)
	(segment
		(start 136.516364 -58.807096)
		(end 137.329418 -54.986174)
		(width 0.12446)
		(layer "B.Cu")
		(net "PHY_DPB_TO_SCC_0_DP")
	)
	(segment
		(start 137.050018 -52.373022)
		(end 136.972548 -52.00777)
		(width 0.12446)
		(layer "B.Cu")
		(net "PHY_DPB_TO_SCC_0_DP")
	)
	(segment
		(start 134.330694 -33.458658)
		(end 136.746996 -22.091396)
		(width 0.12446)
		(layer "B.Cu")
		(net "PHY_DPB_TO_SCC_0_DP")
	)
	(segment
		(start 136.400032 -4.822444)
		(end 136.400032 -5.200142)
		(width 0.12446)
		(layer "B.Cu")
		(net "PHY_DPB_TO_SCC_0_DP")
	)
	(segment
		(start 135.649462 -61.00826)
		(end 135.649462 -59.673998)
		(width 0.12446)
		(layer "B.Cu")
		(net "PHY_DPB_TO_SCC_0_DP")
	)
	(segment
		(start 135.649462 -59.673998)
		(end 136.516364 -58.807096)
		(width 0.12446)
		(layer "B.Cu")
		(net "PHY_DPB_TO_SCC_0_DP")
	)
	(arc
		(start 135.70331 -4.93649)
		(mid 135.771604 -4.771612)
		(end 135.936482 -4.703318)
		(width 0.12446)
		(layer "B.Cu")
		(net "PHY_DPB_TO_SCC_0_DP")
	)
	(arc
		(start 136.280906 -4.703318)
		(mid 136.326562 -4.712435)
		(end 136.365234 -4.73837)
		(width 0.12446)
		(layer "B.Cu")
		(net "PHY_DPB_TO_SCC_0_DP")
	)
	(arc
		(start 136.365234 -4.73837)
		(mid 136.391008 -4.776943)
		(end 136.400032 -4.822444)
		(width 0.12446)
		(layer "B.Cu")
		(net "PHY_DPB_TO_SCC_0_DP")
	)
	(segment
		(start 136.692132 -46.522386)
		(end 133.91515 -33.458658)
		(width 0.12446)
		(layer "B.Cu")
		(net "PHY_DPB_TO_SCC_0_DN")
	)
	(segment
		(start 135.10768 -61.025278)
		(end 135.243062 -60.889896)
		(width 0.12446)
		(layer "B.Cu")
		(net "PHY_DPB_TO_SCC_0_DN")
	)
	(segment
		(start 136.143746 -58.604658)
		(end 136.913874 -54.986174)
		(width 0.12446)
		(layer "B.Cu")
		(net "PHY_DPB_TO_SCC_0_DN")
	)
	(segment
		(start 135.29691 -17.22247)
		(end 135.29691 -4.93649)
		(width 0.12446)
		(layer "B.Cu")
		(net "PHY_DPB_TO_SCC_0_DN")
	)
	(segment
		(start 136.400032 -4.177792)
		(end 136.400032 -3.800094)
		(width 0.12446)
		(layer "B.Cu")
		(net "PHY_DPB_TO_SCC_0_DN")
	)
	(segment
		(start 133.91515 -33.458658)
		(end 136.331452 -22.091396)
		(width 0.12446)
		(layer "B.Cu")
		(net "PHY_DPB_TO_SCC_0_DN")
	)
	(segment
		(start 135.243062 -59.505342)
		(end 136.143746 -58.604658)
		(width 0.12446)
		(layer "B.Cu")
		(net "PHY_DPB_TO_SCC_0_DN")
	)
	(segment
		(start 136.913874 -54.986174)
		(end 135.904224 -50.230278)
		(width 0.12446)
		(layer "B.Cu")
		(net "PHY_DPB_TO_SCC_0_DN")
	)
	(segment
		(start 136.331452 -22.091396)
		(end 135.29691 -17.22247)
		(width 0.12446)
		(layer "B.Cu")
		(net "PHY_DPB_TO_SCC_0_DN")
	)
	(segment
		(start 135.936482 -4.296918)
		(end 136.280906 -4.296918)
		(width 0.12446)
		(layer "B.Cu")
		(net "PHY_DPB_TO_SCC_0_DN")
	)
	(segment
		(start 135.904224 -50.230278)
		(end 136.692132 -46.522386)
		(width 0.12446)
		(layer "B.Cu")
		(net "PHY_DPB_TO_SCC_0_DN")
	)
	(segment
		(start 135.243062 -60.889896)
		(end 135.243062 -59.505342)
		(width 0.12446)
		(layer "B.Cu")
		(net "PHY_DPB_TO_SCC_0_DN")
	)
	(arc
		(start 136.365234 -4.261866)
		(mid 136.391008 -4.223293)
		(end 136.400032 -4.177792)
		(width 0.12446)
		(layer "B.Cu")
		(net "PHY_DPB_TO_SCC_0_DN")
	)
	(arc
		(start 136.280906 -4.296918)
		(mid 136.326562 -4.287801)
		(end 136.365234 -4.261866)
		(width 0.12446)
		(layer "B.Cu")
		(net "PHY_DPB_TO_SCC_0_DN")
	)
	(arc
		(start 135.29691 -4.93649)
		(mid 135.484236 -4.484244)
		(end 135.936482 -4.296918)
		(width 0.12446)
		(layer "B.Cu")
		(net "PHY_DPB_TO_SCC_0_DN")
	)
	(segment
		(start 71.4121 -84.328)
		(end 72.060054 -84.328)
		(width 0.127)
		(layer "F.Cu")
		(net "PCIE_COMP_TO_SCC_RST_0")
	)
	(segment
		(start 72.4916 -83.005168)
		(end 72.4916 -81.4959)
		(width 0.127)
		(layer "F.Cu")
		(net "PCIE_COMP_TO_SCC_RST_0")
	)
	(segment
		(start 72.4916 -83.896454)
		(end 72.4916 -83.005168)
		(width 0.127)
		(layer "F.Cu")
		(net "PCIE_COMP_TO_SCC_RST_0")
	)
	(segment
		(start 72.060054 -84.328)
		(end 72.4916 -83.896454)
		(width 0.127)
		(layer "F.Cu")
		(net "PCIE_COMP_TO_SCC_RST_0")
	)
	(via
		(at 72.4916 -83.005168)
		(size 0.6604)
		(drill 0.3302)
		(layers "F.Cu" "B.Cu")
		(net "PCIE_COMP_TO_SCC_RST_0")
	)
	(via
		(at 193.94424 -15.19428)
		(size 0.508)
		(drill 0.254)
		(layers "F.Cu" "B.Cu")
		(net "PCIE_COMP_TO_SCC_RST_0")
	)
	(via
		(at 71.4121 -84.328)
		(size 0.508)
		(drill 0.254)
		(layers "F.Cu" "B.Cu")
		(net "PCIE_COMP_TO_SCC_RST_0")
	)
	(segment
		(start 193.94424 -15.19428)
		(end 196.37121 -17.62125)
		(width 0.127)
		(layer "B.Cu")
		(net "PCIE_COMP_TO_SCC_RST_0")
	)
	(segment
		(start 200.35012 -17.62125)
		(end 203.0095 -20.28063)
		(width 0.127)
		(layer "B.Cu")
		(net "PCIE_COMP_TO_SCC_RST_0")
	)
	(segment
		(start 196.37121 -17.62125)
		(end 200.35012 -17.62125)
		(width 0.127)
		(layer "B.Cu")
		(net "PCIE_COMP_TO_SCC_RST_0")
	)
	(segment
		(start 203.0095 -20.28063)
		(end 203.0095 -20.92325)
		(width 0.127)
		(layer "B.Cu")
		(net "PCIE_COMP_TO_SCC_RST_0")
	)
	(segment
		(start 71.4121 -84.328)
		(end 70.759066 -83.674966)
		(width 0.127)
		(layer "In2.Cu")
		(net "PCIE_COMP_TO_SCC_RST_0")
	)
	(segment
		(start 74.743818 -70.50024)
		(end 76.598526 -70.50024)
		(width 0.127)
		(layer "In2.Cu")
		(net "PCIE_COMP_TO_SCC_RST_0")
	)
	(segment
		(start 122.732038 -41.020746)
		(end 139.389104 -24.36368)
		(width 0.127)
		(layer "In2.Cu")
		(net "PCIE_COMP_TO_SCC_RST_0")
	)
	(segment
		(start 151.564594 -24.36368)
		(end 156.550868 -19.377406)
		(width 0.127)
		(layer "In2.Cu")
		(net "PCIE_COMP_TO_SCC_RST_0")
	)
	(segment
		(start 76.598526 -70.50024)
		(end 80.05572 -67.043046)
		(width 0.127)
		(layer "In2.Cu")
		(net "PCIE_COMP_TO_SCC_RST_0")
	)
	(segment
		(start 83.890866 -63.403734)
		(end 87.66556 -59.62904)
		(width 0.127)
		(layer "In2.Cu")
		(net "PCIE_COMP_TO_SCC_RST_0")
	)
	(segment
		(start 80.663288 -67.043046)
		(end 81.745074 -65.96126)
		(width 0.127)
		(layer "In2.Cu")
		(net "PCIE_COMP_TO_SCC_RST_0")
	)
	(segment
		(start 82.020156 -65.321942)
		(end 82.879692 -65.321942)
		(width 0.127)
		(layer "In2.Cu")
		(net "PCIE_COMP_TO_SCC_RST_0")
	)
	(segment
		(start 93.576394 -53.48986)
		(end 99.695254 -47.371)
		(width 0.127)
		(layer "In2.Cu")
		(net "PCIE_COMP_TO_SCC_RST_0")
	)
	(segment
		(start 192.80886 -15.19428)
		(end 193.94424 -15.19428)
		(width 0.127)
		(layer "In2.Cu")
		(net "PCIE_COMP_TO_SCC_RST_0")
	)
	(segment
		(start 189.682374 -20.63623)
		(end 193.94424 -16.374364)
		(width 0.127)
		(layer "In2.Cu")
		(net "PCIE_COMP_TO_SCC_RST_0")
	)
	(segment
		(start 81.745074 -65.96126)
		(end 81.745074 -65.597024)
		(width 0.127)
		(layer "In2.Cu")
		(net "PCIE_COMP_TO_SCC_RST_0")
	)
	(segment
		(start 156.550868 -19.377406)
		(end 183.623966 -19.377406)
		(width 0.127)
		(layer "In2.Cu")
		(net "PCIE_COMP_TO_SCC_RST_0")
	)
	(segment
		(start 88.937084 -55.847996)
		(end 91.29522 -53.48986)
		(width 0.127)
		(layer "In2.Cu")
		(net "PCIE_COMP_TO_SCC_RST_0")
	)
	(segment
		(start 81.745074 -65.597024)
		(end 82.020156 -65.321942)
		(width 0.127)
		(layer "In2.Cu")
		(net "PCIE_COMP_TO_SCC_RST_0")
	)
	(segment
		(start 102.710234 -47.371)
		(end 109.060488 -41.020746)
		(width 0.127)
		(layer "In2.Cu")
		(net "PCIE_COMP_TO_SCC_RST_0")
	)
	(segment
		(start 87.66556 -59.62904)
		(end 87.66556 -57.978294)
		(width 0.127)
		(layer "In2.Cu")
		(net "PCIE_COMP_TO_SCC_RST_0")
	)
	(segment
		(start 88.937084 -56.70677)
		(end 88.937084 -55.847996)
		(width 0.127)
		(layer "In2.Cu")
		(net "PCIE_COMP_TO_SCC_RST_0")
	)
	(segment
		(start 80.05572 -67.043046)
		(end 80.663288 -67.043046)
		(width 0.127)
		(layer "In2.Cu")
		(net "PCIE_COMP_TO_SCC_RST_0")
	)
	(segment
		(start 109.060488 -41.020746)
		(end 122.732038 -41.020746)
		(width 0.127)
		(layer "In2.Cu")
		(net "PCIE_COMP_TO_SCC_RST_0")
	)
	(segment
		(start 139.389104 -24.36368)
		(end 151.564594 -24.36368)
		(width 0.127)
		(layer "In2.Cu")
		(net "PCIE_COMP_TO_SCC_RST_0")
	)
	(segment
		(start 193.94424 -16.374364)
		(end 193.94424 -15.19428)
		(width 0.127)
		(layer "In2.Cu")
		(net "PCIE_COMP_TO_SCC_RST_0")
	)
	(segment
		(start 70.759066 -83.674966)
		(end 70.759066 -74.484992)
		(width 0.127)
		(layer "In2.Cu")
		(net "PCIE_COMP_TO_SCC_RST_0")
	)
	(segment
		(start 87.66556 -57.978294)
		(end 88.937084 -56.70677)
		(width 0.127)
		(layer "In2.Cu")
		(net "PCIE_COMP_TO_SCC_RST_0")
	)
	(segment
		(start 99.695254 -47.371)
		(end 102.710234 -47.371)
		(width 0.127)
		(layer "In2.Cu")
		(net "PCIE_COMP_TO_SCC_RST_0")
	)
	(segment
		(start 184.88279 -20.63623)
		(end 189.682374 -20.63623)
		(width 0.127)
		(layer "In2.Cu")
		(net "PCIE_COMP_TO_SCC_RST_0")
	)
	(segment
		(start 190.799974 -7.400036)
		(end 191.684402 -8.284464)
		(width 0.127)
		(layer "In2.Cu")
		(net "PCIE_COMP_TO_SCC_RST_0")
	)
	(segment
		(start 191.684402 -14.069822)
		(end 192.80886 -15.19428)
		(width 0.127)
		(layer "In2.Cu")
		(net "PCIE_COMP_TO_SCC_RST_0")
	)
	(segment
		(start 70.759066 -74.484992)
		(end 74.743818 -70.50024)
		(width 0.127)
		(layer "In2.Cu")
		(net "PCIE_COMP_TO_SCC_RST_0")
	)
	(segment
		(start 183.623966 -19.377406)
		(end 184.88279 -20.63623)
		(width 0.127)
		(layer "In2.Cu")
		(net "PCIE_COMP_TO_SCC_RST_0")
	)
	(segment
		(start 91.29522 -53.48986)
		(end 93.576394 -53.48986)
		(width 0.127)
		(layer "In2.Cu")
		(net "PCIE_COMP_TO_SCC_RST_0")
	)
	(segment
		(start 83.890866 -64.310768)
		(end 83.890866 -63.403734)
		(width 0.127)
		(layer "In2.Cu")
		(net "PCIE_COMP_TO_SCC_RST_0")
	)
	(segment
		(start 191.684402 -8.284464)
		(end 191.684402 -14.069822)
		(width 0.127)
		(layer "In2.Cu")
		(net "PCIE_COMP_TO_SCC_RST_0")
	)
	(segment
		(start 82.879692 -65.321942)
		(end 83.890866 -64.310768)
		(width 0.127)
		(layer "In2.Cu")
		(net "PCIE_COMP_TO_SCC_RST_0")
	)
	(segment
		(start 168.562528 -19.426682)
		(end 163.829746 -19.426682)
		(width 0.14605)
		(layer "F.Cu")
		(net "PCIE_COMP_TO_SCC_CLK_0_DP")
	)
	(segment
		(start 179.999894 -7.400036)
		(end 179.999894 -7.768336)
		(width 0.14605)
		(layer "F.Cu")
		(net "PCIE_COMP_TO_SCC_CLK_0_DP")
	)
	(segment
		(start 163.829746 -19.426682)
		(end 162.77082 -20.485608)
		(width 0.14605)
		(layer "F.Cu")
		(net "PCIE_COMP_TO_SCC_CLK_0_DP")
	)
	(segment
		(start 170.75785 -17.23136)
		(end 168.562528 -19.426682)
		(width 0.14605)
		(layer "F.Cu")
		(net "PCIE_COMP_TO_SCC_CLK_0_DP")
	)
	(segment
		(start 162.77082 -21.228812)
		(end 162.405568 -21.594064)
		(width 0.14605)
		(layer "F.Cu")
		(net "PCIE_COMP_TO_SCC_CLK_0_DP")
	)
	(segment
		(start 178.354482 -7.944358)
		(end 170.75785 -15.54099)
		(width 0.14605)
		(layer "F.Cu")
		(net "PCIE_COMP_TO_SCC_CLK_0_DP")
	)
	(segment
		(start 179.823872 -7.944358)
		(end 178.354482 -7.944358)
		(width 0.14605)
		(layer "F.Cu")
		(net "PCIE_COMP_TO_SCC_CLK_0_DP")
	)
	(segment
		(start 162.405568 -21.594064)
		(end 162.405568 -22.018244)
		(width 0.14605)
		(layer "F.Cu")
		(net "PCIE_COMP_TO_SCC_CLK_0_DP")
	)
	(segment
		(start 162.77082 -20.485608)
		(end 162.77082 -21.228812)
		(width 0.14605)
		(layer "F.Cu")
		(net "PCIE_COMP_TO_SCC_CLK_0_DP")
	)
	(segment
		(start 170.75785 -15.54099)
		(end 170.75785 -17.23136)
		(width 0.14605)
		(layer "F.Cu")
		(net "PCIE_COMP_TO_SCC_CLK_0_DP")
	)
	(arc
		(start 179.999894 -7.768336)
		(mid 179.948338 -7.892802)
		(end 179.823872 -7.944358)
		(width 0.14605)
		(layer "F.Cu")
		(net "PCIE_COMP_TO_SCC_CLK_0_DP")
	)
	(segment
		(start 172.76953 -14.184884)
		(end 172.554138 -14.184884)
		(width 0.14605)
		(layer "F.Cu")
		(net "PCIE_COMP_TO_SCC_CLK_0_DN")
	)
	(segment
		(start 171.069 -15.670022)
		(end 171.069 -17.360392)
		(width 0.14605)
		(layer "F.Cu")
		(net "PCIE_COMP_TO_SCC_CLK_0_DN")
	)
	(segment
		(start 174.439834 -12.51458)
		(end 174.224442 -12.51458)
		(width 0.14605)
		(layer "F.Cu")
		(net "PCIE_COMP_TO_SCC_CLK_0_DN")
	)
	(segment
		(start 163.08197 -21.228812)
		(end 163.446968 -21.59381)
		(width 0.14605)
		(layer "F.Cu")
		(net "PCIE_COMP_TO_SCC_CLK_0_DN")
	)
	(segment
		(start 171.718986 -15.020036)
		(end 171.069 -15.670022)
		(width 0.14605)
		(layer "F.Cu")
		(net "PCIE_COMP_TO_SCC_CLK_0_DN")
	)
	(segment
		(start 179.823618 -8.255508)
		(end 178.483514 -8.255508)
		(width 0.14605)
		(layer "F.Cu")
		(net "PCIE_COMP_TO_SCC_CLK_0_DN")
	)
	(segment
		(start 172.244258 -14.710156)
		(end 171.934378 -15.020036)
		(width 0.14605)
		(layer "F.Cu")
		(net "PCIE_COMP_TO_SCC_CLK_0_DN")
	)
	(segment
		(start 163.08197 -20.61464)
		(end 163.08197 -21.228812)
		(width 0.14605)
		(layer "F.Cu")
		(net "PCIE_COMP_TO_SCC_CLK_0_DN")
	)
	(segment
		(start 172.554138 -14.184884)
		(end 172.244258 -14.494764)
		(width 0.14605)
		(layer "F.Cu")
		(net "PCIE_COMP_TO_SCC_CLK_0_DN")
	)
	(segment
		(start 174.749714 -12.2047)
		(end 174.439834 -12.51458)
		(width 0.14605)
		(layer "F.Cu")
		(net "PCIE_COMP_TO_SCC_CLK_0_DN")
	)
	(segment
		(start 168.69156 -19.737832)
		(end 163.958778 -19.737832)
		(width 0.14605)
		(layer "F.Cu")
		(net "PCIE_COMP_TO_SCC_CLK_0_DN")
	)
	(segment
		(start 163.446968 -21.59381)
		(end 163.446968 -22.018244)
		(width 0.14605)
		(layer "F.Cu")
		(net "PCIE_COMP_TO_SCC_CLK_0_DN")
	)
	(segment
		(start 173.914562 -12.82446)
		(end 173.914562 -13.039852)
		(width 0.14605)
		(layer "F.Cu")
		(net "PCIE_COMP_TO_SCC_CLK_0_DN")
	)
	(segment
		(start 174.749714 -11.989308)
		(end 174.749714 -12.2047)
		(width 0.14605)
		(layer "F.Cu")
		(net "PCIE_COMP_TO_SCC_CLK_0_DN")
	)
	(segment
		(start 171.069 -17.360392)
		(end 168.69156 -19.737832)
		(width 0.14605)
		(layer "F.Cu")
		(net "PCIE_COMP_TO_SCC_CLK_0_DN")
	)
	(segment
		(start 173.07941 -13.875004)
		(end 172.76953 -14.184884)
		(width 0.14605)
		(layer "F.Cu")
		(net "PCIE_COMP_TO_SCC_CLK_0_DN")
	)
	(segment
		(start 171.934378 -15.020036)
		(end 171.718986 -15.020036)
		(width 0.14605)
		(layer "F.Cu")
		(net "PCIE_COMP_TO_SCC_CLK_0_DN")
	)
	(segment
		(start 173.914562 -13.039852)
		(end 173.604682 -13.349732)
		(width 0.14605)
		(layer "F.Cu")
		(net "PCIE_COMP_TO_SCC_CLK_0_DN")
	)
	(segment
		(start 179.999894 -8.800084)
		(end 179.999894 -8.431784)
		(width 0.14605)
		(layer "F.Cu")
		(net "PCIE_COMP_TO_SCC_CLK_0_DN")
	)
	(segment
		(start 163.958778 -19.737832)
		(end 163.08197 -20.61464)
		(width 0.14605)
		(layer "F.Cu")
		(net "PCIE_COMP_TO_SCC_CLK_0_DN")
	)
	(segment
		(start 173.07941 -13.659612)
		(end 173.07941 -13.875004)
		(width 0.14605)
		(layer "F.Cu")
		(net "PCIE_COMP_TO_SCC_CLK_0_DN")
	)
	(segment
		(start 172.244258 -14.494764)
		(end 172.244258 -14.710156)
		(width 0.14605)
		(layer "F.Cu")
		(net "PCIE_COMP_TO_SCC_CLK_0_DN")
	)
	(segment
		(start 178.483514 -8.255508)
		(end 174.749714 -11.989308)
		(width 0.14605)
		(layer "F.Cu")
		(net "PCIE_COMP_TO_SCC_CLK_0_DN")
	)
	(segment
		(start 174.224442 -12.51458)
		(end 173.914562 -12.82446)
		(width 0.14605)
		(layer "F.Cu")
		(net "PCIE_COMP_TO_SCC_CLK_0_DN")
	)
	(segment
		(start 173.38929 -13.349732)
		(end 173.07941 -13.659612)
		(width 0.14605)
		(layer "F.Cu")
		(net "PCIE_COMP_TO_SCC_CLK_0_DN")
	)
	(segment
		(start 173.604682 -13.349732)
		(end 173.38929 -13.349732)
		(width 0.14605)
		(layer "F.Cu")
		(net "PCIE_COMP_TO_SCC_CLK_0_DN")
	)
	(arc
		(start 179.999894 -8.431784)
		(mid 179.948264 -8.307138)
		(end 179.823618 -8.255508)
		(width 0.14605)
		(layer "F.Cu")
		(net "PCIE_COMP_TO_SCC_CLK_0_DN")
	)
	(segment
		(start 168.581324 -110.669324)
		(end 169.6466 -111.7346)
		(width 0.508)
		(layer "F.Cu")
		(net "P5V")
	)
	(segment
		(start 198.8312 -81.59242)
		(end 198.82358 -81.5848)
		(width 0.508)
		(layer "F.Cu")
		(net "P5V")
	)
	(segment
		(start 168.581324 -106.503724)
		(end 168.581324 -107.442)
		(width 0.508)
		(layer "F.Cu")
		(net "P5V")
	)
	(segment
		(start 49.442878 -38.911784)
		(end 50.433478 -38.911784)
		(width 0.508)
		(layer "F.Cu")
		(net "P5V")
	)
	(segment
		(start 169.6466 -111.7346)
		(end 169.6466 -112.5601)
		(width 0.508)
		(layer "F.Cu")
		(net "P5V")
	)
	(segment
		(start 165.9128 -103.8352)
		(end 168.581324 -106.503724)
		(width 0.508)
		(layer "F.Cu")
		(net "P5V")
	)
	(segment
		(start 168.581324 -107.442)
		(end 168.581324 -110.669324)
		(width 0.508)
		(layer "F.Cu")
		(net "P5V")
	)
	(segment
		(start 198.8312 -82.47888)
		(end 198.8312 -81.59242)
		(width 0.508)
		(layer "F.Cu")
		(net "P5V")
	)
	(segment
		(start 149.44979 -109.33176)
		(end 149.35962 -109.42193)
		(width 0.508)
		(layer "F.Cu")
		(net "P5V")
	)
	(segment
		(start 150.35276 -109.33176)
		(end 149.44979 -109.33176)
		(width 0.508)
		(layer "F.Cu")
		(net "P5V")
	)
	(via
		(at 36.319714 -109.4486)
		(size 0.7112)
		(drill 0.4064)
		(layers "F.Cu" "B.Cu")
		(net "P5V")
	)
	(via
		(at 35.702494 -106.684064)
		(size 0.6096)
		(drill 0.3048)
		(layers "F.Cu" "B.Cu")
		(net "P5V")
	)
	(via
		(at 50.433478 -38.911784)
		(size 0.7112)
		(drill 0.4064)
		(layers "F.Cu" "B.Cu")
		(net "P5V")
	)
	(via
		(at 40.149018 -96.229678)
		(size 0.7112)
		(drill 0.4064)
		(layers "F.Cu" "B.Cu")
		(net "P5V")
	)
	(via
		(at 36.945824 -111.845852)
		(size 0.7112)
		(drill 0.4064)
		(layers "F.Cu" "B.Cu")
		(net "P5V")
	)
	(via
		(at 36.476432 -105.6386)
		(size 0.7112)
		(drill 0.4064)
		(layers "F.Cu" "B.Cu")
		(net "P5V")
	)
	(via
		(at 165.9128 -103.8352)
		(size 0.7112)
		(drill 0.4064)
		(layers "F.Cu" "B.Cu")
		(net "P5V")
	)
	(via
		(at 149.35962 -109.42193)
		(size 0.508)
		(drill 0.254)
		(layers "F.Cu" "B.Cu")
		(net "P5V")
	)
	(via
		(at 36.28771 -107.701334)
		(size 0.7112)
		(drill 0.4064)
		(layers "F.Cu" "B.Cu")
		(net "P5V")
	)
	(via
		(at 168.581324 -107.442)
		(size 0.6604)
		(drill 0.3302)
		(layers "F.Cu" "B.Cu")
		(net "P5V")
	)
	(via
		(at 23.89632 -113.91138)
		(size 0.7112)
		(drill 0.4064)
		(layers "F.Cu" "B.Cu")
		(net "P5V")
	)
	(via
		(at 36.929568 -113.082578)
		(size 0.7112)
		(drill 0.4064)
		(layers "F.Cu" "B.Cu")
		(net "P5V")
	)
	(via
		(at 35.76828 -110.931452)
		(size 0.6096)
		(drill 0.3048)
		(layers "F.Cu" "B.Cu")
		(net "P5V")
	)
	(via
		(at 35.740848 -112.785144)
		(size 0.6096)
		(drill 0.3048)
		(layers "F.Cu" "B.Cu")
		(net "P5V")
	)
	(via
		(at 198.82358 -81.5848)
		(size 0.508)
		(drill 0.254)
		(layers "F.Cu" "B.Cu")
		(net "P5V")
	)
	(segment
		(start 40.149018 -68.668646)
		(end 40.149018 -96.229678)
		(width 1.016)
		(layer "In5.Cu")
		(net "P5V")
	)
	(segment
		(start 47.212758 -61.604906)
		(end 40.149018 -68.668646)
		(width 1.016)
		(layer "In5.Cu")
		(net "P5V")
	)
	(segment
		(start 48.909224 -38.911784)
		(end 47.212758 -40.60825)
		(width 1.016)
		(layer "In5.Cu")
		(net "P5V")
	)
	(segment
		(start 47.212758 -40.60825)
		(end 47.212758 -61.604906)
		(width 1.016)
		(layer "In5.Cu")
		(net "P5V")
	)
	(segment
		(start 50.433478 -38.911784)
		(end 48.909224 -38.911784)
		(width 1.016)
		(layer "In5.Cu")
		(net "P5V")
	)
	(via
		(at 144.628108 -119.902732)
		(size 0.6096)
		(drill 0.3048)
		(layers "F.Cu" "B.Cu")
		(net "P1V8_C_PG_G")
	)
	(segment
		(start 142.96517 -120.50141)
		(end 143.563848 -119.902732)
		(width 0.127)
		(layer "B.Cu")
		(net "P1V8_C_PG_G")
	)
	(segment
		(start 144.928082 -120.202706)
		(end 144.628108 -119.902732)
		(width 0.127)
		(layer "B.Cu")
		(net "P1V8_C_PG_G")
	)
	(segment
		(start 143.563848 -119.902732)
		(end 144.628108 -119.902732)
		(width 0.127)
		(layer "B.Cu")
		(net "P1V8_C_PG_G")
	)
	(segment
		(start 144.928082 -121.027952)
		(end 144.928082 -120.202706)
		(width 0.127)
		(layer "B.Cu")
		(net "P1V8_C_PG_G")
	)
	(via
		(at 144.6276 -122.7836)
		(size 0.6096)
		(drill 0.3048)
		(layers "F.Cu" "B.Cu")
		(net "P1V5_C_PG_R_1")
	)
	(segment
		(start 144.6276 -122.7836)
		(end 145.8087 -122.7836)
		(width 0.127)
		(layer "B.Cu")
		(net "P1V5_C_PG_R_1")
	)
	(segment
		(start 143.5862 -123.1646)
		(end 143.9672 -122.7836)
		(width 0.127)
		(layer "B.Cu")
		(net "P1V5_C_PG_R_1")
	)
	(segment
		(start 145.8087 -122.7836)
		(end 145.8087 -123.9266)
		(width 0.127)
		(layer "B.Cu")
		(net "P1V5_C_PG_R_1")
	)
	(segment
		(start 141.1097 -123.1646)
		(end 143.5862 -123.1646)
		(width 0.127)
		(layer "B.Cu")
		(net "P1V5_C_PG_R_1")
	)
	(segment
		(start 143.9672 -122.7836)
		(end 144.6276 -122.7836)
		(width 0.127)
		(layer "B.Cu")
		(net "P1V5_C_PG_R_1")
	)
	(via
		(at 139.7254 -121.8819)
		(size 0.6096)
		(drill 0.3048)
		(layers "F.Cu" "B.Cu")
		(net "P1V5_C_PG_G")
	)
	(segment
		(start 139.26693 -120.262396)
		(end 139.26693 -119.731282)
		(width 0.127)
		(layer "B.Cu")
		(net "P1V5_C_PG_G")
	)
	(segment
		(start 139.26693 -119.13616)
		(end 139.144248 -119.013478)
		(width 0.127)
		(layer "B.Cu")
		(net "P1V5_C_PG_G")
	)
	(segment
		(start 139.144248 -119.013478)
		(end 139.144248 -118.051834)
		(width 0.127)
		(layer "B.Cu")
		(net "P1V5_C_PG_G")
	)
	(segment
		(start 140.2207 -121.8819)
		(end 140.6906 -121.412)
		(width 0.127)
		(layer "B.Cu")
		(net "P1V5_C_PG_G")
	)
	(segment
		(start 138.61923 -121.94286)
		(end 138.61923 -120.910096)
		(width 0.127)
		(layer "B.Cu")
		(net "P1V5_C_PG_G")
	)
	(segment
		(start 139.26693 -119.731282)
		(end 139.26693 -119.13616)
		(width 0.127)
		(layer "B.Cu")
		(net "P1V5_C_PG_G")
	)
	(segment
		(start 139.66444 -121.94286)
		(end 139.7254 -121.8819)
		(width 0.127)
		(layer "B.Cu")
		(net "P1V5_C_PG_G")
	)
	(segment
		(start 138.61923 -120.910096)
		(end 139.26693 -120.262396)
		(width 0.127)
		(layer "B.Cu")
		(net "P1V5_C_PG_G")
	)
	(segment
		(start 138.61923 -121.94286)
		(end 139.66444 -121.94286)
		(width 0.127)
		(layer "B.Cu")
		(net "P1V5_C_PG_G")
	)
	(segment
		(start 140.6906 -119.88673)
		(end 141.06017 -119.51716)
		(width 0.127)
		(layer "B.Cu")
		(net "P1V5_C_PG_G")
	)
	(segment
		(start 139.7254 -121.8819)
		(end 140.2207 -121.8819)
		(width 0.127)
		(layer "B.Cu")
		(net "P1V5_C_PG_G")
	)
	(segment
		(start 140.6906 -121.412)
		(end 140.6906 -119.88673)
		(width 0.127)
		(layer "B.Cu")
		(net "P1V5_C_PG_G")
	)
	(via
		(at 135.1407 -120.9548)
		(size 0.6096)
		(drill 0.3048)
		(layers "F.Cu" "B.Cu")
		(net "P1V5_C_G")
	)
	(segment
		(start 135.0899 -120.904)
		(end 135.1407 -120.9548)
		(width 0.127)
		(layer "B.Cu")
		(net "P1V5_C_G")
	)
	(segment
		(start 134.66445 -122.23115)
		(end 132.5753 -122.23115)
		(width 0.127)
		(layer "B.Cu")
		(net "P1V5_C_G")
	)
	(segment
		(start 135.1407 -120.9548)
		(end 135.1407 -121.7549)
		(width 0.127)
		(layer "B.Cu")
		(net "P1V5_C_G")
	)
	(segment
		(start 134.0358 -120.904)
		(end 135.0899 -120.904)
		(width 0.127)
		(layer "B.Cu")
		(net "P1V5_C_G")
	)
	(segment
		(start 135.1407 -121.7549)
		(end 134.66445 -122.23115)
		(width 0.127)
		(layer "B.Cu")
		(net "P1V5_C_G")
	)
	(segment
		(start 161.29 -110.1598)
		(end 161.29 -108.657136)
		(width 1.016)
		(layer "F.Cu")
		(net "P12V_STBY_SCC")
	)
	(segment
		(start 6.5786 -51.7017)
		(end 5.6261 -51.7017)
		(width 0.508)
		(layer "F.Cu")
		(net "P12V_STBY_SCC")
	)
	(segment
		(start 185.925968 -114.091212)
		(end 185.38698 -114.6302)
		(width 0.508)
		(layer "F.Cu")
		(net "P12V_STBY_SCC")
	)
	(segment
		(start 158.0896 -63.415926)
		(end 158.0896 -55.0545)
		(width 1.016)
		(layer "F.Cu")
		(net "P12V_STBY_SCC")
	)
	(segment
		(start 185.925968 -113.631218)
		(end 185.925968 -114.091212)
		(width 0.508)
		(layer "F.Cu")
		(net "P12V_STBY_SCC")
	)
	(segment
		(start 184.87136 -113.64722)
		(end 184.87136 -114.11458)
		(width 0.508)
		(layer "F.Cu")
		(net "P12V_STBY_SCC")
	)
	(segment
		(start 6.6421 -57.785)
		(end 6.6421 -58.6359)
		(width 0.508)
		(layer "F.Cu")
		(net "P12V_STBY_SCC")
	)
	(segment
		(start 167.6654 -76.0476)
		(end 167.6654 -72.991726)
		(width 1.016)
		(layer "F.Cu")
		(net "P12V_STBY_SCC")
	)
	(segment
		(start 167.6654 -72.991726)
		(end 158.0896 -63.415926)
		(width 1.016)
		(layer "F.Cu")
		(net "P12V_STBY_SCC")
	)
	(segment
		(start 184.87136 -114.11458)
		(end 185.38698 -114.6302)
		(width 0.508)
		(layer "F.Cu")
		(net "P12V_STBY_SCC")
	)
	(via
		(at 162.33648 -117.40642)
		(size 0.7112)
		(drill 0.4064)
		(layers "F.Cu" "B.Cu")
		(net "P12V_STBY_SCC")
	)
	(via
		(at 32.628586 -44.617132)
		(size 0.7112)
		(drill 0.4064)
		(layers "F.Cu" "B.Cu")
		(net "P12V_STBY_SCC")
	)
	(via
		(at 32.65932 -43.38574)
		(size 0.7112)
		(drill 0.4064)
		(layers "F.Cu" "B.Cu")
		(net "P12V_STBY_SCC")
	)
	(via
		(at 50.220372 -89.137998)
		(size 0.7112)
		(drill 0.4064)
		(layers "F.Cu" "B.Cu")
		(net "P12V_STBY_SCC")
	)
	(via
		(at 185.38698 -114.6302)
		(size 0.508)
		(drill 0.254)
		(layers "F.Cu" "B.Cu")
		(net "P12V_STBY_SCC")
	)
	(via
		(at 169.04208 -79.376778)
		(size 0.7112)
		(drill 0.4064)
		(layers "F.Cu" "B.Cu")
		(net "P12V_STBY_SCC")
	)
	(via
		(at 9.779508 -40.975026)
		(size 0.8636)
		(drill 0.508)
		(layers "F.Cu" "B.Cu")
		(net "P12V_STBY_SCC")
	)
	(via
		(at 31.237936 -43.429936)
		(size 0.7112)
		(drill 0.4064)
		(layers "F.Cu" "B.Cu")
		(net "P12V_STBY_SCC")
	)
	(via
		(at 12.522708 -38.231826)
		(size 0.8636)
		(drill 0.508)
		(layers "F.Cu" "B.Cu")
		(net "P12V_STBY_SCC")
	)
	(via
		(at 50.220372 -90.388186)
		(size 0.7112)
		(drill 0.4064)
		(layers "F.Cu" "B.Cu")
		(net "P12V_STBY_SCC")
	)
	(via
		(at 166.279068 -79.376778)
		(size 0.7112)
		(drill 0.4064)
		(layers "F.Cu" "B.Cu")
		(net "P12V_STBY_SCC")
	)
	(via
		(at 11.151108 -38.231826)
		(size 0.8636)
		(drill 0.508)
		(layers "F.Cu" "B.Cu")
		(net "P12V_STBY_SCC")
	)
	(via
		(at 158.0896 -55.0545)
		(size 0.508)
		(drill 0.254)
		(layers "F.Cu" "B.Cu")
		(net "P12V_STBY_SCC")
	)
	(via
		(at 45.064934 -109.958886)
		(size 0.7112)
		(drill 0.4064)
		(layers "F.Cu" "B.Cu")
		(net "P12V_STBY_SCC")
	)
	(via
		(at 167.6654 -78.105)
		(size 0.7112)
		(drill 0.4064)
		(layers "F.Cu" "B.Cu")
		(net "P12V_STBY_SCC")
	)
	(via
		(at 44.811442 -111.879888)
		(size 0.7112)
		(drill 0.4064)
		(layers "F.Cu" "B.Cu")
		(net "P12V_STBY_SCC")
	)
	(via
		(at 11.151108 -40.975026)
		(size 0.8636)
		(drill 0.508)
		(layers "F.Cu" "B.Cu")
		(net "P12V_STBY_SCC")
	)
	(via
		(at 5.6261 -51.7017)
		(size 0.508)
		(drill 0.254)
		(layers "F.Cu" "B.Cu")
		(net "P12V_STBY_SCC")
	)
	(via
		(at 12.522708 -40.975026)
		(size 0.8636)
		(drill 0.508)
		(layers "F.Cu" "B.Cu")
		(net "P12V_STBY_SCC")
	)
	(via
		(at 31.2928 -44.6532)
		(size 0.7112)
		(drill 0.4064)
		(layers "F.Cu" "B.Cu")
		(net "P12V_STBY_SCC")
	)
	(via
		(at 136.91616 -121.94286)
		(size 0.508)
		(drill 0.254)
		(layers "F.Cu" "B.Cu")
		(net "P12V_STBY_SCC")
	)
	(via
		(at 166.239952 -80.623918)
		(size 0.7112)
		(drill 0.4064)
		(layers "F.Cu" "B.Cu")
		(net "P12V_STBY_SCC")
	)
	(via
		(at 12.522708 -39.603426)
		(size 0.8636)
		(drill 0.508)
		(layers "F.Cu" "B.Cu")
		(net "P12V_STBY_SCC")
	)
	(via
		(at 9.779508 -38.231826)
		(size 0.8636)
		(drill 0.508)
		(layers "F.Cu" "B.Cu")
		(net "P12V_STBY_SCC")
	)
	(via
		(at 169.031412 -80.651858)
		(size 0.7112)
		(drill 0.4064)
		(layers "F.Cu" "B.Cu")
		(net "P12V_STBY_SCC")
	)
	(via
		(at 161.29 -108.657136)
		(size 0.7112)
		(drill 0.4064)
		(layers "F.Cu" "B.Cu")
		(net "P12V_STBY_SCC")
	)
	(via
		(at 33.9852 -42.1386)
		(size 0.6604)
		(drill 0.3302)
		(layers "F.Cu" "B.Cu")
		(net "P12V_STBY_SCC")
	)
	(via
		(at 11.151108 -39.603426)
		(size 0.8636)
		(drill 0.508)
		(layers "F.Cu" "B.Cu")
		(net "P12V_STBY_SCC")
	)
	(via
		(at 6.6421 -58.6359)
		(size 0.508)
		(drill 0.254)
		(layers "F.Cu" "B.Cu")
		(net "P12V_STBY_SCC")
	)
	(via
		(at 9.779508 -39.603426)
		(size 0.8636)
		(drill 0.508)
		(layers "F.Cu" "B.Cu")
		(net "P12V_STBY_SCC")
	)
	(via
		(at 64.5922 -90.863928)
		(size 0.7112)
		(drill 0.4064)
		(layers "F.Cu" "B.Cu")
		(net "P12V_STBY_SCC")
	)
	(via
		(at 45.076872 -106.1466)
		(size 0.7112)
		(drill 0.4064)
		(layers "F.Cu" "B.Cu")
		(net "P12V_STBY_SCC")
	)
	(via
		(at 170.0403 -72.3646)
		(size 0.508)
		(drill 0.254)
		(layers "F.Cu" "B.Cu")
		(net "P12V_STBY_SCC")
	)
	(via
		(at 44.782994 -113.155222)
		(size 0.7112)
		(drill 0.4064)
		(layers "F.Cu" "B.Cu")
		(net "P12V_STBY_SCC")
	)
	(via
		(at 169.04208 -78.157578)
		(size 0.7112)
		(drill 0.4064)
		(layers "F.Cu" "B.Cu")
		(net "P12V_STBY_SCC")
	)
	(via
		(at 166.279068 -78.157578)
		(size 0.7112)
		(drill 0.4064)
		(layers "F.Cu" "B.Cu")
		(net "P12V_STBY_SCC")
	)
	(via
		(at 45.093128 -108.238036)
		(size 0.7112)
		(drill 0.4064)
		(layers "F.Cu" "B.Cu")
		(net "P12V_STBY_SCC")
	)
	(via
		(at 138.65352 -123.42876)
		(size 0.508)
		(drill 0.254)
		(layers "F.Cu" "B.Cu")
		(net "P12V_STBY_SCC")
	)
	(via
		(at 31.938214 -42.242486)
		(size 0.7112)
		(drill 0.4064)
		(layers "F.Cu" "B.Cu")
		(net "P12V_STBY_SCC")
	)
	(segment
		(start 160.782 -18.140934)
		(end 160.782 -18.929858)
		(width 1.016)
		(layer "B.Cu")
		(net "P12V_STBY_SCC")
	)
	(segment
		(start 155.2702 -52.2351)
		(end 158.0896 -55.0545)
		(width 1.016)
		(layer "B.Cu")
		(net "P12V_STBY_SCC")
	)
	(segment
		(start 155.2702 -24.441658)
		(end 155.2702 -52.2351)
		(width 1.016)
		(layer "B.Cu")
		(net "P12V_STBY_SCC")
	)
	(segment
		(start 162.33648 -116.36502)
		(end 162.33648 -117.40642)
		(width 0.508)
		(layer "B.Cu")
		(net "P12V_STBY_SCC")
	)
	(segment
		(start 139.5476 -123.42876)
		(end 138.65352 -123.42876)
		(width 0.508)
		(layer "B.Cu")
		(net "P12V_STBY_SCC")
	)
	(segment
		(start 137.73023 -121.94286)
		(end 136.91616 -121.94286)
		(width 0.508)
		(layer "B.Cu")
		(net "P12V_STBY_SCC")
	)
	(segment
		(start 170.0403 -73.152)
		(end 170.0403 -72.3646)
		(width 0.508)
		(layer "B.Cu")
		(net "P12V_STBY_SCC")
	)
	(segment
		(start 64.5922 -90.863928)
		(end 64.5922 -92.329)
		(width 0.508)
		(layer "B.Cu")
		(net "P12V_STBY_SCC")
	)
	(segment
		(start 160.782 -16.7005)
		(end 160.782 -18.140934)
		(width 0.508)
		(layer "B.Cu")
		(net "P12V_STBY_SCC")
	)
	(segment
		(start 160.782 -18.929858)
		(end 155.2702 -24.441658)
		(width 1.016)
		(layer "B.Cu")
		(net "P12V_STBY_SCC")
	)
	(segment
		(start 170.0403 -74.03846)
		(end 170.0403 -72.3646)
		(width 0.508)
		(layer "In2.Cu")
		(net "P12V_STBY_SCC")
	)
	(segment
		(start 167.6654 -76.41336)
		(end 170.0403 -74.03846)
		(width 0.508)
		(layer "In2.Cu")
		(net "P12V_STBY_SCC")
	)
	(segment
		(start 167.6654 -78.105)
		(end 167.6654 -76.41336)
		(width 0.508)
		(layer "In2.Cu")
		(net "P12V_STBY_SCC")
	)
	(segment
		(start 161.29 -108.657136)
		(end 163.503864 -110.871)
		(width 1.016)
		(layer "In5.Cu")
		(net "P12V_STBY_SCC")
	)
	(segment
		(start 183.007 -110.617)
		(end 185.38698 -112.99698)
		(width 1.016)
		(layer "In5.Cu")
		(net "P12V_STBY_SCC")
	)
	(segment
		(start 163.503864 -110.871)
		(end 169.926 -110.871)
		(width 1.016)
		(layer "In5.Cu")
		(net "P12V_STBY_SCC")
	)
	(segment
		(start 185.38698 -112.99698)
		(end 185.38698 -114.6302)
		(width 1.016)
		(layer "In5.Cu")
		(net "P12V_STBY_SCC")
	)
	(segment
		(start 169.926 -110.871)
		(end 170.688 -110.109)
		(width 1.016)
		(layer "In5.Cu")
		(net "P12V_STBY_SCC")
	)
	(segment
		(start 176.149 -110.617)
		(end 183.007 -110.617)
		(width 1.016)
		(layer "In5.Cu")
		(net "P12V_STBY_SCC")
	)
	(segment
		(start 175.641 -110.109)
		(end 176.149 -110.617)
		(width 1.016)
		(layer "In5.Cu")
		(net "P12V_STBY_SCC")
	)
	(segment
		(start 170.688 -110.109)
		(end 175.641 -110.109)
		(width 1.016)
		(layer "In5.Cu")
		(net "P12V_STBY_SCC")
	)
	(segment
		(start 10.719816 -54.513734)
		(end 9.98855 -55.245)
		(width 0.127)
		(layer "F.Cu")
		(net "P12V_SCC_PGOOD")
	)
	(segment
		(start 8.6614 -55.245)
		(end 8.6614 -55.6387)
		(width 0.127)
		(layer "F.Cu")
		(net "P12V_SCC_PGOOD")
	)
	(segment
		(start 8.6614 -55.6387)
		(end 7.5311 -56.769)
		(width 0.127)
		(layer "F.Cu")
		(net "P12V_SCC_PGOOD")
	)
	(segment
		(start 8.99287 -60.911232)
		(end 7.992364 -60.911232)
		(width 0.127)
		(layer "F.Cu")
		(net "P12V_SCC_PGOOD")
	)
	(segment
		(start 7.5311 -56.769)
		(end 7.5311 -57.785)
		(width 0.127)
		(layer "F.Cu")
		(net "P12V_SCC_PGOOD")
	)
	(segment
		(start 11.4681 -54.513734)
		(end 10.719816 -54.513734)
		(width 0.127)
		(layer "F.Cu")
		(net "P12V_SCC_PGOOD")
	)
	(segment
		(start 9.98855 -55.245)
		(end 8.6614 -55.245)
		(width 0.127)
		(layer "F.Cu")
		(net "P12V_SCC_PGOOD")
	)
	(segment
		(start 7.5311 -57.785)
		(end 7.5311 -59.817)
		(width 0.127)
		(layer "F.Cu")
		(net "P12V_SCC_PGOOD")
	)
	(segment
		(start 68.453 -106.7435)
		(end 68.453 -107.40771)
		(width 0.127)
		(layer "F.Cu")
		(net "P12V_SCC_PGOOD")
	)
	(segment
		(start 7.5311 -60.449968)
		(end 7.5311 -59.817)
		(width 0.127)
		(layer "F.Cu")
		(net "P12V_SCC_PGOOD")
	)
	(segment
		(start 7.992364 -60.911232)
		(end 7.5311 -60.449968)
		(width 0.127)
		(layer "F.Cu")
		(net "P12V_SCC_PGOOD")
	)
	(segment
		(start 68.453 -107.40771)
		(end 68.073016 -107.787694)
		(width 0.127)
		(layer "F.Cu")
		(net "P12V_SCC_PGOOD")
	)
	(via
		(at 7.5311 -59.817)
		(size 0.6604)
		(drill 0.3302)
		(layers "F.Cu" "B.Cu")
		(net "P12V_SCC_PGOOD")
	)
	(via
		(at 8.99287 -60.911232)
		(size 0.508)
		(drill 0.254)
		(layers "F.Cu" "B.Cu")
		(net "P12V_SCC_PGOOD")
	)
	(via
		(at 68.073016 -107.787694)
		(size 0.508)
		(drill 0.254)
		(layers "F.Cu" "B.Cu")
		(net "P12V_SCC_PGOOD")
	)
	(segment
		(start 9.00176 -60.920122)
		(end 8.99287 -60.911232)
		(width 0.127)
		(layer "B.Cu")
		(net "P12V_SCC_PGOOD")
	)
	(segment
		(start 66.384932 -89.600532)
		(end 61.0362 -89.600532)
		(width 0.127)
		(layer "B.Cu")
		(net "P12V_SCC_PGOOD")
	)
	(segment
		(start 68.564506 -107.787694)
		(end 69.3166 -107.0356)
		(width 0.127)
		(layer "B.Cu")
		(net "P12V_SCC_PGOOD")
	)
	(segment
		(start 68.073016 -107.787694)
		(end 68.564506 -107.787694)
		(width 0.127)
		(layer "B.Cu")
		(net "P12V_SCC_PGOOD")
	)
	(segment
		(start 69.3166 -92.5322)
		(end 66.384932 -89.600532)
		(width 0.127)
		(layer "B.Cu")
		(net "P12V_SCC_PGOOD")
	)
	(segment
		(start 14.4018 -92.4814)
		(end 14.4018 -72.5424)
		(width 0.127)
		(layer "B.Cu")
		(net "P12V_SCC_PGOOD")
	)
	(segment
		(start 69.3166 -107.0356)
		(end 69.3166 -92.5322)
		(width 0.127)
		(layer "B.Cu")
		(net "P12V_SCC_PGOOD")
	)
	(segment
		(start 14.4018 -72.5424)
		(end 9.00176 -67.14236)
		(width 0.127)
		(layer "B.Cu")
		(net "P12V_SCC_PGOOD")
	)
	(segment
		(start 28.069032 -93.98)
		(end 15.9004 -93.98)
		(width 0.127)
		(layer "B.Cu")
		(net "P12V_SCC_PGOOD")
	)
	(segment
		(start 34.168842 -87.88019)
		(end 28.069032 -93.98)
		(width 0.127)
		(layer "B.Cu")
		(net "P12V_SCC_PGOOD")
	)
	(segment
		(start 9.00176 -67.14236)
		(end 9.00176 -60.920122)
		(width 0.127)
		(layer "B.Cu")
		(net "P12V_SCC_PGOOD")
	)
	(segment
		(start 59.315858 -87.88019)
		(end 34.168842 -87.88019)
		(width 0.127)
		(layer "B.Cu")
		(net "P12V_SCC_PGOOD")
	)
	(segment
		(start 15.9004 -93.98)
		(end 14.4018 -92.4814)
		(width 0.127)
		(layer "B.Cu")
		(net "P12V_SCC_PGOOD")
	)
	(segment
		(start 61.0362 -89.600532)
		(end 59.315858 -87.88019)
		(width 0.127)
		(layer "B.Cu")
		(net "P12V_SCC_PGOOD")
	)
	(segment
		(start 21.79193 -94.405704)
		(end 21.79193 -93.969586)
		(width 0.127)
		(layer "F.Cu")
		(net "LS_EN_U46")
	)
	(segment
		(start 21.94433 -93.817186)
		(end 21.94433 -93.377004)
		(width 0.127)
		(layer "F.Cu")
		(net "LS_EN_U46")
	)
	(segment
		(start 23.187914 -91.654884)
		(end 22.165564 -91.654884)
		(width 0.127)
		(layer "F.Cu")
		(net "LS_EN_U46")
	)
	(segment
		(start 22.165564 -91.654884)
		(end 21.94433 -91.876118)
		(width 0.127)
		(layer "F.Cu")
		(net "LS_EN_U46")
	)
	(segment
		(start 21.79193 -93.969586)
		(end 21.94433 -93.817186)
		(width 0.127)
		(layer "F.Cu")
		(net "LS_EN_U46")
	)
	(segment
		(start 21.94433 -93.377004)
		(end 21.94433 -92.161868)
		(width 0.127)
		(layer "F.Cu")
		(net "LS_EN_U46")
	)
	(segment
		(start 21.94433 -91.876118)
		(end 21.94433 -92.161868)
		(width 0.127)
		(layer "F.Cu")
		(net "LS_EN_U46")
	)
	(segment
		(start 23.43404 -91.408758)
		(end 23.187914 -91.654884)
		(width 0.127)
		(layer "F.Cu")
		(net "LS_EN_U46")
	)
	(segment
		(start 23.43404 -90.678)
		(end 23.43404 -91.408758)
		(width 0.127)
		(layer "F.Cu")
		(net "LS_EN_U46")
	)
	(via
		(at 21.94433 -92.161868)
		(size 0.6604)
		(drill 0.3302)
		(layers "F.Cu" "B.Cu")
		(net "LS_EN_U46")
	)
	(segment
		(start 11.0744 -93.3069)
		(end 11.0744 -92.112846)
		(width 0.127)
		(layer "F.Cu")
		(net "LS_EN_U40")
	)
	(segment
		(start 11.0871 -94.191582)
		(end 11.0871 -93.3196)
		(width 0.127)
		(layer "F.Cu")
		(net "LS_EN_U40")
	)
	(segment
		(start 12.56411 -90.628978)
		(end 12.56411 -91.359736)
		(width 0.127)
		(layer "F.Cu")
		(net "LS_EN_U40")
	)
	(segment
		(start 11.0744 -91.827096)
		(end 11.0744 -92.112846)
		(width 0.127)
		(layer "F.Cu")
		(net "LS_EN_U40")
	)
	(segment
		(start 11.295634 -91.605862)
		(end 11.0744 -91.827096)
		(width 0.127)
		(layer "F.Cu")
		(net "LS_EN_U40")
	)
	(segment
		(start 12.317984 -91.605862)
		(end 11.295634 -91.605862)
		(width 0.127)
		(layer "F.Cu")
		(net "LS_EN_U40")
	)
	(segment
		(start 11.0871 -93.3196)
		(end 11.0744 -93.3069)
		(width 0.127)
		(layer "F.Cu")
		(net "LS_EN_U40")
	)
	(segment
		(start 10.922 -94.356682)
		(end 11.0871 -94.191582)
		(width 0.127)
		(layer "F.Cu")
		(net "LS_EN_U40")
	)
	(segment
		(start 12.56411 -91.359736)
		(end 12.317984 -91.605862)
		(width 0.127)
		(layer "F.Cu")
		(net "LS_EN_U40")
	)
	(via
		(at 11.0744 -92.112846)
		(size 0.6604)
		(drill 0.3302)
		(layers "F.Cu" "B.Cu")
		(net "LS_EN_U40")
	)
	(segment
		(start 71.142098 -71.62292)
		(end 71.142098 -72.002142)
		(width 0.127)
		(layer "F.Cu")
		(net "LS_EN_U39")
	)
	(segment
		(start 72.006714 -70.758304)
		(end 71.142098 -71.62292)
		(width 0.127)
		(layer "F.Cu")
		(net "LS_EN_U39")
	)
	(segment
		(start 70.0024 -73.1393)
		(end 70.0024 -74.219054)
		(width 0.127)
		(layer "F.Cu")
		(net "LS_EN_U39")
	)
	(segment
		(start 70.0024 -74.219054)
		(end 69.249798 -74.971656)
		(width 0.127)
		(layer "F.Cu")
		(net "LS_EN_U39")
	)
	(segment
		(start 69.249798 -74.971656)
		(end 69.249798 -75.934824)
		(width 0.127)
		(layer "F.Cu")
		(net "LS_EN_U39")
	)
	(segment
		(start 70.5485 -73.1393)
		(end 70.0024 -73.1393)
		(width 0.127)
		(layer "F.Cu")
		(net "LS_EN_U39")
	)
	(segment
		(start 71.142098 -72.545702)
		(end 70.5485 -73.1393)
		(width 0.127)
		(layer "F.Cu")
		(net "LS_EN_U39")
	)
	(segment
		(start 71.142098 -72.002142)
		(end 71.142098 -72.545702)
		(width 0.127)
		(layer "F.Cu")
		(net "LS_EN_U39")
	)
	(via
		(at 71.142098 -72.002142)
		(size 0.6604)
		(drill 0.3302)
		(layers "F.Cu" "B.Cu")
		(net "LS_EN_U39")
	)
	(segment
		(start 65.4812 -73.3298)
		(end 65.4812 -75.057)
		(width 0.127)
		(layer "F.Cu")
		(net "LS_EN_U38")
	)
	(segment
		(start 65.4812 -75.057)
		(end 65.7352 -75.311)
		(width 0.127)
		(layer "F.Cu")
		(net "LS_EN_U38")
	)
	(segment
		(start 64.31661 -75.861418)
		(end 64.31661 -74.9808)
		(width 0.127)
		(layer "F.Cu")
		(net "LS_EN_U38")
	)
	(segment
		(start 65.024 -73.1393)
		(end 65.2907 -73.1393)
		(width 0.127)
		(layer "F.Cu")
		(net "LS_EN_U38")
	)
	(segment
		(start 64.31661 -74.9808)
		(end 64.8462 -74.45121)
		(width 0.127)
		(layer "F.Cu")
		(net "LS_EN_U38")
	)
	(segment
		(start 64.8462 -74.45121)
		(end 64.8462 -73.3171)
		(width 0.127)
		(layer "F.Cu")
		(net "LS_EN_U38")
	)
	(segment
		(start 65.7352 -76.3905)
		(end 65.7352 -75.311)
		(width 0.127)
		(layer "F.Cu")
		(net "LS_EN_U38")
	)
	(segment
		(start 65.2907 -73.1393)
		(end 65.4812 -73.3298)
		(width 0.127)
		(layer "F.Cu")
		(net "LS_EN_U38")
	)
	(segment
		(start 64.8462 -73.3171)
		(end 65.024 -73.1393)
		(width 0.127)
		(layer "F.Cu")
		(net "LS_EN_U38")
	)
	(segment
		(start 65.7098 -76.4159)
		(end 65.7352 -76.3905)
		(width 0.127)
		(layer "F.Cu")
		(net "LS_EN_U38")
	)
	(via
		(at 65.7352 -75.311)
		(size 0.6604)
		(drill 0.3302)
		(layers "F.Cu" "B.Cu")
		(net "LS_EN_U38")
	)
	(segment
		(start 59.6392 -73.1139)
		(end 59.6392 -73.843642)
		(width 0.127)
		(layer "F.Cu")
		(net "LS_EN_U37")
	)
	(segment
		(start 59.6392 -73.843642)
		(end 59.657488 -73.86193)
		(width 0.127)
		(layer "F.Cu")
		(net "LS_EN_U37")
	)
	(segment
		(start 61.0108 -75.7936)
		(end 60.96 -75.7428)
		(width 0.127)
		(layer "F.Cu")
		(net "LS_EN_U37")
	)
	(segment
		(start 60.96 -75.7428)
		(end 60.1726 -74.9554)
		(width 0.127)
		(layer "F.Cu")
		(net "LS_EN_U37")
	)
	(segment
		(start 59.86145 -73.1139)
		(end 59.6392 -73.1139)
		(width 0.127)
		(layer "F.Cu")
		(net "LS_EN_U37")
	)
	(segment
		(start 59.657488 -73.86193)
		(end 59.657488 -75.87107)
		(width 0.127)
		(layer "F.Cu")
		(net "LS_EN_U37")
	)
	(segment
		(start 61.0108 -77.0509)
		(end 61.0108 -75.7936)
		(width 0.127)
		(layer "F.Cu")
		(net "LS_EN_U37")
	)
	(segment
		(start 60.1726 -73.42505)
		(end 59.86145 -73.1139)
		(width 0.127)
		(layer "F.Cu")
		(net "LS_EN_U37")
	)
	(segment
		(start 60.1726 -74.9554)
		(end 60.1726 -73.42505)
		(width 0.127)
		(layer "F.Cu")
		(net "LS_EN_U37")
	)
	(via
		(at 60.96 -75.7428)
		(size 0.6604)
		(drill 0.3302)
		(layers "F.Cu" "B.Cu")
		(net "LS_EN_U37")
	)
	(segment
		(start 5.7404 -93.818964)
		(end 5.7404 -93.358208)
		(width 0.127)
		(layer "F.Cu")
		(net "LS_EN_U36")
	)
	(segment
		(start 5.588 -93.971364)
		(end 5.7404 -93.818964)
		(width 0.127)
		(layer "F.Cu")
		(net "LS_EN_U36")
	)
	(segment
		(start 5.588 -94.386908)
		(end 5.588 -93.971364)
		(width 0.127)
		(layer "F.Cu")
		(net "LS_EN_U36")
	)
	(segment
		(start 7.23011 -91.410536)
		(end 6.983984 -91.656662)
		(width 0.127)
		(layer "F.Cu")
		(net "LS_EN_U36")
	)
	(segment
		(start 6.983984 -91.656662)
		(end 5.961634 -91.656662)
		(width 0.127)
		(layer "F.Cu")
		(net "LS_EN_U36")
	)
	(segment
		(start 5.7404 -91.877896)
		(end 5.7404 -92.163646)
		(width 0.127)
		(layer "F.Cu")
		(net "LS_EN_U36")
	)
	(segment
		(start 5.961634 -91.656662)
		(end 5.7404 -91.877896)
		(width 0.127)
		(layer "F.Cu")
		(net "LS_EN_U36")
	)
	(segment
		(start 5.7404 -93.358208)
		(end 5.7404 -92.163646)
		(width 0.127)
		(layer "F.Cu")
		(net "LS_EN_U36")
	)
	(segment
		(start 7.23011 -90.679778)
		(end 7.23011 -91.410536)
		(width 0.127)
		(layer "F.Cu")
		(net "LS_EN_U36")
	)
	(via
		(at 5.7404 -92.163646)
		(size 0.6604)
		(drill 0.3302)
		(layers "F.Cu" "B.Cu")
		(net "LS_EN_U36")
	)
	(segment
		(start 16.637 -94.5007)
		(end 16.5862 -94.4499)
		(width 0.127)
		(layer "F.Cu")
		(net "LS_EN_U35")
	)
	(segment
		(start 16.5862 -91.928696)
		(end 16.5862 -92.214446)
		(width 0.127)
		(layer "F.Cu")
		(net "LS_EN_U35")
	)
	(segment
		(start 16.5862 -93.408754)
		(end 16.5862 -92.214446)
		(width 0.127)
		(layer "F.Cu")
		(net "LS_EN_U35")
	)
	(segment
		(start 16.5862 -94.4499)
		(end 16.5862 -93.408754)
		(width 0.127)
		(layer "F.Cu")
		(net "LS_EN_U35")
	)
	(segment
		(start 16.807434 -91.707462)
		(end 16.5862 -91.928696)
		(width 0.127)
		(layer "F.Cu")
		(net "LS_EN_U35")
	)
	(segment
		(start 18.07591 -91.461336)
		(end 17.829784 -91.707462)
		(width 0.127)
		(layer "F.Cu")
		(net "LS_EN_U35")
	)
	(segment
		(start 17.829784 -91.707462)
		(end 16.807434 -91.707462)
		(width 0.127)
		(layer "F.Cu")
		(net "LS_EN_U35")
	)
	(segment
		(start 18.07591 -90.730578)
		(end 18.07591 -91.461336)
		(width 0.127)
		(layer "F.Cu")
		(net "LS_EN_U35")
	)
	(via
		(at 16.5862 -92.214446)
		(size 0.6604)
		(drill 0.3302)
		(layers "F.Cu" "B.Cu")
		(net "LS_EN_U35")
	)
	(segment
		(start 71.90613 -74.083418)
		(end 71.719948 -74.2696)
		(width 0.127)
		(layer "F.Cu")
		(net "I2C_IOC_4_R_SDA")
	)
	(segment
		(start 71.719948 -74.2696)
		(end 71.616824 -74.372724)
		(width 0.127)
		(layer "F.Cu")
		(net "I2C_IOC_4_R_SDA")
	)
	(segment
		(start 71.612252 -75.552808)
		(end 71.612252 -77.314806)
		(width 0.127)
		(layer "F.Cu")
		(net "I2C_IOC_4_R_SDA")
	)
	(segment
		(start 72.952356 -74.083418)
		(end 71.90613 -74.083418)
		(width 0.127)
		(layer "F.Cu")
		(net "I2C_IOC_4_R_SDA")
	)
	(segment
		(start 71.616824 -74.372724)
		(end 71.616824 -75.548236)
		(width 0.127)
		(layer "F.Cu")
		(net "I2C_IOC_4_R_SDA")
	)
	(segment
		(start 71.616824 -75.548236)
		(end 71.612252 -75.552808)
		(width 0.127)
		(layer "F.Cu")
		(net "I2C_IOC_4_R_SDA")
	)
	(via
		(at 71.719948 -74.2696)
		(size 0.6604)
		(drill 0.3302)
		(layers "F.Cu" "B.Cu")
		(net "I2C_IOC_4_R_SDA")
	)
	(segment
		(start 75.47229 -75.606402)
		(end 75.47229 -74.803762)
		(width 0.127)
		(layer "F.Cu")
		(net "I2C_IOC_4_R_SCL")
	)
	(segment
		(start 74.855832 -74.187304)
		(end 74.855832 -73.224644)
		(width 0.127)
		(layer "F.Cu")
		(net "I2C_IOC_4_R_SCL")
	)
	(segment
		(start 75.47229 -74.803762)
		(end 74.855832 -74.187304)
		(width 0.127)
		(layer "F.Cu")
		(net "I2C_IOC_4_R_SCL")
	)
	(segment
		(start 75.68184 -72.398636)
		(end 75.447652 -72.632824)
		(width 0.127)
		(layer "F.Cu")
		(net "I2C_IOC_4_R_SCL")
	)
	(segment
		(start 74.855832 -73.224644)
		(end 75.447652 -72.632824)
		(width 0.127)
		(layer "F.Cu")
		(net "I2C_IOC_4_R_SCL")
	)
	(segment
		(start 74.914252 -77.314806)
		(end 74.914252 -76.16444)
		(width 0.127)
		(layer "F.Cu")
		(net "I2C_IOC_4_R_SCL")
	)
	(segment
		(start 75.68184 -71.404988)
		(end 75.68184 -72.398636)
		(width 0.127)
		(layer "F.Cu")
		(net "I2C_IOC_4_R_SCL")
	)
	(segment
		(start 74.914252 -76.16444)
		(end 75.47229 -75.606402)
		(width 0.127)
		(layer "F.Cu")
		(net "I2C_IOC_4_R_SCL")
	)
	(via
		(at 75.447652 -72.632824)
		(size 0.6604)
		(drill 0.3302)
		(layers "F.Cu" "B.Cu")
		(net "I2C_IOC_4_R_SCL")
	)
	(segment
		(start 119.500142 -79.500222)
		(end 120.000014 -80.000094)
		(width 0.127)
		(layer "F.Cu")
		(net "SLOT_ID_1")
	)
	(via
		(at 120.000014 -80.000094)
		(size 0.4572)
		(drill 0.2032)
		(layers "F.Cu" "B.Cu")
		(net "SLOT_ID_1")
	)
	(via
		(at 118.937278 -82.188812)
		(size 0.6096)
		(drill 0.3048)
		(layers "F.Cu" "B.Cu")
		(net "SLOT_ID_1")
	)
	(via
		(at 67.79133 -25.457658)
		(size 0.508)
		(drill 0.254)
		(layers "F.Cu" "B.Cu")
		(net "SLOT_ID_1")
	)
	(via
		(at 120.9548 -85.0646)
		(size 0.508)
		(drill 0.254)
		(layers "F.Cu" "B.Cu")
		(net "SLOT_ID_1")
	)
	(segment
		(start 120.542558 -85.795612)
		(end 120.9548 -85.38337)
		(width 0.127)
		(layer "B.Cu")
		(net "SLOT_ID_1")
	)
	(segment
		(start 118.937278 -82.188812)
		(end 118.937278 -83.466178)
		(width 0.127)
		(layer "B.Cu")
		(net "SLOT_ID_1")
	)
	(segment
		(start 120.000014 -80.000094)
		(end 119.45366 -80.546448)
		(width 0.127)
		(layer "B.Cu")
		(net "SLOT_ID_1")
	)
	(segment
		(start 118.937278 -83.466178)
		(end 120.5357 -85.0646)
		(width 0.127)
		(layer "B.Cu")
		(net "SLOT_ID_1")
	)
	(segment
		(start 120.9548 -85.38337)
		(end 120.9548 -85.0646)
		(width 0.127)
		(layer "B.Cu")
		(net "SLOT_ID_1")
	)
	(segment
		(start 119.45366 -80.546448)
		(end 119.45366 -81.2165)
		(width 0.127)
		(layer "B.Cu")
		(net "SLOT_ID_1")
	)
	(segment
		(start 118.937278 -81.732882)
		(end 118.937278 -82.188812)
		(width 0.127)
		(layer "B.Cu")
		(net "SLOT_ID_1")
	)
	(segment
		(start 120.5357 -85.0646)
		(end 120.9548 -85.0646)
		(width 0.127)
		(layer "B.Cu")
		(net "SLOT_ID_1")
	)
	(segment
		(start 120.542558 -86.21141)
		(end 120.542558 -85.795612)
		(width 0.127)
		(layer "B.Cu")
		(net "SLOT_ID_1")
	)
	(segment
		(start 119.45366 -81.2165)
		(end 118.937278 -81.732882)
		(width 0.127)
		(layer "B.Cu")
		(net "SLOT_ID_1")
	)
	(segment
		(start 90.740992 -8.259318)
		(end 91.400122 -7.600188)
		(width 0.127)
		(layer "In2.Cu")
		(net "SLOT_ID_1")
	)
	(segment
		(start 75.995022 -16.9672)
		(end 89.298272 -16.9672)
		(width 0.127)
		(layer "In2.Cu")
		(net "SLOT_ID_1")
	)
	(segment
		(start 67.79133 -25.170892)
		(end 75.995022 -16.9672)
		(width 0.127)
		(layer "In2.Cu")
		(net "SLOT_ID_1")
	)
	(segment
		(start 89.298272 -16.9672)
		(end 90.740992 -15.52448)
		(width 0.127)
		(layer "In2.Cu")
		(net "SLOT_ID_1")
	)
	(segment
		(start 90.740992 -15.52448)
		(end 90.740992 -8.259318)
		(width 0.127)
		(layer "In2.Cu")
		(net "SLOT_ID_1")
	)
	(segment
		(start 67.79133 -25.457658)
		(end 67.79133 -25.170892)
		(width 0.127)
		(layer "In2.Cu")
		(net "SLOT_ID_1")
	)
	(segment
		(start 68.683886 -30.48508)
		(end 67.79133 -29.592524)
		(width 0.127)
		(layer "In5.Cu")
		(net "SLOT_ID_1")
	)
	(segment
		(start 76.034392 -81.622392)
		(end 76.034392 -78.66126)
		(width 0.127)
		(layer "In5.Cu")
		(net "SLOT_ID_1")
	)
	(segment
		(start 82.719164 -92.161106)
		(end 77.18171 -86.623652)
		(width 0.127)
		(layer "In5.Cu")
		(net "SLOT_ID_1")
	)
	(segment
		(start 77.18171 -82.76971)
		(end 76.034392 -81.622392)
		(width 0.127)
		(layer "In5.Cu")
		(net "SLOT_ID_1")
	)
	(segment
		(start 116.324634 -87.541354)
		(end 113.39068 -90.475308)
		(width 0.127)
		(layer "In5.Cu")
		(net "SLOT_ID_1")
	)
	(segment
		(start 76.034392 -78.66126)
		(end 74.883518 -77.510386)
		(width 0.127)
		(layer "In5.Cu")
		(net "SLOT_ID_1")
	)
	(segment
		(start 74.883518 -77.510386)
		(end 74.883518 -72.409304)
		(width 0.127)
		(layer "In5.Cu")
		(net "SLOT_ID_1")
	)
	(segment
		(start 98.332544 -92.161106)
		(end 82.719164 -92.161106)
		(width 0.127)
		(layer "In5.Cu")
		(net "SLOT_ID_1")
	)
	(segment
		(start 67.79133 -29.592524)
		(end 67.79133 -25.457658)
		(width 0.127)
		(layer "In5.Cu")
		(net "SLOT_ID_1")
	)
	(segment
		(start 100.018342 -90.475308)
		(end 98.332544 -92.161106)
		(width 0.127)
		(layer "In5.Cu")
		(net "SLOT_ID_1")
	)
	(segment
		(start 74.883518 -72.409304)
		(end 68.683886 -66.209672)
		(width 0.127)
		(layer "In5.Cu")
		(net "SLOT_ID_1")
	)
	(segment
		(start 68.683886 -66.209672)
		(end 68.683886 -30.48508)
		(width 0.127)
		(layer "In5.Cu")
		(net "SLOT_ID_1")
	)
	(segment
		(start 113.39068 -90.475308)
		(end 100.018342 -90.475308)
		(width 0.127)
		(layer "In5.Cu")
		(net "SLOT_ID_1")
	)
	(segment
		(start 120.9548 -85.0646)
		(end 118.478046 -87.541354)
		(width 0.127)
		(layer "In5.Cu")
		(net "SLOT_ID_1")
	)
	(segment
		(start 77.18171 -86.623652)
		(end 77.18171 -82.76971)
		(width 0.127)
		(layer "In5.Cu")
		(net "SLOT_ID_1")
	)
	(segment
		(start 118.478046 -87.541354)
		(end 116.324634 -87.541354)
		(width 0.127)
		(layer "In5.Cu")
		(net "SLOT_ID_1")
	)
	(segment
		(start 104.7496 -86.444836)
		(end 103.828342 -86.444836)
		(width 0.127)
		(layer "F.Cu")
		(net "SLOT_ID_0")
	)
	(segment
		(start 103.452168 -87.830152)
		(end 103.452168 -87.309452)
		(width 0.127)
		(layer "F.Cu")
		(net "SLOT_ID_0")
	)
	(segment
		(start 103.452168 -87.303356)
		(end 103.455216 -87.306404)
		(width 0.127)
		(layer "F.Cu")
		(net "SLOT_ID_0")
	)
	(segment
		(start 103.452168 -86.82101)
		(end 103.452168 -87.303356)
		(width 0.127)
		(layer "F.Cu")
		(net "SLOT_ID_0")
	)
	(segment
		(start 103.452168 -87.309452)
		(end 103.455216 -87.306404)
		(width 0.127)
		(layer "F.Cu")
		(net "SLOT_ID_0")
	)
	(segment
		(start 103.828342 -86.444836)
		(end 103.452168 -86.82101)
		(width 0.127)
		(layer "F.Cu")
		(net "SLOT_ID_0")
	)
	(segment
		(start 119.500142 -78.500224)
		(end 119.00027 -78.000352)
		(width 0.127)
		(layer "F.Cu")
		(net "SLOT_ID_0")
	)
	(segment
		(start 103.103934 -88.178386)
		(end 103.452168 -87.830152)
		(width 0.127)
		(layer "F.Cu")
		(net "SLOT_ID_0")
	)
	(via
		(at 69.325998 -22.951948)
		(size 0.508)
		(drill 0.254)
		(layers "F.Cu" "B.Cu")
		(net "SLOT_ID_0")
	)
	(via
		(at 103.455216 -87.306404)
		(size 0.6604)
		(drill 0.3302)
		(layers "F.Cu" "B.Cu")
		(net "SLOT_ID_0")
	)
	(via
		(at 119.00027 -78.000352)
		(size 0.4572)
		(drill 0.2032)
		(layers "F.Cu" "B.Cu")
		(net "SLOT_ID_0")
	)
	(via
		(at 103.103934 -88.178386)
		(size 0.508)
		(drill 0.254)
		(layers "F.Cu" "B.Cu")
		(net "SLOT_ID_0")
	)
	(segment
		(start 69.325998 -22.951948)
		(end 69.325998 -22.699218)
		(width 0.127)
		(layer "In2.Cu")
		(net "SLOT_ID_0")
	)
	(segment
		(start 69.952108 -22.073108)
		(end 69.952108 -20.766278)
		(width 0.127)
		(layer "In2.Cu")
		(net "SLOT_ID_0")
	)
	(segment
		(start 74.259186 -16.4592)
		(end 88.599772 -16.4592)
		(width 0.127)
		(layer "In2.Cu")
		(net "SLOT_ID_0")
	)
	(segment
		(start 90.232738 -14.826234)
		(end 90.232738 -7.367524)
		(width 0.127)
		(layer "In2.Cu")
		(net "SLOT_ID_0")
	)
	(segment
		(start 69.325998 -22.699218)
		(end 69.952108 -22.073108)
		(width 0.127)
		(layer "In2.Cu")
		(net "SLOT_ID_0")
	)
	(segment
		(start 69.952108 -20.766278)
		(end 74.259186 -16.4592)
		(width 0.127)
		(layer "In2.Cu")
		(net "SLOT_ID_0")
	)
	(segment
		(start 88.599772 -16.4592)
		(end 90.232738 -14.826234)
		(width 0.127)
		(layer "In2.Cu")
		(net "SLOT_ID_0")
	)
	(segment
		(start 90.232738 -7.367524)
		(end 91.400122 -6.20014)
		(width 0.127)
		(layer "In2.Cu")
		(net "SLOT_ID_0")
	)
	(segment
		(start 99.159314 -88.372696)
		(end 97.30232 -90.22969)
		(width 0.127)
		(layer "In5.Cu")
		(net "SLOT_ID_0")
	)
	(segment
		(start 71.1073 -65.60185)
		(end 71.1073 -30.752796)
		(width 0.127)
		(layer "In5.Cu")
		(net "SLOT_ID_0")
	)
	(segment
		(start 71.1073 -30.752796)
		(end 69.325998 -28.971494)
		(width 0.127)
		(layer "In5.Cu")
		(net "SLOT_ID_0")
	)
	(segment
		(start 108.077 -86.487)
		(end 108.585 -86.487)
		(width 0.127)
		(layer "In5.Cu")
		(net "SLOT_ID_0")
	)
	(segment
		(start 77.650086 -76.3397)
		(end 78.16342 -75.826366)
		(width 0.127)
		(layer "In5.Cu")
		(net "SLOT_ID_0")
	)
	(segment
		(start 78.16342 -75.826366)
		(end 78.16342 -72.65797)
		(width 0.127)
		(layer "In5.Cu")
		(net "SLOT_ID_0")
	)
	(segment
		(start 85.550248 -90.22969)
		(end 79.375 -84.054442)
		(width 0.127)
		(layer "In5.Cu")
		(net "SLOT_ID_0")
	)
	(segment
		(start 69.325998 -28.971494)
		(end 69.325998 -22.951948)
		(width 0.127)
		(layer "In5.Cu")
		(net "SLOT_ID_0")
	)
	(segment
		(start 103.103934 -88.178386)
		(end 103.635302 -87.647018)
		(width 0.127)
		(layer "In5.Cu")
		(net "SLOT_ID_0")
	)
	(segment
		(start 79.375 -81.05267)
		(end 78.066392 -79.744062)
		(width 0.127)
		(layer "In5.Cu")
		(net "SLOT_ID_0")
	)
	(segment
		(start 118.420896 -80.022192)
		(end 118.420896 -78.579726)
		(width 0.127)
		(layer "In5.Cu")
		(net "SLOT_ID_0")
	)
	(segment
		(start 118.420896 -78.579726)
		(end 119.00027 -78.000352)
		(width 0.127)
		(layer "In5.Cu")
		(net "SLOT_ID_0")
	)
	(segment
		(start 117.39372 -81.049368)
		(end 118.420896 -80.022192)
		(width 0.127)
		(layer "In5.Cu")
		(net "SLOT_ID_0")
	)
	(segment
		(start 102.909624 -88.372696)
		(end 99.159314 -88.372696)
		(width 0.127)
		(layer "In5.Cu")
		(net "SLOT_ID_0")
	)
	(segment
		(start 78.066392 -78.537562)
		(end 77.650086 -78.121256)
		(width 0.127)
		(layer "In5.Cu")
		(net "SLOT_ID_0")
	)
	(segment
		(start 78.066392 -79.744062)
		(end 78.066392 -78.537562)
		(width 0.127)
		(layer "In5.Cu")
		(net "SLOT_ID_0")
	)
	(segment
		(start 103.635302 -87.647018)
		(end 106.916982 -87.647018)
		(width 0.127)
		(layer "In5.Cu")
		(net "SLOT_ID_0")
	)
	(segment
		(start 106.916982 -87.647018)
		(end 108.077 -86.487)
		(width 0.127)
		(layer "In5.Cu")
		(net "SLOT_ID_0")
	)
	(segment
		(start 117.39372 -81.163414)
		(end 117.39372 -81.049368)
		(width 0.127)
		(layer "In5.Cu")
		(net "SLOT_ID_0")
	)
	(segment
		(start 110.436152 -84.635848)
		(end 113.921286 -84.635848)
		(width 0.127)
		(layer "In5.Cu")
		(net "SLOT_ID_0")
	)
	(segment
		(start 103.103934 -88.178386)
		(end 102.909624 -88.372696)
		(width 0.127)
		(layer "In5.Cu")
		(net "SLOT_ID_0")
	)
	(segment
		(start 77.650086 -78.121256)
		(end 77.650086 -76.3397)
		(width 0.127)
		(layer "In5.Cu")
		(net "SLOT_ID_0")
	)
	(segment
		(start 108.585 -86.487)
		(end 110.436152 -84.635848)
		(width 0.127)
		(layer "In5.Cu")
		(net "SLOT_ID_0")
	)
	(segment
		(start 97.30232 -90.22969)
		(end 85.550248 -90.22969)
		(width 0.127)
		(layer "In5.Cu")
		(net "SLOT_ID_0")
	)
	(segment
		(start 78.16342 -72.65797)
		(end 71.1073 -65.60185)
		(width 0.127)
		(layer "In5.Cu")
		(net "SLOT_ID_0")
	)
	(segment
		(start 113.921286 -84.635848)
		(end 117.39372 -81.163414)
		(width 0.127)
		(layer "In5.Cu")
		(net "SLOT_ID_0")
	)
	(segment
		(start 79.375 -84.054442)
		(end 79.375 -81.05267)
		(width 0.127)
		(layer "In5.Cu")
		(net "SLOT_ID_0")
	)
	(segment
		(start 117.500146 -78.500224)
		(end 118.000018 -78.000352)
		(width 0.127)
		(layer "F.Cu")
		(net "SCC_RMT_HEARTBEAT_LS")
	)
	(segment
		(start 163.091114 -5.247386)
		(end 163.348162 -4.990338)
		(width 0.127)
		(layer "F.Cu")
		(net "SCC_RMT_HEARTBEAT_LS")
	)
	(segment
		(start 163.091114 -6.418072)
		(end 163.091114 -5.247386)
		(width 0.127)
		(layer "F.Cu")
		(net "SCC_RMT_HEARTBEAT_LS")
	)
	(segment
		(start 163.348162 -4.482592)
		(end 163.348162 -3.505962)
		(width 0.127)
		(layer "F.Cu")
		(net "SCC_RMT_HEARTBEAT_LS")
	)
	(segment
		(start 163.348162 -4.990338)
		(end 163.348162 -4.482592)
		(width 0.127)
		(layer "F.Cu")
		(net "SCC_RMT_HEARTBEAT_LS")
	)
	(via
		(at 163.348162 -3.505962)
		(size 0.508)
		(drill 0.254)
		(layers "F.Cu" "B.Cu")
		(net "SCC_RMT_HEARTBEAT_LS")
	)
	(via
		(at 118.000018 -78.000352)
		(size 0.4572)
		(drill 0.2032)
		(layers "F.Cu" "B.Cu")
		(net "SCC_RMT_HEARTBEAT_LS")
	)
	(via
		(at 120.4468 -93.345)
		(size 0.508)
		(drill 0.254)
		(layers "F.Cu" "B.Cu")
		(net "SCC_RMT_HEARTBEAT_LS")
	)
	(via
		(at 163.348162 -4.482592)
		(size 0.6604)
		(drill 0.3302)
		(layers "F.Cu" "B.Cu")
		(net "SCC_RMT_HEARTBEAT_LS")
	)
	(segment
		(start 120.4468 -93.345)
		(end 121.5009 -93.345)
		(width 0.127)
		(layer "B.Cu")
		(net "SCC_RMT_HEARTBEAT_LS")
	)
	(segment
		(start 121.5009 -93.345)
		(end 121.5009 -92.3036)
		(width 0.127)
		(layer "B.Cu")
		(net "SCC_RMT_HEARTBEAT_LS")
	)
	(segment
		(start 118.872508 -80.543908)
		(end 117.5258 -79.1972)
		(width 0.127)
		(layer "In2.Cu")
		(net "SCC_RMT_HEARTBEAT_LS")
	)
	(segment
		(start 121.211848 -91.152472)
		(end 122.2629 -90.10142)
		(width 0.127)
		(layer "In2.Cu")
		(net "SCC_RMT_HEARTBEAT_LS")
	)
	(segment
		(start 117.5258 -78.47457)
		(end 118.000018 -78.000352)
		(width 0.127)
		(layer "In2.Cu")
		(net "SCC_RMT_HEARTBEAT_LS")
	)
	(segment
		(start 119.3292 -80.543908)
		(end 118.872508 -80.543908)
		(width 0.127)
		(layer "In2.Cu")
		(net "SCC_RMT_HEARTBEAT_LS")
	)
	(segment
		(start 121.211848 -92.579952)
		(end 121.211848 -91.152472)
		(width 0.127)
		(layer "In2.Cu")
		(net "SCC_RMT_HEARTBEAT_LS")
	)
	(segment
		(start 122.249692 -85.471)
		(end 121.6406 -85.471)
		(width 0.127)
		(layer "In2.Cu")
		(net "SCC_RMT_HEARTBEAT_LS")
	)
	(segment
		(start 122.2629 -90.10142)
		(end 122.2629 -89.416382)
		(width 0.127)
		(layer "In2.Cu")
		(net "SCC_RMT_HEARTBEAT_LS")
	)
	(segment
		(start 117.5258 -79.1972)
		(end 117.5258 -78.47457)
		(width 0.127)
		(layer "In2.Cu")
		(net "SCC_RMT_HEARTBEAT_LS")
	)
	(segment
		(start 119.561356 -80.776064)
		(end 119.3292 -80.543908)
		(width 0.127)
		(layer "In2.Cu")
		(net "SCC_RMT_HEARTBEAT_LS")
	)
	(segment
		(start 121.6406 -85.471)
		(end 121.3866 -85.217)
		(width 0.127)
		(layer "In2.Cu")
		(net "SCC_RMT_HEARTBEAT_LS")
	)
	(segment
		(start 120.841516 -82.455766)
		(end 119.561356 -81.175606)
		(width 0.127)
		(layer "In2.Cu")
		(net "SCC_RMT_HEARTBEAT_LS")
	)
	(segment
		(start 122.2629 -89.416382)
		(end 122.790458 -88.888824)
		(width 0.127)
		(layer "In2.Cu")
		(net "SCC_RMT_HEARTBEAT_LS")
	)
	(segment
		(start 121.3866 -84.305648)
		(end 120.841516 -83.760564)
		(width 0.127)
		(layer "In2.Cu")
		(net "SCC_RMT_HEARTBEAT_LS")
	)
	(segment
		(start 120.4468 -93.345)
		(end 121.211848 -92.579952)
		(width 0.127)
		(layer "In2.Cu")
		(net "SCC_RMT_HEARTBEAT_LS")
	)
	(segment
		(start 119.561356 -81.175606)
		(end 119.561356 -80.776064)
		(width 0.127)
		(layer "In2.Cu")
		(net "SCC_RMT_HEARTBEAT_LS")
	)
	(segment
		(start 122.790458 -88.888824)
		(end 122.790458 -86.011766)
		(width 0.127)
		(layer "In2.Cu")
		(net "SCC_RMT_HEARTBEAT_LS")
	)
	(segment
		(start 120.841516 -83.760564)
		(end 120.841516 -82.455766)
		(width 0.127)
		(layer "In2.Cu")
		(net "SCC_RMT_HEARTBEAT_LS")
	)
	(segment
		(start 122.790458 -86.011766)
		(end 122.249692 -85.471)
		(width 0.127)
		(layer "In2.Cu")
		(net "SCC_RMT_HEARTBEAT_LS")
	)
	(segment
		(start 121.3866 -85.217)
		(end 121.3866 -84.305648)
		(width 0.127)
		(layer "In2.Cu")
		(net "SCC_RMT_HEARTBEAT_LS")
	)
	(segment
		(start 156.68244 -31.718758)
		(end 156.68244 -6.656324)
		(width 0.127)
		(layer "In5.Cu")
		(net "SCC_RMT_HEARTBEAT_LS")
	)
	(segment
		(start 151.4348 -58.5978)
		(end 153.108152 -56.924448)
		(width 0.127)
		(layer "In5.Cu")
		(net "SCC_RMT_HEARTBEAT_LS")
	)
	(segment
		(start 151.4348 -64.80429)
		(end 151.4348 -58.5978)
		(width 0.127)
		(layer "In5.Cu")
		(net "SCC_RMT_HEARTBEAT_LS")
	)
	(segment
		(start 153.108152 -41.781476)
		(end 154.526234 -40.363394)
		(width 0.127)
		(layer "In5.Cu")
		(net "SCC_RMT_HEARTBEAT_LS")
	)
	(segment
		(start 162.500056 -4.354068)
		(end 163.348162 -3.505962)
		(width 0.127)
		(layer "In5.Cu")
		(net "SCC_RMT_HEARTBEAT_LS")
	)
	(segment
		(start 141.41323 -74.82586)
		(end 151.4348 -64.80429)
		(width 0.127)
		(layer "In5.Cu")
		(net "SCC_RMT_HEARTBEAT_LS")
	)
	(segment
		(start 135.134604 -74.82586)
		(end 141.41323 -74.82586)
		(width 0.127)
		(layer "In5.Cu")
		(net "SCC_RMT_HEARTBEAT_LS")
	)
	(segment
		(start 156.68244 -6.656324)
		(end 158.984696 -4.354068)
		(width 0.127)
		(layer "In5.Cu")
		(net "SCC_RMT_HEARTBEAT_LS")
	)
	(segment
		(start 154.526234 -33.874964)
		(end 156.68244 -31.718758)
		(width 0.127)
		(layer "In5.Cu")
		(net "SCC_RMT_HEARTBEAT_LS")
	)
	(segment
		(start 131.377182 -78.583282)
		(end 135.134604 -74.82586)
		(width 0.127)
		(layer "In5.Cu")
		(net "SCC_RMT_HEARTBEAT_LS")
	)
	(segment
		(start 118.42877 -77.5716)
		(end 120.777 -77.5716)
		(width 0.127)
		(layer "In5.Cu")
		(net "SCC_RMT_HEARTBEAT_LS")
	)
	(segment
		(start 158.984696 -4.354068)
		(end 162.500056 -4.354068)
		(width 0.127)
		(layer "In5.Cu")
		(net "SCC_RMT_HEARTBEAT_LS")
	)
	(segment
		(start 121.788682 -78.583282)
		(end 131.377182 -78.583282)
		(width 0.127)
		(layer "In5.Cu")
		(net "SCC_RMT_HEARTBEAT_LS")
	)
	(segment
		(start 118.000018 -78.000352)
		(end 118.42877 -77.5716)
		(width 0.127)
		(layer "In5.Cu")
		(net "SCC_RMT_HEARTBEAT_LS")
	)
	(segment
		(start 153.108152 -56.924448)
		(end 153.108152 -41.781476)
		(width 0.127)
		(layer "In5.Cu")
		(net "SCC_RMT_HEARTBEAT_LS")
	)
	(segment
		(start 154.526234 -40.363394)
		(end 154.526234 -33.874964)
		(width 0.127)
		(layer "In5.Cu")
		(net "SCC_RMT_HEARTBEAT_LS")
	)
	(segment
		(start 120.777 -77.5716)
		(end 121.788682 -78.583282)
		(width 0.127)
		(layer "In5.Cu")
		(net "SCC_RMT_HEARTBEAT_LS")
	)
	(segment
		(start 161.29 -16.383)
		(end 159.385 -16.383)
		(width 0.127)
		(layer "F.Cu")
		(net "SCC_RMT_HEARTBEAT")
	)
	(segment
		(start 163.489894 -12.982194)
		(end 163.614354 -13.106654)
		(width 0.127)
		(layer "F.Cu")
		(net "SCC_RMT_HEARTBEAT")
	)
	(segment
		(start 163.489894 -12.056872)
		(end 163.489894 -12.982194)
		(width 0.127)
		(layer "F.Cu")
		(net "SCC_RMT_HEARTBEAT")
	)
	(segment
		(start 163.614354 -14.058646)
		(end 163.068 -14.605)
		(width 0.127)
		(layer "F.Cu")
		(net "SCC_RMT_HEARTBEAT")
	)
	(segment
		(start 163.068 -14.605)
		(end 161.29 -16.383)
		(width 0.127)
		(layer "F.Cu")
		(net "SCC_RMT_HEARTBEAT")
	)
	(segment
		(start 163.614354 -13.106654)
		(end 163.614354 -14.058646)
		(width 0.127)
		(layer "F.Cu")
		(net "SCC_RMT_HEARTBEAT")
	)
	(via
		(at 79.040228 -15.9512)
		(size 0.508)
		(drill 0.254)
		(layers "F.Cu" "B.Cu")
		(net "SCC_RMT_HEARTBEAT")
	)
	(via
		(at 94.265496 -45.40504)
		(size 0.508)
		(drill 0.254)
		(layers "F.Cu" "B.Cu")
		(net "SCC_RMT_HEARTBEAT")
	)
	(via
		(at 159.385 -16.383)
		(size 0.508)
		(drill 0.254)
		(layers "F.Cu" "B.Cu")
		(net "SCC_RMT_HEARTBEAT")
	)
	(via
		(at 163.068 -14.605)
		(size 0.6604)
		(drill 0.3302)
		(layers "F.Cu" "B.Cu")
		(net "SCC_RMT_HEARTBEAT")
	)
	(segment
		(start 102.523036 -45.365924)
		(end 94.304612 -45.365924)
		(width 0.127)
		(layer "In2.Cu")
		(net "SCC_RMT_HEARTBEAT")
	)
	(segment
		(start 88.389206 -15.9512)
		(end 88.940894 -15.399512)
		(width 0.127)
		(layer "In2.Cu")
		(net "SCC_RMT_HEARTBEAT")
	)
	(segment
		(start 157.389576 -16.383)
		(end 150.932896 -22.83968)
		(width 0.127)
		(layer "In2.Cu")
		(net "SCC_RMT_HEARTBEAT")
	)
	(segment
		(start 159.385 -16.383)
		(end 157.389576 -16.383)
		(width 0.127)
		(layer "In2.Cu")
		(net "SCC_RMT_HEARTBEAT")
	)
	(segment
		(start 150.932896 -22.83968)
		(end 138.757406 -22.83968)
		(width 0.127)
		(layer "In2.Cu")
		(net "SCC_RMT_HEARTBEAT")
	)
	(segment
		(start 88.940894 -9.459214)
		(end 89.600024 -8.800084)
		(width 0.127)
		(layer "In2.Cu")
		(net "SCC_RMT_HEARTBEAT")
	)
	(segment
		(start 122.393964 -39.203122)
		(end 108.685838 -39.203122)
		(width 0.127)
		(layer "In2.Cu")
		(net "SCC_RMT_HEARTBEAT")
	)
	(segment
		(start 138.757406 -22.83968)
		(end 122.393964 -39.203122)
		(width 0.127)
		(layer "In2.Cu")
		(net "SCC_RMT_HEARTBEAT")
	)
	(segment
		(start 94.304612 -45.365924)
		(end 94.265496 -45.40504)
		(width 0.127)
		(layer "In2.Cu")
		(net "SCC_RMT_HEARTBEAT")
	)
	(segment
		(start 108.685838 -39.203122)
		(end 102.523036 -45.365924)
		(width 0.127)
		(layer "In2.Cu")
		(net "SCC_RMT_HEARTBEAT")
	)
	(segment
		(start 88.940894 -15.399512)
		(end 88.940894 -9.459214)
		(width 0.127)
		(layer "In2.Cu")
		(net "SCC_RMT_HEARTBEAT")
	)
	(segment
		(start 79.040228 -15.9512)
		(end 88.389206 -15.9512)
		(width 0.127)
		(layer "In2.Cu")
		(net "SCC_RMT_HEARTBEAT")
	)
	(segment
		(start 94.22638 -45.365924)
		(end 94.265496 -45.40504)
		(width 0.127)
		(layer "In5.Cu")
		(net "SCC_RMT_HEARTBEAT")
	)
	(segment
		(start 89.37752 -41.692068)
		(end 93.051376 -45.365924)
		(width 0.127)
		(layer "In5.Cu")
		(net "SCC_RMT_HEARTBEAT")
	)
	(segment
		(start 89.37752 -37.68852)
		(end 89.37752 -41.692068)
		(width 0.127)
		(layer "In5.Cu")
		(net "SCC_RMT_HEARTBEAT")
	)
	(segment
		(start 79.040228 -15.9512)
		(end 79.040228 -20.837398)
		(width 0.127)
		(layer "In5.Cu")
		(net "SCC_RMT_HEARTBEAT")
	)
	(segment
		(start 87.861394 -29.658564)
		(end 87.861394 -36.172394)
		(width 0.127)
		(layer "In5.Cu")
		(net "SCC_RMT_HEARTBEAT")
	)
	(segment
		(start 93.051376 -45.365924)
		(end 94.22638 -45.365924)
		(width 0.127)
		(layer "In5.Cu")
		(net "SCC_RMT_HEARTBEAT")
	)
	(segment
		(start 87.861394 -36.172394)
		(end 89.37752 -37.68852)
		(width 0.127)
		(layer "In5.Cu")
		(net "SCC_RMT_HEARTBEAT")
	)
	(segment
		(start 79.040228 -20.837398)
		(end 87.861394 -29.658564)
		(width 0.127)
		(layer "In5.Cu")
		(net "SCC_RMT_HEARTBEAT")
	)
	(segment
		(start 76.556362 -26.460958)
		(end 76.17079 -26.460958)
		(width 0.127)
		(layer "F.Cu")
		(net "SCC_LOC_INS_N")
	)
	(segment
		(start 76.17079 -26.460958)
		(end 76.17079 -27.362658)
		(width 0.127)
		(layer "F.Cu")
		(net "SCC_LOC_INS_N")
	)
	(segment
		(start 76.835 -26.739596)
		(end 76.556362 -26.460958)
		(width 0.127)
		(layer "F.Cu")
		(net "SCC_LOC_INS_N")
	)
	(segment
		(start 76.17079 -27.362658)
		(end 76.29779 -27.489658)
		(width 0.127)
		(layer "F.Cu")
		(net "SCC_LOC_INS_N")
	)
	(segment
		(start 76.835 -29.21)
		(end 76.835 -26.739596)
		(width 0.127)
		(layer "F.Cu")
		(net "SCC_LOC_INS_N")
	)
	(via
		(at 76.29779 -27.489658)
		(size 0.508)
		(drill 0.254)
		(layers "F.Cu" "B.Cu")
		(net "SCC_LOC_INS_N")
	)
	(via
		(at 76.835 -29.21)
		(size 0.6604)
		(drill 0.3302)
		(layers "F.Cu" "B.Cu")
		(net "SCC_LOC_INS_N")
	)
	(segment
		(start 92.30995 -24.55418)
		(end 103.340662 -13.523468)
		(width 0.127)
		(layer "In2.Cu")
		(net "SCC_LOC_INS_N")
	)
	(segment
		(start 79.233268 -24.55418)
		(end 92.30995 -24.55418)
		(width 0.127)
		(layer "In2.Cu")
		(net "SCC_LOC_INS_N")
	)
	(segment
		(start 76.29779 -27.489658)
		(end 79.233268 -24.55418)
		(width 0.127)
		(layer "In2.Cu")
		(net "SCC_LOC_INS_N")
	)
	(segment
		(start 103.340662 -13.523468)
		(end 103.340662 -9.459468)
		(width 0.127)
		(layer "In2.Cu")
		(net "SCC_LOC_INS_N")
	)
	(segment
		(start 103.340662 -9.459468)
		(end 104.000046 -8.800084)
		(width 0.127)
		(layer "In2.Cu")
		(net "SCC_LOC_INS_N")
	)
	(segment
		(start 73.017126 -15.4432)
		(end 72.930766 -15.52956)
		(width 0.127)
		(layer "F.Cu")
		(net "SCC_LOC_HEARTBEAT")
	)
	(segment
		(start 76.278994 -15.4432)
		(end 74.839576 -15.4432)
		(width 0.127)
		(layer "F.Cu")
		(net "SCC_LOC_HEARTBEAT")
	)
	(segment
		(start 74.839576 -15.4432)
		(end 73.017126 -15.4432)
		(width 0.127)
		(layer "F.Cu")
		(net "SCC_LOC_HEARTBEAT")
	)
	(segment
		(start 72.930766 -15.52956)
		(end 71.958708 -15.52956)
		(width 0.127)
		(layer "F.Cu")
		(net "SCC_LOC_HEARTBEAT")
	)
	(via
		(at 76.278994 -15.4432)
		(size 0.508)
		(drill 0.254)
		(layers "F.Cu" "B.Cu")
		(net "SCC_LOC_HEARTBEAT")
	)
	(via
		(at 74.839576 -15.4432)
		(size 0.6604)
		(drill 0.3302)
		(layers "F.Cu" "B.Cu")
		(net "SCC_LOC_HEARTBEAT")
	)
	(segment
		(start 88.43264 -8.56742)
		(end 89.600024 -7.400036)
		(width 0.127)
		(layer "In2.Cu")
		(net "SCC_LOC_HEARTBEAT")
	)
	(segment
		(start 87.671656 -15.4432)
		(end 88.43264 -14.682216)
		(width 0.127)
		(layer "In2.Cu")
		(net "SCC_LOC_HEARTBEAT")
	)
	(segment
		(start 88.43264 -14.682216)
		(end 88.43264 -8.56742)
		(width 0.127)
		(layer "In2.Cu")
		(net "SCC_LOC_HEARTBEAT")
	)
	(segment
		(start 76.278994 -15.4432)
		(end 87.671656 -15.4432)
		(width 0.127)
		(layer "In2.Cu")
		(net "SCC_LOC_HEARTBEAT")
	)
	(segment
		(start 176.1998 -30.80004)
		(end 175.800004 -30.400244)
		(width 0.1397)
		(layer "F.Cu")
		(net "PCIE_SCC_TO_COMP_C_7_DP")
	)
	(via
		(at 175.800004 -30.400244)
		(size 0.4572)
		(drill 0.2032)
		(layers "F.Cu" "B.Cu")
		(net "PCIE_SCC_TO_COMP_C_7_DP")
	)
	(segment
		(start 179.640992 -21.75002)
		(end 180.521356 -21.378164)
		(width 0.14605)
		(layer "B.Cu")
		(net "PCIE_SCC_TO_COMP_C_7_DP")
	)
	(segment
		(start 177.116994 -26.60777)
		(end 177.332386 -26.60777)
		(width 0.14605)
		(layer "B.Cu")
		(net "PCIE_SCC_TO_COMP_C_7_DP")
	)
	(segment
		(start 177.332386 -26.60777)
		(end 178.026568 -25.913588)
		(width 0.14605)
		(layer "B.Cu")
		(net "PCIE_SCC_TO_COMP_C_7_DP")
	)
	(segment
		(start 179.342796 -22.04847)
		(end 179.469796 -21.921216)
		(width 0.14605)
		(layer "B.Cu")
		(net "PCIE_SCC_TO_COMP_C_7_DP")
	)
	(segment
		(start 180.521356 -21.378164)
		(end 180.739288 -21.378164)
		(width 0.14605)
		(layer "B.Cu")
		(net "PCIE_SCC_TO_COMP_C_7_DP")
	)
	(segment
		(start 176.807114 -26.91765)
		(end 177.116994 -26.60777)
		(width 0.14605)
		(layer "B.Cu")
		(net "PCIE_SCC_TO_COMP_C_7_DP")
	)
	(segment
		(start 176.464468 -28.380436)
		(end 176.464468 -27.475688)
		(width 0.14605)
		(layer "B.Cu")
		(net "PCIE_SCC_TO_COMP_C_7_DP")
	)
	(segment
		(start 176.464468 -27.475688)
		(end 176.807114 -27.133042)
		(width 0.14605)
		(layer "B.Cu")
		(net "PCIE_SCC_TO_COMP_C_7_DP")
	)
	(segment
		(start 179.190396 -23.254208)
		(end 179.342796 -23.101808)
		(width 0.14605)
		(layer "B.Cu")
		(net "PCIE_SCC_TO_COMP_C_7_DP")
	)
	(segment
		(start 179.190396 -23.692358)
		(end 179.190396 -23.254208)
		(width 0.14605)
		(layer "B.Cu")
		(net "PCIE_SCC_TO_COMP_C_7_DP")
	)
	(segment
		(start 175.800004 -30.400244)
		(end 175.976788 -30.22346)
		(width 0.09525)
		(layer "B.Cu")
		(net "PCIE_SCC_TO_COMP_C_7_DP")
	)
	(segment
		(start 176.540668 -28.480258)
		(end 176.464468 -28.404058)
		(width 0.09525)
		(layer "B.Cu")
		(net "PCIE_SCC_TO_COMP_C_7_DP")
	)
	(segment
		(start 178.026568 -25.913588)
		(end 178.893216 -25.913588)
		(width 0.14605)
		(layer "B.Cu")
		(net "PCIE_SCC_TO_COMP_C_7_DP")
	)
	(segment
		(start 180.739288 -21.378164)
		(end 180.842412 -21.27504)
		(width 0.14605)
		(layer "B.Cu")
		(net "PCIE_SCC_TO_COMP_C_7_DP")
	)
	(segment
		(start 179.469796 -21.921216)
		(end 179.640992 -21.75002)
		(width 0.14605)
		(layer "B.Cu")
		(net "PCIE_SCC_TO_COMP_C_7_DP")
	)
	(segment
		(start 179.342796 -23.844758)
		(end 179.190396 -23.692358)
		(width 0.14605)
		(layer "B.Cu")
		(net "PCIE_SCC_TO_COMP_C_7_DP")
	)
	(segment
		(start 179.342796 -25.464008)
		(end 179.342796 -25.025858)
		(width 0.14605)
		(layer "B.Cu")
		(net "PCIE_SCC_TO_COMP_C_7_DP")
	)
	(segment
		(start 178.893216 -25.913588)
		(end 179.342796 -25.464008)
		(width 0.14605)
		(layer "B.Cu")
		(net "PCIE_SCC_TO_COMP_C_7_DP")
	)
	(segment
		(start 180.842412 -21.27504)
		(end 180.99024 -21.27504)
		(width 0.14605)
		(layer "B.Cu")
		(net "PCIE_SCC_TO_COMP_C_7_DP")
	)
	(segment
		(start 175.976788 -29.739082)
		(end 176.540668 -29.175202)
		(width 0.09525)
		(layer "B.Cu")
		(net "PCIE_SCC_TO_COMP_C_7_DP")
	)
	(segment
		(start 179.342796 -24.282908)
		(end 179.342796 -23.844758)
		(width 0.14605)
		(layer "B.Cu")
		(net "PCIE_SCC_TO_COMP_C_7_DP")
	)
	(segment
		(start 179.190396 -24.435308)
		(end 179.342796 -24.282908)
		(width 0.14605)
		(layer "B.Cu")
		(net "PCIE_SCC_TO_COMP_C_7_DP")
	)
	(segment
		(start 179.342796 -23.101808)
		(end 179.342796 -22.04847)
		(width 0.14605)
		(layer "B.Cu")
		(net "PCIE_SCC_TO_COMP_C_7_DP")
	)
	(segment
		(start 176.807114 -27.133042)
		(end 176.807114 -26.91765)
		(width 0.14605)
		(layer "B.Cu")
		(net "PCIE_SCC_TO_COMP_C_7_DP")
	)
	(segment
		(start 176.464468 -28.404058)
		(end 176.464468 -28.380436)
		(width 0.09525)
		(layer "B.Cu")
		(net "PCIE_SCC_TO_COMP_C_7_DP")
	)
	(segment
		(start 176.540668 -29.175202)
		(end 176.540668 -28.480258)
		(width 0.09525)
		(layer "B.Cu")
		(net "PCIE_SCC_TO_COMP_C_7_DP")
	)
	(segment
		(start 175.976788 -30.22346)
		(end 175.976788 -29.739082)
		(width 0.09525)
		(layer "B.Cu")
		(net "PCIE_SCC_TO_COMP_C_7_DP")
	)
	(segment
		(start 179.190396 -24.873458)
		(end 179.190396 -24.435308)
		(width 0.14605)
		(layer "B.Cu")
		(net "PCIE_SCC_TO_COMP_C_7_DP")
	)
	(segment
		(start 179.342796 -25.025858)
		(end 179.190396 -24.873458)
		(width 0.14605)
		(layer "B.Cu")
		(net "PCIE_SCC_TO_COMP_C_7_DP")
	)
	(segment
		(start 176.1998 -31.599886)
		(end 175.800004 -31.20009)
		(width 0.1397)
		(layer "F.Cu")
		(net "PCIE_SCC_TO_COMP_C_7_DN")
	)
	(via
		(at 175.800004 -31.20009)
		(size 0.4572)
		(drill 0.2032)
		(layers "F.Cu" "B.Cu")
		(net "PCIE_SCC_TO_COMP_C_7_DN")
	)
	(segment
		(start 176.160938 -29.815536)
		(end 176.724818 -29.251656)
		(width 0.09525)
		(layer "B.Cu")
		(net "PCIE_SCC_TO_COMP_C_7_DN")
	)
	(segment
		(start 176.213516 -30.498542)
		(end 176.213516 -30.246066)
		(width 0.09525)
		(layer "B.Cu")
		(net "PCIE_SCC_TO_COMP_C_7_DN")
	)
	(segment
		(start 179.653946 -25.59304)
		(end 179.653946 -22.177502)
		(width 0.14605)
		(layer "B.Cu")
		(net "PCIE_SCC_TO_COMP_C_7_DN")
	)
	(segment
		(start 179.022248 -26.224738)
		(end 179.653946 -25.59304)
		(width 0.14605)
		(layer "B.Cu")
		(net "PCIE_SCC_TO_COMP_C_7_DN")
	)
	(segment
		(start 175.800004 -31.20009)
		(end 176.213516 -30.498542)
		(width 0.09525)
		(layer "B.Cu")
		(net "PCIE_SCC_TO_COMP_C_7_DN")
	)
	(segment
		(start 176.160938 -30.193488)
		(end 176.160938 -29.815536)
		(width 0.09525)
		(layer "B.Cu")
		(net "PCIE_SCC_TO_COMP_C_7_DN")
	)
	(segment
		(start 180.71211 -21.689314)
		(end 180.864764 -21.841968)
		(width 0.14605)
		(layer "B.Cu")
		(net "PCIE_SCC_TO_COMP_C_7_DN")
	)
	(segment
		(start 179.818284 -22.013164)
		(end 180.584602 -21.689314)
		(width 0.14605)
		(layer "B.Cu")
		(net "PCIE_SCC_TO_COMP_C_7_DN")
	)
	(segment
		(start 178.1556 -26.224738)
		(end 179.022248 -26.224738)
		(width 0.14605)
		(layer "B.Cu")
		(net "PCIE_SCC_TO_COMP_C_7_DN")
	)
	(segment
		(start 176.724818 -29.251656)
		(end 176.724818 -28.454858)
		(width 0.09525)
		(layer "B.Cu")
		(net "PCIE_SCC_TO_COMP_C_7_DN")
	)
	(segment
		(start 179.690268 -22.140926)
		(end 179.690268 -22.14118)
		(width 0.14605)
		(layer "B.Cu")
		(net "PCIE_SCC_TO_COMP_C_7_DN")
	)
	(segment
		(start 179.653946 -22.177502)
		(end 179.690268 -22.140926)
		(width 0.14605)
		(layer "B.Cu")
		(net "PCIE_SCC_TO_COMP_C_7_DN")
	)
	(segment
		(start 176.775618 -27.60472)
		(end 178.1556 -26.224738)
		(width 0.14605)
		(layer "B.Cu")
		(net "PCIE_SCC_TO_COMP_C_7_DN")
	)
	(segment
		(start 180.584602 -21.689314)
		(end 180.71211 -21.689314)
		(width 0.14605)
		(layer "B.Cu")
		(net "PCIE_SCC_TO_COMP_C_7_DN")
	)
	(segment
		(start 176.775618 -28.404058)
		(end 176.775618 -28.380436)
		(width 0.09525)
		(layer "B.Cu")
		(net "PCIE_SCC_TO_COMP_C_7_DN")
	)
	(segment
		(start 176.213516 -30.246066)
		(end 176.160938 -30.193488)
		(width 0.09525)
		(layer "B.Cu")
		(net "PCIE_SCC_TO_COMP_C_7_DN")
	)
	(segment
		(start 176.724818 -28.454858)
		(end 176.775618 -28.404058)
		(width 0.09525)
		(layer "B.Cu")
		(net "PCIE_SCC_TO_COMP_C_7_DN")
	)
	(segment
		(start 180.864764 -21.841968)
		(end 180.989986 -21.841968)
		(width 0.14605)
		(layer "B.Cu")
		(net "PCIE_SCC_TO_COMP_C_7_DN")
	)
	(segment
		(start 176.775618 -28.380436)
		(end 176.775618 -27.60472)
		(width 0.14605)
		(layer "B.Cu")
		(net "PCIE_SCC_TO_COMP_C_7_DN")
	)
	(segment
		(start 179.690268 -22.14118)
		(end 179.818284 -22.013164)
		(width 0.14605)
		(layer "B.Cu")
		(net "PCIE_SCC_TO_COMP_C_7_DN")
	)
	(segment
		(start 175.399954 -30.80004)
		(end 174.999904 -30.39999)
		(width 0.1397)
		(layer "F.Cu")
		(net "PCIE_SCC_TO_COMP_C_6_DP")
	)
	(via
		(at 174.999904 -30.39999)
		(size 0.4572)
		(drill 0.2032)
		(layers "F.Cu" "B.Cu")
		(net "PCIE_SCC_TO_COMP_C_6_DP")
	)
	(segment
		(start 175.107854 -29.90215)
		(end 175.107854 -29.878528)
		(width 0.09525)
		(layer "B.Cu")
		(net "PCIE_SCC_TO_COMP_C_6_DP")
	)
	(segment
		(start 175.107854 -29.878528)
		(end 175.107854 -29.463746)
		(width 0.14605)
		(layer "B.Cu")
		(net "PCIE_SCC_TO_COMP_C_6_DP")
	)
	(segment
		(start 175.668178 -26.815796)
		(end 175.978058 -26.505916)
		(width 0.14605)
		(layer "B.Cu")
		(net "PCIE_SCC_TO_COMP_C_6_DP")
	)
	(segment
		(start 175.174656 -30.225238)
		(end 175.174656 -29.968952)
		(width 0.09525)
		(layer "B.Cu")
		(net "PCIE_SCC_TO_COMP_C_6_DP")
	)
	(segment
		(start 177.178716 -21.063458)
		(end 177.534062 -20.716748)
		(width 0.14605)
		(layer "B.Cu")
		(net "PCIE_SCC_TO_COMP_C_6_DP")
	)
	(segment
		(start 175.515778 -28.312872)
		(end 175.515778 -27.874722)
		(width 0.14605)
		(layer "B.Cu")
		(net "PCIE_SCC_TO_COMP_C_6_DP")
	)
	(segment
		(start 175.978058 -26.290524)
		(end 176.287938 -25.980644)
		(width 0.14605)
		(layer "B.Cu")
		(net "PCIE_SCC_TO_COMP_C_6_DP")
	)
	(segment
		(start 176.287938 -25.980644)
		(end 176.50333 -25.980644)
		(width 0.14605)
		(layer "B.Cu")
		(net "PCIE_SCC_TO_COMP_C_6_DP")
	)
	(segment
		(start 175.668178 -28.903422)
		(end 175.668178 -28.465272)
		(width 0.14605)
		(layer "B.Cu")
		(net "PCIE_SCC_TO_COMP_C_6_DP")
	)
	(segment
		(start 178.003708 -20.716748)
		(end 178.140614 -20.579842)
		(width 0.14605)
		(layer "B.Cu")
		(net "PCIE_SCC_TO_COMP_C_6_DP")
	)
	(segment
		(start 177.534062 -20.716748)
		(end 178.003708 -20.716748)
		(width 0.14605)
		(layer "B.Cu")
		(net "PCIE_SCC_TO_COMP_C_6_DP")
	)
	(segment
		(start 175.668178 -28.465272)
		(end 175.515778 -28.312872)
		(width 0.14605)
		(layer "B.Cu")
		(net "PCIE_SCC_TO_COMP_C_6_DP")
	)
	(segment
		(start 177.178716 -25.305258)
		(end 177.178716 -21.063458)
		(width 0.14605)
		(layer "B.Cu")
		(net "PCIE_SCC_TO_COMP_C_6_DP")
	)
	(segment
		(start 176.50333 -25.980644)
		(end 177.178716 -25.305258)
		(width 0.14605)
		(layer "B.Cu")
		(net "PCIE_SCC_TO_COMP_C_6_DP")
	)
	(segment
		(start 175.515778 -27.874722)
		(end 175.668178 -27.722322)
		(width 0.14605)
		(layer "B.Cu")
		(net "PCIE_SCC_TO_COMP_C_6_DP")
	)
	(segment
		(start 174.999904 -30.39999)
		(end 175.174656 -30.225238)
		(width 0.09525)
		(layer "B.Cu")
		(net "PCIE_SCC_TO_COMP_C_6_DP")
	)
	(segment
		(start 175.668178 -27.722322)
		(end 175.668178 -26.815796)
		(width 0.14605)
		(layer "B.Cu")
		(net "PCIE_SCC_TO_COMP_C_6_DP")
	)
	(segment
		(start 175.107854 -29.463746)
		(end 175.668178 -28.903422)
		(width 0.14605)
		(layer "B.Cu")
		(net "PCIE_SCC_TO_COMP_C_6_DP")
	)
	(segment
		(start 175.978058 -26.505916)
		(end 175.978058 -26.290524)
		(width 0.14605)
		(layer "B.Cu")
		(net "PCIE_SCC_TO_COMP_C_6_DP")
	)
	(segment
		(start 175.174656 -29.968952)
		(end 175.107854 -29.90215)
		(width 0.09525)
		(layer "B.Cu")
		(net "PCIE_SCC_TO_COMP_C_6_DP")
	)
	(segment
		(start 175.399954 -31.599886)
		(end 175.000158 -31.20009)
		(width 0.1397)
		(layer "F.Cu")
		(net "PCIE_SCC_TO_COMP_C_6_DN")
	)
	(via
		(at 175.000158 -31.20009)
		(size 0.4572)
		(drill 0.2032)
		(layers "F.Cu" "B.Cu")
		(net "PCIE_SCC_TO_COMP_C_6_DN")
	)
	(segment
		(start 175.358806 -29.950664)
		(end 175.358806 -30.191202)
		(width 0.09525)
		(layer "B.Cu")
		(net "PCIE_SCC_TO_COMP_C_6_DN")
	)
	(segment
		(start 175.419004 -29.890466)
		(end 175.358806 -29.950664)
		(width 0.09525)
		(layer "B.Cu")
		(net "PCIE_SCC_TO_COMP_C_6_DN")
	)
	(segment
		(start 175.358806 -30.191202)
		(end 175.40097 -30.233366)
		(width 0.09525)
		(layer "B.Cu")
		(net "PCIE_SCC_TO_COMP_C_6_DN")
	)
	(segment
		(start 177.489866 -25.43429)
		(end 175.979328 -26.944828)
		(width 0.14605)
		(layer "B.Cu")
		(net "PCIE_SCC_TO_COMP_C_6_DN")
	)
	(segment
		(start 177.489866 -21.194776)
		(end 177.489866 -25.43429)
		(width 0.14605)
		(layer "B.Cu")
		(net "PCIE_SCC_TO_COMP_C_6_DN")
	)
	(segment
		(start 177.912268 -21.027898)
		(end 177.660808 -21.027898)
		(width 0.14605)
		(layer "B.Cu")
		(net "PCIE_SCC_TO_COMP_C_6_DN")
	)
	(segment
		(start 178.03495 -21.15058)
		(end 177.912268 -21.027898)
		(width 0.14605)
		(layer "B.Cu")
		(net "PCIE_SCC_TO_COMP_C_6_DN")
	)
	(segment
		(start 175.419004 -29.878528)
		(end 175.419004 -29.890466)
		(width 0.09525)
		(layer "B.Cu")
		(net "PCIE_SCC_TO_COMP_C_6_DN")
	)
	(segment
		(start 175.399954 -30.234382)
		(end 175.399954 -30.52191)
		(width 0.09525)
		(layer "B.Cu")
		(net "PCIE_SCC_TO_COMP_C_6_DN")
	)
	(segment
		(start 175.419004 -29.592778)
		(end 175.419004 -29.878528)
		(width 0.14605)
		(layer "B.Cu")
		(net "PCIE_SCC_TO_COMP_C_6_DN")
	)
	(segment
		(start 175.399954 -30.52191)
		(end 175.000158 -31.20009)
		(width 0.09525)
		(layer "B.Cu")
		(net "PCIE_SCC_TO_COMP_C_6_DN")
	)
	(segment
		(start 175.40097 -30.233366)
		(end 175.399954 -30.234382)
		(width 0.09525)
		(layer "B.Cu")
		(net "PCIE_SCC_TO_COMP_C_6_DN")
	)
	(segment
		(start 178.141376 -21.15058)
		(end 178.03495 -21.15058)
		(width 0.14605)
		(layer "B.Cu")
		(net "PCIE_SCC_TO_COMP_C_6_DN")
	)
	(segment
		(start 175.979328 -29.032454)
		(end 175.419004 -29.592778)
		(width 0.14605)
		(layer "B.Cu")
		(net "PCIE_SCC_TO_COMP_C_6_DN")
	)
	(segment
		(start 175.979328 -26.944828)
		(end 175.979328 -29.032454)
		(width 0.14605)
		(layer "B.Cu")
		(net "PCIE_SCC_TO_COMP_C_6_DN")
	)
	(segment
		(start 177.660808 -21.027898)
		(end 177.489866 -21.194776)
		(width 0.14605)
		(layer "B.Cu")
		(net "PCIE_SCC_TO_COMP_C_6_DN")
	)
	(segment
		(start 173.399958 -30.39999)
		(end 173.800008 -30.80004)
		(width 0.14605)
		(layer "F.Cu")
		(net "PCIE_SCC_TO_COMP_C_5_DP")
	)
	(via
		(at 173.399958 -30.39999)
		(size 0.4572)
		(drill 0.2032)
		(layers "F.Cu" "B.Cu")
		(net "PCIE_SCC_TO_COMP_C_5_DP")
	)
	(segment
		(start 174.27321 -27.815032)
		(end 174.12081 -27.662632)
		(width 0.14605)
		(layer "B.Cu")
		(net "PCIE_SCC_TO_COMP_C_5_DP")
	)
	(segment
		(start 174.12081 -27.224482)
		(end 174.27321 -27.072082)
		(width 0.14605)
		(layer "B.Cu")
		(net "PCIE_SCC_TO_COMP_C_5_DP")
	)
	(segment
		(start 173.449742 -29.464)
		(end 173.449742 -29.069792)
		(width 0.14605)
		(layer "B.Cu")
		(net "PCIE_SCC_TO_COMP_C_5_DP")
	)
	(segment
		(start 175.079406 -24.680926)
		(end 175.231806 -24.528526)
		(width 0.14605)
		(layer "B.Cu")
		(net "PCIE_SCC_TO_COMP_C_5_DP")
	)
	(segment
		(start 175.079406 -23.499826)
		(end 175.231806 -23.347426)
		(width 0.14605)
		(layer "B.Cu")
		(net "PCIE_SCC_TO_COMP_C_5_DP")
	)
	(segment
		(start 173.449742 -29.487622)
		(end 173.449742 -29.464)
		(width 0.09525)
		(layer "B.Cu")
		(net "PCIE_SCC_TO_COMP_C_5_DP")
	)
	(segment
		(start 175.231806 -24.528526)
		(end 175.231806 -24.090376)
		(width 0.14605)
		(layer "B.Cu")
		(net "PCIE_SCC_TO_COMP_C_5_DP")
	)
	(segment
		(start 175.231806 -24.090376)
		(end 175.079406 -23.937976)
		(width 0.14605)
		(layer "B.Cu")
		(net "PCIE_SCC_TO_COMP_C_5_DP")
	)
	(segment
		(start 175.079406 -22.756876)
		(end 175.079406 -22.318726)
		(width 0.14605)
		(layer "B.Cu")
		(net "PCIE_SCC_TO_COMP_C_5_DP")
	)
	(segment
		(start 173.81982 -28.484068)
		(end 174.035466 -28.484068)
		(width 0.14605)
		(layer "B.Cu")
		(net "PCIE_SCC_TO_COMP_C_5_DP")
	)
	(segment
		(start 175.231806 -25.271476)
		(end 175.079406 -25.119076)
		(width 0.14605)
		(layer "B.Cu")
		(net "PCIE_SCC_TO_COMP_C_5_DP")
	)
	(segment
		(start 174.412656 -26.406602)
		(end 174.412656 -26.190956)
		(width 0.14605)
		(layer "B.Cu")
		(net "PCIE_SCC_TO_COMP_C_5_DP")
	)
	(segment
		(start 175.043846 -21.382482)
		(end 175.043846 -21.233892)
		(width 0.14605)
		(layer "B.Cu")
		(net "PCIE_SCC_TO_COMP_C_5_DP")
	)
	(segment
		(start 174.27321 -26.546048)
		(end 174.412656 -26.406602)
		(width 0.14605)
		(layer "B.Cu")
		(net "PCIE_SCC_TO_COMP_C_5_DP")
	)
	(segment
		(start 175.079406 -25.119076)
		(end 175.079406 -24.680926)
		(width 0.14605)
		(layer "B.Cu")
		(net "PCIE_SCC_TO_COMP_C_5_DP")
	)
	(segment
		(start 175.079406 -23.937976)
		(end 175.079406 -23.499826)
		(width 0.14605)
		(layer "B.Cu")
		(net "PCIE_SCC_TO_COMP_C_5_DP")
	)
	(segment
		(start 173.513242 -29.551122)
		(end 173.449742 -29.487622)
		(width 0.09525)
		(layer "B.Cu")
		(net "PCIE_SCC_TO_COMP_C_5_DP")
	)
	(segment
		(start 174.937928 -25.88133)
		(end 175.231806 -25.587452)
		(width 0.14605)
		(layer "B.Cu")
		(net "PCIE_SCC_TO_COMP_C_5_DP")
	)
	(segment
		(start 173.513242 -30.286706)
		(end 173.513242 -29.551122)
		(width 0.09525)
		(layer "B.Cu")
		(net "PCIE_SCC_TO_COMP_C_5_DP")
	)
	(segment
		(start 173.50994 -29.009594)
		(end 173.50994 -28.793948)
		(width 0.14605)
		(layer "B.Cu")
		(net "PCIE_SCC_TO_COMP_C_5_DP")
	)
	(segment
		(start 175.231806 -23.347426)
		(end 175.231806 -22.909276)
		(width 0.14605)
		(layer "B.Cu")
		(net "PCIE_SCC_TO_COMP_C_5_DP")
	)
	(segment
		(start 173.399958 -30.39999)
		(end 173.513242 -30.286706)
		(width 0.09525)
		(layer "B.Cu")
		(net "PCIE_SCC_TO_COMP_C_5_DP")
	)
	(segment
		(start 173.449742 -29.069792)
		(end 173.50994 -29.009594)
		(width 0.14605)
		(layer "B.Cu")
		(net "PCIE_SCC_TO_COMP_C_5_DP")
	)
	(segment
		(start 175.231806 -21.570442)
		(end 175.043846 -21.382482)
		(width 0.14605)
		(layer "B.Cu")
		(net "PCIE_SCC_TO_COMP_C_5_DP")
	)
	(segment
		(start 174.035466 -28.484068)
		(end 174.27321 -28.246324)
		(width 0.14605)
		(layer "B.Cu")
		(net "PCIE_SCC_TO_COMP_C_5_DP")
	)
	(segment
		(start 175.231806 -22.166326)
		(end 175.231806 -21.570442)
		(width 0.14605)
		(layer "B.Cu")
		(net "PCIE_SCC_TO_COMP_C_5_DP")
	)
	(segment
		(start 174.27321 -28.246324)
		(end 174.27321 -27.815032)
		(width 0.14605)
		(layer "B.Cu")
		(net "PCIE_SCC_TO_COMP_C_5_DP")
	)
	(segment
		(start 175.231806 -22.909276)
		(end 175.079406 -22.756876)
		(width 0.14605)
		(layer "B.Cu")
		(net "PCIE_SCC_TO_COMP_C_5_DP")
	)
	(segment
		(start 174.12081 -27.662632)
		(end 174.12081 -27.224482)
		(width 0.14605)
		(layer "B.Cu")
		(net "PCIE_SCC_TO_COMP_C_5_DP")
	)
	(segment
		(start 173.50994 -28.793948)
		(end 173.81982 -28.484068)
		(width 0.14605)
		(layer "B.Cu")
		(net "PCIE_SCC_TO_COMP_C_5_DP")
	)
	(segment
		(start 175.231806 -25.587452)
		(end 175.231806 -25.271476)
		(width 0.14605)
		(layer "B.Cu")
		(net "PCIE_SCC_TO_COMP_C_5_DP")
	)
	(segment
		(start 174.722536 -25.88133)
		(end 174.937928 -25.88133)
		(width 0.14605)
		(layer "B.Cu")
		(net "PCIE_SCC_TO_COMP_C_5_DP")
	)
	(segment
		(start 174.27321 -27.072082)
		(end 174.27321 -26.546048)
		(width 0.14605)
		(layer "B.Cu")
		(net "PCIE_SCC_TO_COMP_C_5_DP")
	)
	(segment
		(start 175.079406 -22.318726)
		(end 175.231806 -22.166326)
		(width 0.14605)
		(layer "B.Cu")
		(net "PCIE_SCC_TO_COMP_C_5_DP")
	)
	(segment
		(start 174.412656 -26.190956)
		(end 174.722536 -25.88133)
		(width 0.14605)
		(layer "B.Cu")
		(net "PCIE_SCC_TO_COMP_C_5_DP")
	)
	(segment
		(start 173.800008 -31.599886)
		(end 173.400212 -31.20009)
		(width 0.1397)
		(layer "F.Cu")
		(net "PCIE_SCC_TO_COMP_C_5_DN")
	)
	(via
		(at 173.400212 -31.20009)
		(size 0.4572)
		(drill 0.2032)
		(layers "F.Cu" "B.Cu")
		(net "PCIE_SCC_TO_COMP_C_5_DN")
	)
	(segment
		(start 174.58436 -28.375356)
		(end 174.58436 -26.67508)
		(width 0.14605)
		(layer "B.Cu")
		(net "PCIE_SCC_TO_COMP_C_5_DN")
	)
	(segment
		(start 174.58436 -26.67508)
		(end 175.542956 -25.716484)
		(width 0.14605)
		(layer "B.Cu")
		(net "PCIE_SCC_TO_COMP_C_5_DN")
	)
	(segment
		(start 173.760892 -29.487622)
		(end 173.760892 -29.464)
		(width 0.09525)
		(layer "B.Cu")
		(net "PCIE_SCC_TO_COMP_C_5_DN")
	)
	(segment
		(start 173.809914 -30.196536)
		(end 173.697392 -30.084014)
		(width 0.09525)
		(layer "B.Cu")
		(net "PCIE_SCC_TO_COMP_C_5_DN")
	)
	(segment
		(start 173.760892 -29.198824)
		(end 174.58436 -28.375356)
		(width 0.14605)
		(layer "B.Cu")
		(net "PCIE_SCC_TO_COMP_C_5_DN")
	)
	(segment
		(start 173.697392 -29.551122)
		(end 173.760892 -29.487622)
		(width 0.09525)
		(layer "B.Cu")
		(net "PCIE_SCC_TO_COMP_C_5_DN")
	)
	(segment
		(start 175.542956 -25.716484)
		(end 175.542956 -21.580602)
		(width 0.14605)
		(layer "B.Cu")
		(net "PCIE_SCC_TO_COMP_C_5_DN")
	)
	(segment
		(start 175.542956 -21.580602)
		(end 175.611028 -21.51253)
		(width 0.14605)
		(layer "B.Cu")
		(net "PCIE_SCC_TO_COMP_C_5_DN")
	)
	(segment
		(start 173.760892 -29.464)
		(end 173.760892 -29.198824)
		(width 0.14605)
		(layer "B.Cu")
		(net "PCIE_SCC_TO_COMP_C_5_DN")
	)
	(segment
		(start 173.400212 -31.20009)
		(end 173.809914 -30.505146)
		(width 0.09525)
		(layer "B.Cu")
		(net "PCIE_SCC_TO_COMP_C_5_DN")
	)
	(segment
		(start 173.697392 -30.084014)
		(end 173.697392 -29.551122)
		(width 0.09525)
		(layer "B.Cu")
		(net "PCIE_SCC_TO_COMP_C_5_DN")
	)
	(segment
		(start 173.809914 -30.505146)
		(end 173.809914 -30.196536)
		(width 0.09525)
		(layer "B.Cu")
		(net "PCIE_SCC_TO_COMP_C_5_DN")
	)
	(segment
		(start 175.611028 -21.51253)
		(end 175.611028 -21.234146)
		(width 0.14605)
		(layer "B.Cu")
		(net "PCIE_SCC_TO_COMP_C_5_DN")
	)
	(segment
		(start 172.999908 -30.80004)
		(end 172.599858 -30.39999)
		(width 0.14605)
		(layer "F.Cu")
		(net "PCIE_SCC_TO_COMP_C_4_DP")
	)
	(via
		(at 172.599858 -30.39999)
		(size 0.4572)
		(drill 0.2032)
		(layers "F.Cu" "B.Cu")
		(net "PCIE_SCC_TO_COMP_C_4_DP")
	)
	(segment
		(start 173.204632 -23.196804)
		(end 173.204632 -22.758654)
		(width 0.14605)
		(layer "B.Cu")
		(net "PCIE_SCC_TO_COMP_C_4_DP")
	)
	(segment
		(start 173.204632 -21.456904)
		(end 173.045882 -21.298154)
		(width 0.14605)
		(layer "B.Cu")
		(net "PCIE_SCC_TO_COMP_C_4_DP")
	)
	(segment
		(start 173.204632 -22.758654)
		(end 173.039532 -22.593554)
		(width 0.14605)
		(layer "B.Cu")
		(net "PCIE_SCC_TO_COMP_C_4_DP")
	)
	(segment
		(start 173.039532 -22.593554)
		(end 173.039532 -22.155404)
		(width 0.14605)
		(layer "B.Cu")
		(net "PCIE_SCC_TO_COMP_C_4_DP")
	)
	(segment
		(start 173.039532 -24.568404)
		(end 173.204632 -24.403304)
		(width 0.14605)
		(layer "B.Cu")
		(net "PCIE_SCC_TO_COMP_C_4_DP")
	)
	(segment
		(start 173.039532 -22.155404)
		(end 173.204632 -21.990304)
		(width 0.14605)
		(layer "B.Cu")
		(net "PCIE_SCC_TO_COMP_C_4_DP")
	)
	(segment
		(start 173.039532 -23.800054)
		(end 173.039532 -23.361904)
		(width 0.14605)
		(layer "B.Cu")
		(net "PCIE_SCC_TO_COMP_C_4_DP")
	)
	(segment
		(start 173.204632 -27.584654)
		(end 173.039532 -27.419554)
		(width 0.14605)
		(layer "B.Cu")
		(net "PCIE_SCC_TO_COMP_C_4_DP")
	)
	(segment
		(start 172.74413 -29.718)
		(end 172.74413 -28.483306)
		(width 0.14605)
		(layer "B.Cu")
		(net "PCIE_SCC_TO_COMP_C_4_DP")
	)
	(segment
		(start 173.204632 -26.378154)
		(end 173.039532 -26.213054)
		(width 0.14605)
		(layer "B.Cu")
		(net "PCIE_SCC_TO_COMP_C_4_DP")
	)
	(segment
		(start 173.204632 -23.965154)
		(end 173.039532 -23.800054)
		(width 0.14605)
		(layer "B.Cu")
		(net "PCIE_SCC_TO_COMP_C_4_DP")
	)
	(segment
		(start 172.80763 -29.805122)
		(end 172.74413 -29.741622)
		(width 0.09525)
		(layer "B.Cu")
		(net "PCIE_SCC_TO_COMP_C_4_DP")
	)
	(segment
		(start 173.039532 -25.006554)
		(end 173.039532 -24.568404)
		(width 0.14605)
		(layer "B.Cu")
		(net "PCIE_SCC_TO_COMP_C_4_DP")
	)
	(segment
		(start 172.74413 -28.483306)
		(end 173.204632 -28.022804)
		(width 0.14605)
		(layer "B.Cu")
		(net "PCIE_SCC_TO_COMP_C_4_DP")
	)
	(segment
		(start 173.204632 -21.990304)
		(end 173.204632 -21.456904)
		(width 0.14605)
		(layer "B.Cu")
		(net "PCIE_SCC_TO_COMP_C_4_DP")
	)
	(segment
		(start 172.74413 -29.741622)
		(end 172.74413 -29.718)
		(width 0.09525)
		(layer "B.Cu")
		(net "PCIE_SCC_TO_COMP_C_4_DP")
	)
	(segment
		(start 173.204632 -25.171654)
		(end 173.039532 -25.006554)
		(width 0.14605)
		(layer "B.Cu")
		(net "PCIE_SCC_TO_COMP_C_4_DP")
	)
	(segment
		(start 173.204632 -28.022804)
		(end 173.204632 -27.584654)
		(width 0.14605)
		(layer "B.Cu")
		(net "PCIE_SCC_TO_COMP_C_4_DP")
	)
	(segment
		(start 173.039532 -26.981404)
		(end 173.204632 -26.816304)
		(width 0.14605)
		(layer "B.Cu")
		(net "PCIE_SCC_TO_COMP_C_4_DP")
	)
	(segment
		(start 173.039532 -25.774904)
		(end 173.204632 -25.609804)
		(width 0.14605)
		(layer "B.Cu")
		(net "PCIE_SCC_TO_COMP_C_4_DP")
	)
	(segment
		(start 173.045882 -21.298154)
		(end 173.045882 -21.165566)
		(width 0.14605)
		(layer "B.Cu")
		(net "PCIE_SCC_TO_COMP_C_4_DP")
	)
	(segment
		(start 173.204632 -25.609804)
		(end 173.204632 -25.171654)
		(width 0.14605)
		(layer "B.Cu")
		(net "PCIE_SCC_TO_COMP_C_4_DP")
	)
	(segment
		(start 173.039532 -26.213054)
		(end 173.039532 -25.774904)
		(width 0.14605)
		(layer "B.Cu")
		(net "PCIE_SCC_TO_COMP_C_4_DP")
	)
	(segment
		(start 172.599858 -30.39999)
		(end 172.80763 -30.192218)
		(width 0.09525)
		(layer "B.Cu")
		(net "PCIE_SCC_TO_COMP_C_4_DP")
	)
	(segment
		(start 173.039532 -27.419554)
		(end 173.039532 -26.981404)
		(width 0.14605)
		(layer "B.Cu")
		(net "PCIE_SCC_TO_COMP_C_4_DP")
	)
	(segment
		(start 173.039532 -23.361904)
		(end 173.204632 -23.196804)
		(width 0.14605)
		(layer "B.Cu")
		(net "PCIE_SCC_TO_COMP_C_4_DP")
	)
	(segment
		(start 173.204632 -24.403304)
		(end 173.204632 -23.965154)
		(width 0.14605)
		(layer "B.Cu")
		(net "PCIE_SCC_TO_COMP_C_4_DP")
	)
	(segment
		(start 172.80763 -30.192218)
		(end 172.80763 -29.805122)
		(width 0.09525)
		(layer "B.Cu")
		(net "PCIE_SCC_TO_COMP_C_4_DP")
	)
	(segment
		(start 173.204632 -26.816304)
		(end 173.204632 -26.378154)
		(width 0.14605)
		(layer "B.Cu")
		(net "PCIE_SCC_TO_COMP_C_4_DP")
	)
	(segment
		(start 172.999908 -31.599886)
		(end 172.600112 -31.20009)
		(width 0.1397)
		(layer "F.Cu")
		(net "PCIE_SCC_TO_COMP_C_4_DN")
	)
	(via
		(at 172.600112 -31.20009)
		(size 0.4572)
		(drill 0.2032)
		(layers "F.Cu" "B.Cu")
		(net "PCIE_SCC_TO_COMP_C_4_DN")
	)
	(segment
		(start 172.99178 -30.22473)
		(end 172.99178 -29.805122)
		(width 0.09525)
		(layer "B.Cu")
		(net "PCIE_SCC_TO_COMP_C_4_DN")
	)
	(segment
		(start 172.999908 -30.234382)
		(end 173.00067 -30.23362)
		(width 0.09525)
		(layer "B.Cu")
		(net "PCIE_SCC_TO_COMP_C_4_DN")
	)
	(segment
		(start 173.05528 -29.718)
		(end 173.05528 -28.612338)
		(width 0.14605)
		(layer "B.Cu")
		(net "PCIE_SCC_TO_COMP_C_4_DN")
	)
	(segment
		(start 173.515782 -21.444458)
		(end 173.625002 -21.335238)
		(width 0.14605)
		(layer "B.Cu")
		(net "PCIE_SCC_TO_COMP_C_4_DN")
	)
	(segment
		(start 173.05528 -29.741622)
		(end 173.05528 -29.718)
		(width 0.09525)
		(layer "B.Cu")
		(net "PCIE_SCC_TO_COMP_C_4_DN")
	)
	(segment
		(start 173.00067 -30.23362)
		(end 172.99178 -30.22473)
		(width 0.09525)
		(layer "B.Cu")
		(net "PCIE_SCC_TO_COMP_C_4_DN")
	)
	(segment
		(start 172.999908 -30.52191)
		(end 172.999908 -30.234382)
		(width 0.09525)
		(layer "B.Cu")
		(net "PCIE_SCC_TO_COMP_C_4_DN")
	)
	(segment
		(start 173.515782 -28.151836)
		(end 173.515782 -21.444458)
		(width 0.14605)
		(layer "B.Cu")
		(net "PCIE_SCC_TO_COMP_C_4_DN")
	)
	(segment
		(start 173.05528 -28.612338)
		(end 173.515782 -28.151836)
		(width 0.14605)
		(layer "B.Cu")
		(net "PCIE_SCC_TO_COMP_C_4_DN")
	)
	(segment
		(start 172.600112 -31.20009)
		(end 172.999908 -30.52191)
		(width 0.09525)
		(layer "B.Cu")
		(net "PCIE_SCC_TO_COMP_C_4_DN")
	)
	(segment
		(start 173.625002 -21.335238)
		(end 173.625002 -21.16582)
		(width 0.14605)
		(layer "B.Cu")
		(net "PCIE_SCC_TO_COMP_C_4_DN")
	)
	(segment
		(start 172.99178 -29.805122)
		(end 173.05528 -29.741622)
		(width 0.09525)
		(layer "B.Cu")
		(net "PCIE_SCC_TO_COMP_C_4_DN")
	)
	(segment
		(start 170.999912 -30.39999)
		(end 171.399962 -30.80004)
		(width 0.14605)
		(layer "F.Cu")
		(net "PCIE_SCC_TO_COMP_C_3_DP")
	)
	(via
		(at 170.999912 -30.39999)
		(size 0.4572)
		(drill 0.2032)
		(layers "F.Cu" "B.Cu")
		(net "PCIE_SCC_TO_COMP_C_3_DP")
	)
	(segment
		(start 170.974258 -23.258526)
		(end 171.126658 -23.106126)
		(width 0.14605)
		(layer "B.Cu")
		(net "PCIE_SCC_TO_COMP_C_3_DP")
	)
	(segment
		(start 170.974258 -24.439626)
		(end 171.126658 -24.287226)
		(width 0.14605)
		(layer "B.Cu")
		(net "PCIE_SCC_TO_COMP_C_3_DP")
	)
	(segment
		(start 171.126658 -29.035248)
		(end 171.126658 -29.011626)
		(width 0.09525)
		(layer "B.Cu")
		(net "PCIE_SCC_TO_COMP_C_3_DP")
	)
	(segment
		(start 170.974258 -25.620726)
		(end 171.126658 -25.468326)
		(width 0.14605)
		(layer "B.Cu")
		(net "PCIE_SCC_TO_COMP_C_3_DP")
	)
	(segment
		(start 170.999912 -30.39999)
		(end 171.190158 -30.209744)
		(width 0.09525)
		(layer "B.Cu")
		(net "PCIE_SCC_TO_COMP_C_3_DP")
	)
	(segment
		(start 171.190158 -30.209744)
		(end 171.190158 -29.098748)
		(width 0.09525)
		(layer "B.Cu")
		(net "PCIE_SCC_TO_COMP_C_3_DP")
	)
	(segment
		(start 171.126658 -25.030176)
		(end 170.974258 -24.877776)
		(width 0.14605)
		(layer "B.Cu")
		(net "PCIE_SCC_TO_COMP_C_3_DP")
	)
	(segment
		(start 171.126658 -28.639008)
		(end 170.941492 -28.453842)
		(width 0.14605)
		(layer "B.Cu")
		(net "PCIE_SCC_TO_COMP_C_3_DP")
	)
	(segment
		(start 171.126658 -23.849076)
		(end 170.974258 -23.696676)
		(width 0.14605)
		(layer "B.Cu")
		(net "PCIE_SCC_TO_COMP_C_3_DP")
	)
	(segment
		(start 171.126658 -21.925026)
		(end 171.126658 -21.511768)
		(width 0.14605)
		(layer "B.Cu")
		(net "PCIE_SCC_TO_COMP_C_3_DP")
	)
	(segment
		(start 170.974258 -26.801826)
		(end 171.126658 -26.649426)
		(width 0.14605)
		(layer "B.Cu")
		(net "PCIE_SCC_TO_COMP_C_3_DP")
	)
	(segment
		(start 171.126658 -26.649426)
		(end 171.126658 -26.211276)
		(width 0.14605)
		(layer "B.Cu")
		(net "PCIE_SCC_TO_COMP_C_3_DP")
	)
	(segment
		(start 171.126658 -27.392376)
		(end 170.974258 -27.239976)
		(width 0.14605)
		(layer "B.Cu")
		(net "PCIE_SCC_TO_COMP_C_3_DP")
	)
	(segment
		(start 170.974258 -22.515576)
		(end 170.974258 -22.077426)
		(width 0.14605)
		(layer "B.Cu")
		(net "PCIE_SCC_TO_COMP_C_3_DP")
	)
	(segment
		(start 170.974258 -23.696676)
		(end 170.974258 -23.258526)
		(width 0.14605)
		(layer "B.Cu")
		(net "PCIE_SCC_TO_COMP_C_3_DP")
	)
	(segment
		(start 171.126658 -22.667976)
		(end 170.974258 -22.515576)
		(width 0.14605)
		(layer "B.Cu")
		(net "PCIE_SCC_TO_COMP_C_3_DP")
	)
	(segment
		(start 170.974258 -24.877776)
		(end 170.974258 -24.439626)
		(width 0.14605)
		(layer "B.Cu")
		(net "PCIE_SCC_TO_COMP_C_3_DP")
	)
	(segment
		(start 171.126658 -27.830526)
		(end 171.126658 -27.392376)
		(width 0.14605)
		(layer "B.Cu")
		(net "PCIE_SCC_TO_COMP_C_3_DP")
	)
	(segment
		(start 170.974258 -26.058876)
		(end 170.974258 -25.620726)
		(width 0.14605)
		(layer "B.Cu")
		(net "PCIE_SCC_TO_COMP_C_3_DP")
	)
	(segment
		(start 171.190158 -29.098748)
		(end 171.126658 -29.035248)
		(width 0.09525)
		(layer "B.Cu")
		(net "PCIE_SCC_TO_COMP_C_3_DP")
	)
	(segment
		(start 171.126658 -25.468326)
		(end 171.126658 -25.030176)
		(width 0.14605)
		(layer "B.Cu")
		(net "PCIE_SCC_TO_COMP_C_3_DP")
	)
	(segment
		(start 171.126658 -23.106126)
		(end 171.126658 -22.667976)
		(width 0.14605)
		(layer "B.Cu")
		(net "PCIE_SCC_TO_COMP_C_3_DP")
	)
	(segment
		(start 170.941492 -28.453842)
		(end 170.941492 -28.015692)
		(width 0.14605)
		(layer "B.Cu")
		(net "PCIE_SCC_TO_COMP_C_3_DP")
	)
	(segment
		(start 171.126658 -21.511768)
		(end 170.923204 -21.308314)
		(width 0.14605)
		(layer "B.Cu")
		(net "PCIE_SCC_TO_COMP_C_3_DP")
	)
	(segment
		(start 171.126658 -29.011626)
		(end 171.126658 -28.639008)
		(width 0.14605)
		(layer "B.Cu")
		(net "PCIE_SCC_TO_COMP_C_3_DP")
	)
	(segment
		(start 170.923204 -21.308314)
		(end 170.923204 -21.16582)
		(width 0.14605)
		(layer "B.Cu")
		(net "PCIE_SCC_TO_COMP_C_3_DP")
	)
	(segment
		(start 171.126658 -26.211276)
		(end 170.974258 -26.058876)
		(width 0.14605)
		(layer "B.Cu")
		(net "PCIE_SCC_TO_COMP_C_3_DP")
	)
	(segment
		(start 170.941492 -28.015692)
		(end 171.126658 -27.830526)
		(width 0.14605)
		(layer "B.Cu")
		(net "PCIE_SCC_TO_COMP_C_3_DP")
	)
	(segment
		(start 171.126658 -24.287226)
		(end 171.126658 -23.849076)
		(width 0.14605)
		(layer "B.Cu")
		(net "PCIE_SCC_TO_COMP_C_3_DP")
	)
	(segment
		(start 170.974258 -27.239976)
		(end 170.974258 -26.801826)
		(width 0.14605)
		(layer "B.Cu")
		(net "PCIE_SCC_TO_COMP_C_3_DP")
	)
	(segment
		(start 170.974258 -22.077426)
		(end 171.126658 -21.925026)
		(width 0.14605)
		(layer "B.Cu")
		(net "PCIE_SCC_TO_COMP_C_3_DP")
	)
	(segment
		(start 171.399962 -31.599886)
		(end 171.000166 -31.20009)
		(width 0.1397)
		(layer "F.Cu")
		(net "PCIE_SCC_TO_COMP_C_3_DN")
	)
	(via
		(at 171.000166 -31.20009)
		(size 0.4572)
		(drill 0.2032)
		(layers "F.Cu" "B.Cu")
		(net "PCIE_SCC_TO_COMP_C_3_DN")
	)
	(segment
		(start 171.374308 -30.163262)
		(end 171.374308 -29.098748)
		(width 0.09525)
		(layer "B.Cu")
		(net "PCIE_SCC_TO_COMP_C_3_DN")
	)
	(segment
		(start 171.532804 -21.358606)
		(end 171.532804 -21.16582)
		(width 0.14605)
		(layer "B.Cu")
		(net "PCIE_SCC_TO_COMP_C_3_DN")
	)
	(segment
		(start 171.437808 -29.011626)
		(end 171.437808 -21.453602)
		(width 0.14605)
		(layer "B.Cu")
		(net "PCIE_SCC_TO_COMP_C_3_DN")
	)
	(segment
		(start 171.390564 -30.567884)
		(end 171.390564 -30.179518)
		(width 0.09525)
		(layer "B.Cu")
		(net "PCIE_SCC_TO_COMP_C_3_DN")
	)
	(segment
		(start 171.374308 -29.098748)
		(end 171.437808 -29.035248)
		(width 0.09525)
		(layer "B.Cu")
		(net "PCIE_SCC_TO_COMP_C_3_DN")
	)
	(segment
		(start 171.000166 -31.20009)
		(end 171.390564 -30.567884)
		(width 0.09525)
		(layer "B.Cu")
		(net "PCIE_SCC_TO_COMP_C_3_DN")
	)
	(segment
		(start 171.437808 -21.453602)
		(end 171.532804 -21.358606)
		(width 0.14605)
		(layer "B.Cu")
		(net "PCIE_SCC_TO_COMP_C_3_DN")
	)
	(segment
		(start 171.437808 -29.035248)
		(end 171.437808 -29.011626)
		(width 0.09525)
		(layer "B.Cu")
		(net "PCIE_SCC_TO_COMP_C_3_DN")
	)
	(segment
		(start 171.390564 -30.179518)
		(end 171.374308 -30.163262)
		(width 0.09525)
		(layer "B.Cu")
		(net "PCIE_SCC_TO_COMP_C_3_DN")
	)
	(segment
		(start 170.599862 -30.80004)
		(end 170.199812 -30.39999)
		(width 0.14605)
		(layer "F.Cu")
		(net "PCIE_SCC_TO_COMP_C_2_DP")
	)
	(via
		(at 170.199812 -30.39999)
		(size 0.4572)
		(drill 0.2032)
		(layers "F.Cu" "B.Cu")
		(net "PCIE_SCC_TO_COMP_C_2_DP")
	)
	(segment
		(start 168.94302 -27.221688)
		(end 168.94302 -26.783538)
		(width 0.14605)
		(layer "B.Cu")
		(net "PCIE_SCC_TO_COMP_C_2_DP")
	)
	(segment
		(start 169.09542 -26.192988)
		(end 168.94302 -26.040588)
		(width 0.14605)
		(layer "B.Cu")
		(net "PCIE_SCC_TO_COMP_C_2_DP")
	)
	(segment
		(start 169.09542 -27.812238)
		(end 169.09542 -27.374088)
		(width 0.14605)
		(layer "B.Cu")
		(net "PCIE_SCC_TO_COMP_C_2_DP")
	)
	(segment
		(start 169.09542 -21.399246)
		(end 168.98239 -21.286216)
		(width 0.14605)
		(layer "B.Cu")
		(net "PCIE_SCC_TO_COMP_C_2_DP")
	)
	(segment
		(start 169.875708 -28.59278)
		(end 169.556684 -28.59278)
		(width 0.14605)
		(layer "B.Cu")
		(net "PCIE_SCC_TO_COMP_C_2_DP")
	)
	(segment
		(start 169.246804 -27.963622)
		(end 169.09542 -27.812238)
		(width 0.14605)
		(layer "B.Cu")
		(net "PCIE_SCC_TO_COMP_C_2_DP")
	)
	(segment
		(start 168.94302 -23.678388)
		(end 168.94302 -23.240238)
		(width 0.14605)
		(layer "B.Cu")
		(net "PCIE_SCC_TO_COMP_C_2_DP")
	)
	(segment
		(start 170.034458 -28.979622)
		(end 170.034458 -28.956)
		(width 0.09525)
		(layer "B.Cu")
		(net "PCIE_SCC_TO_COMP_C_2_DP")
	)
	(segment
		(start 169.09542 -24.268938)
		(end 169.09542 -23.830788)
		(width 0.14605)
		(layer "B.Cu")
		(net "PCIE_SCC_TO_COMP_C_2_DP")
	)
	(segment
		(start 168.94302 -23.240238)
		(end 169.09542 -23.087838)
		(width 0.14605)
		(layer "B.Cu")
		(net "PCIE_SCC_TO_COMP_C_2_DP")
	)
	(segment
		(start 170.034458 -28.956)
		(end 170.034458 -28.75153)
		(width 0.14605)
		(layer "B.Cu")
		(net "PCIE_SCC_TO_COMP_C_2_DP")
	)
	(segment
		(start 169.09542 -22.649688)
		(end 168.94302 -22.497288)
		(width 0.14605)
		(layer "B.Cu")
		(net "PCIE_SCC_TO_COMP_C_2_DP")
	)
	(segment
		(start 170.120564 -29.065728)
		(end 170.034458 -28.979622)
		(width 0.09525)
		(layer "B.Cu")
		(net "PCIE_SCC_TO_COMP_C_2_DP")
	)
	(segment
		(start 170.415712 -29.706316)
		(end 170.120564 -29.411168)
		(width 0.09525)
		(layer "B.Cu")
		(net "PCIE_SCC_TO_COMP_C_2_DP")
	)
	(segment
		(start 170.199812 -30.39999)
		(end 170.415712 -30.18409)
		(width 0.09525)
		(layer "B.Cu")
		(net "PCIE_SCC_TO_COMP_C_2_DP")
	)
	(segment
		(start 168.94302 -22.059138)
		(end 169.09542 -21.906738)
		(width 0.14605)
		(layer "B.Cu")
		(net "PCIE_SCC_TO_COMP_C_2_DP")
	)
	(segment
		(start 169.09542 -21.906738)
		(end 169.09542 -21.399246)
		(width 0.14605)
		(layer "B.Cu")
		(net "PCIE_SCC_TO_COMP_C_2_DP")
	)
	(segment
		(start 169.09542 -23.830788)
		(end 168.94302 -23.678388)
		(width 0.14605)
		(layer "B.Cu")
		(net "PCIE_SCC_TO_COMP_C_2_DP")
	)
	(segment
		(start 170.034458 -28.75153)
		(end 169.930572 -28.647644)
		(width 0.14605)
		(layer "B.Cu")
		(net "PCIE_SCC_TO_COMP_C_2_DP")
	)
	(segment
		(start 169.09542 -25.450038)
		(end 169.09542 -25.011888)
		(width 0.14605)
		(layer "B.Cu")
		(net "PCIE_SCC_TO_COMP_C_2_DP")
	)
	(segment
		(start 168.94302 -24.421338)
		(end 169.09542 -24.268938)
		(width 0.14605)
		(layer "B.Cu")
		(net "PCIE_SCC_TO_COMP_C_2_DP")
	)
	(segment
		(start 169.09542 -27.374088)
		(end 168.94302 -27.221688)
		(width 0.14605)
		(layer "B.Cu")
		(net "PCIE_SCC_TO_COMP_C_2_DP")
	)
	(segment
		(start 168.94302 -24.859488)
		(end 168.94302 -24.421338)
		(width 0.14605)
		(layer "B.Cu")
		(net "PCIE_SCC_TO_COMP_C_2_DP")
	)
	(segment
		(start 168.94302 -26.040588)
		(end 168.94302 -25.602438)
		(width 0.14605)
		(layer "B.Cu")
		(net "PCIE_SCC_TO_COMP_C_2_DP")
	)
	(segment
		(start 168.94302 -25.602438)
		(end 169.09542 -25.450038)
		(width 0.14605)
		(layer "B.Cu")
		(net "PCIE_SCC_TO_COMP_C_2_DP")
	)
	(segment
		(start 169.09542 -25.011888)
		(end 168.94302 -24.859488)
		(width 0.14605)
		(layer "B.Cu")
		(net "PCIE_SCC_TO_COMP_C_2_DP")
	)
	(segment
		(start 169.246804 -28.2829)
		(end 169.246804 -27.963622)
		(width 0.14605)
		(layer "B.Cu")
		(net "PCIE_SCC_TO_COMP_C_2_DP")
	)
	(segment
		(start 169.915078 -28.63215)
		(end 169.875708 -28.59278)
		(width 0.14605)
		(layer "B.Cu")
		(net "PCIE_SCC_TO_COMP_C_2_DP")
	)
	(segment
		(start 168.94302 -26.783538)
		(end 169.09542 -26.631138)
		(width 0.14605)
		(layer "B.Cu")
		(net "PCIE_SCC_TO_COMP_C_2_DP")
	)
	(segment
		(start 169.556684 -28.59278)
		(end 169.246804 -28.2829)
		(width 0.14605)
		(layer "B.Cu")
		(net "PCIE_SCC_TO_COMP_C_2_DP")
	)
	(segment
		(start 169.09542 -26.631138)
		(end 169.09542 -26.192988)
		(width 0.14605)
		(layer "B.Cu")
		(net "PCIE_SCC_TO_COMP_C_2_DP")
	)
	(segment
		(start 169.930572 -28.647644)
		(end 169.915078 -28.63215)
		(width 0.0889)
		(layer "B.Cu")
		(net "PCIE_SCC_TO_COMP_C_2_DP")
	)
	(segment
		(start 169.09542 -23.087838)
		(end 169.09542 -22.649688)
		(width 0.14605)
		(layer "B.Cu")
		(net "PCIE_SCC_TO_COMP_C_2_DP")
	)
	(segment
		(start 168.94302 -22.497288)
		(end 168.94302 -22.059138)
		(width 0.14605)
		(layer "B.Cu")
		(net "PCIE_SCC_TO_COMP_C_2_DP")
	)
	(segment
		(start 170.415712 -30.18409)
		(end 170.415712 -29.706316)
		(width 0.09525)
		(layer "B.Cu")
		(net "PCIE_SCC_TO_COMP_C_2_DP")
	)
	(segment
		(start 170.120564 -29.411168)
		(end 170.120564 -29.065728)
		(width 0.09525)
		(layer "B.Cu")
		(net "PCIE_SCC_TO_COMP_C_2_DP")
	)
	(segment
		(start 170.599862 -31.599886)
		(end 170.200066 -31.20009)
		(width 0.1397)
		(layer "F.Cu")
		(net "PCIE_SCC_TO_COMP_C_2_DN")
	)
	(via
		(at 170.200066 -31.20009)
		(size 0.4572)
		(drill 0.2032)
		(layers "F.Cu" "B.Cu")
		(net "PCIE_SCC_TO_COMP_C_2_DN")
	)
	(segment
		(start 170.345608 -28.622244)
		(end 169.40657 -27.683206)
		(width 0.14605)
		(layer "B.Cu")
		(net "PCIE_SCC_TO_COMP_C_2_DN")
	)
	(segment
		(start 169.40657 -21.434806)
		(end 169.5577 -21.283676)
		(width 0.14605)
		(layer "B.Cu")
		(net "PCIE_SCC_TO_COMP_C_2_DN")
	)
	(segment
		(start 170.304714 -29.020516)
		(end 170.345608 -28.979622)
		(width 0.09525)
		(layer "B.Cu")
		(net "PCIE_SCC_TO_COMP_C_2_DN")
	)
	(segment
		(start 170.345608 -28.956)
		(end 170.345608 -28.622244)
		(width 0.14605)
		(layer "B.Cu")
		(net "PCIE_SCC_TO_COMP_C_2_DN")
	)
	(segment
		(start 170.345608 -28.979622)
		(end 170.345608 -28.956)
		(width 0.09525)
		(layer "B.Cu")
		(net "PCIE_SCC_TO_COMP_C_2_DN")
	)
	(segment
		(start 170.304714 -29.334714)
		(end 170.304714 -29.020516)
		(width 0.09525)
		(layer "B.Cu")
		(net "PCIE_SCC_TO_COMP_C_2_DN")
	)
	(segment
		(start 170.200066 -31.20009)
		(end 170.599862 -30.541722)
		(width 0.09525)
		(layer "B.Cu")
		(net "PCIE_SCC_TO_COMP_C_2_DN")
	)
	(segment
		(start 170.599862 -30.541722)
		(end 170.599862 -29.629862)
		(width 0.09525)
		(layer "B.Cu")
		(net "PCIE_SCC_TO_COMP_C_2_DN")
	)
	(segment
		(start 169.40657 -27.683206)
		(end 169.40657 -21.434806)
		(width 0.14605)
		(layer "B.Cu")
		(net "PCIE_SCC_TO_COMP_C_2_DN")
	)
	(segment
		(start 170.599862 -29.629862)
		(end 170.304714 -29.334714)
		(width 0.09525)
		(layer "B.Cu")
		(net "PCIE_SCC_TO_COMP_C_2_DN")
	)
	(segment
		(start 168.599866 -30.39999)
		(end 168.999916 -30.80004)
		(width 0.14605)
		(layer "F.Cu")
		(net "PCIE_SCC_TO_COMP_C_1_DP")
	)
	(via
		(at 168.599866 -30.39999)
		(size 0.4572)
		(drill 0.2032)
		(layers "F.Cu" "B.Cu")
		(net "PCIE_SCC_TO_COMP_C_1_DP")
	)
	(segment
		(start 166.90848 -25.923748)
		(end 167.06088 -25.771348)
		(width 0.14605)
		(layer "B.Cu")
		(net "PCIE_SCC_TO_COMP_C_1_DP")
	)
	(segment
		(start 167.06088 -22.970998)
		(end 166.90848 -22.818598)
		(width 0.14605)
		(layer "B.Cu")
		(net "PCIE_SCC_TO_COMP_C_1_DP")
	)
	(segment
		(start 167.06088 -21.936456)
		(end 166.819834 -21.69541)
		(width 0.14605)
		(layer "B.Cu")
		(net "PCIE_SCC_TO_COMP_C_1_DP")
	)
	(segment
		(start 166.90848 -23.561548)
		(end 167.06088 -23.409148)
		(width 0.14605)
		(layer "B.Cu")
		(net "PCIE_SCC_TO_COMP_C_1_DP")
	)
	(segment
		(start 168.441624 -28.171902)
		(end 168.331388 -28.061412)
		(width 0.09525)
		(layer "B.Cu")
		(net "PCIE_SCC_TO_COMP_C_1_DP")
	)
	(segment
		(start 168.547288 -28.277312)
		(end 168.441624 -28.171902)
		(width 0.09525)
		(layer "B.Cu")
		(net "PCIE_SCC_TO_COMP_C_1_DP")
	)
	(segment
		(start 166.90848 -22.380448)
		(end 167.06088 -22.228048)
		(width 0.14605)
		(layer "B.Cu")
		(net "PCIE_SCC_TO_COMP_C_1_DP")
	)
	(segment
		(start 166.90848 -23.999698)
		(end 166.90848 -23.561548)
		(width 0.14605)
		(layer "B.Cu")
		(net "PCIE_SCC_TO_COMP_C_1_DP")
	)
	(segment
		(start 167.06088 -22.228048)
		(end 167.06088 -21.936456)
		(width 0.14605)
		(layer "B.Cu")
		(net "PCIE_SCC_TO_COMP_C_1_DP")
	)
	(segment
		(start 167.81907 -27.661362)
		(end 167.603678 -27.661362)
		(width 0.14605)
		(layer "B.Cu")
		(net "PCIE_SCC_TO_COMP_C_1_DP")
	)
	(segment
		(start 167.06088 -25.333198)
		(end 166.90848 -25.180798)
		(width 0.14605)
		(layer "B.Cu")
		(net "PCIE_SCC_TO_COMP_C_1_DP")
	)
	(segment
		(start 167.06088 -26.514298)
		(end 166.90848 -26.361898)
		(width 0.14605)
		(layer "B.Cu")
		(net "PCIE_SCC_TO_COMP_C_1_DP")
	)
	(segment
		(start 168.190164 -28.032456)
		(end 168.1734 -28.015692)
		(width 0.09525)
		(layer "B.Cu")
		(net "PCIE_SCC_TO_COMP_C_1_DP")
	)
	(segment
		(start 168.302432 -28.032456)
		(end 168.190164 -28.032456)
		(width 0.09525)
		(layer "B.Cu")
		(net "PCIE_SCC_TO_COMP_C_1_DP")
	)
	(segment
		(start 167.06088 -25.771348)
		(end 167.06088 -25.333198)
		(width 0.14605)
		(layer "B.Cu")
		(net "PCIE_SCC_TO_COMP_C_1_DP")
	)
	(segment
		(start 167.06088 -24.152098)
		(end 166.90848 -23.999698)
		(width 0.14605)
		(layer "B.Cu")
		(net "PCIE_SCC_TO_COMP_C_1_DP")
	)
	(segment
		(start 167.293798 -27.13609)
		(end 167.06088 -26.903172)
		(width 0.14605)
		(layer "B.Cu")
		(net "PCIE_SCC_TO_COMP_C_1_DP")
	)
	(segment
		(start 168.1734 -28.015692)
		(end 167.81907 -27.661362)
		(width 0.14605)
		(layer "B.Cu")
		(net "PCIE_SCC_TO_COMP_C_1_DP")
	)
	(segment
		(start 166.90848 -25.180798)
		(end 166.90848 -24.742648)
		(width 0.14605)
		(layer "B.Cu")
		(net "PCIE_SCC_TO_COMP_C_1_DP")
	)
	(segment
		(start 166.90848 -26.361898)
		(end 166.90848 -25.923748)
		(width 0.14605)
		(layer "B.Cu")
		(net "PCIE_SCC_TO_COMP_C_1_DP")
	)
	(segment
		(start 166.819834 -21.69541)
		(end 166.819834 -21.277834)
		(width 0.14605)
		(layer "B.Cu")
		(net "PCIE_SCC_TO_COMP_C_1_DP")
	)
	(segment
		(start 167.06088 -26.903172)
		(end 167.06088 -26.514298)
		(width 0.14605)
		(layer "B.Cu")
		(net "PCIE_SCC_TO_COMP_C_1_DP")
	)
	(segment
		(start 166.90848 -24.742648)
		(end 167.06088 -24.590248)
		(width 0.14605)
		(layer "B.Cu")
		(net "PCIE_SCC_TO_COMP_C_1_DP")
	)
	(segment
		(start 168.599866 -30.39999)
		(end 168.80205 -30.197806)
		(width 0.09525)
		(layer "B.Cu")
		(net "PCIE_SCC_TO_COMP_C_1_DP")
	)
	(segment
		(start 168.80205 -28.532074)
		(end 168.547288 -28.277312)
		(width 0.09525)
		(layer "B.Cu")
		(net "PCIE_SCC_TO_COMP_C_1_DP")
	)
	(segment
		(start 167.603678 -27.661362)
		(end 167.293798 -27.351482)
		(width 0.14605)
		(layer "B.Cu")
		(net "PCIE_SCC_TO_COMP_C_1_DP")
	)
	(segment
		(start 166.90848 -22.818598)
		(end 166.90848 -22.380448)
		(width 0.14605)
		(layer "B.Cu")
		(net "PCIE_SCC_TO_COMP_C_1_DP")
	)
	(segment
		(start 167.06088 -23.409148)
		(end 167.06088 -22.970998)
		(width 0.14605)
		(layer "B.Cu")
		(net "PCIE_SCC_TO_COMP_C_1_DP")
	)
	(segment
		(start 166.64432 -21.10232)
		(end 166.64432 -20.852384)
		(width 0.14605)
		(layer "B.Cu")
		(net "PCIE_SCC_TO_COMP_C_1_DP")
	)
	(segment
		(start 166.819834 -21.277834)
		(end 166.64432 -21.10232)
		(width 0.14605)
		(layer "B.Cu")
		(net "PCIE_SCC_TO_COMP_C_1_DP")
	)
	(segment
		(start 167.06088 -24.590248)
		(end 167.06088 -24.152098)
		(width 0.14605)
		(layer "B.Cu")
		(net "PCIE_SCC_TO_COMP_C_1_DP")
	)
	(segment
		(start 168.80205 -30.197806)
		(end 168.80205 -28.532074)
		(width 0.09525)
		(layer "B.Cu")
		(net "PCIE_SCC_TO_COMP_C_1_DP")
	)
	(segment
		(start 168.331388 -28.061412)
		(end 168.302432 -28.032456)
		(width 0.09525)
		(layer "B.Cu")
		(net "PCIE_SCC_TO_COMP_C_1_DP")
	)
	(segment
		(start 167.293798 -27.351482)
		(end 167.293798 -27.13609)
		(width 0.14605)
		(layer "B.Cu")
		(net "PCIE_SCC_TO_COMP_C_1_DP")
	)
	(segment
		(start 168.999916 -31.599886)
		(end 168.599866 -31.199836)
		(width 0.14605)
		(layer "F.Cu")
		(net "PCIE_SCC_TO_COMP_C_1_DN")
	)
	(via
		(at 168.599866 -31.199836)
		(size 0.4572)
		(drill 0.2032)
		(layers "F.Cu" "B.Cu")
		(net "PCIE_SCC_TO_COMP_C_1_DN")
	)
	(segment
		(start 167.130984 -21.235416)
		(end 167.27932 -21.08708)
		(width 0.14605)
		(layer "B.Cu")
		(net "PCIE_SCC_TO_COMP_C_1_DN")
	)
	(segment
		(start 168.397682 -27.799792)
		(end 168.380918 -27.783028)
		(width 0.09525)
		(layer "B.Cu")
		(net "PCIE_SCC_TO_COMP_C_1_DN")
	)
	(segment
		(start 168.380918 -27.783028)
		(end 167.37203 -26.77414)
		(width 0.14605)
		(layer "B.Cu")
		(net "PCIE_SCC_TO_COMP_C_1_DN")
	)
	(segment
		(start 168.397682 -27.867102)
		(end 168.397682 -27.799792)
		(width 0.09525)
		(layer "B.Cu")
		(net "PCIE_SCC_TO_COMP_C_1_DN")
	)
	(segment
		(start 167.130984 -21.566378)
		(end 167.130984 -21.235416)
		(width 0.14605)
		(layer "B.Cu")
		(net "PCIE_SCC_TO_COMP_C_1_DN")
	)
	(segment
		(start 167.37203 -21.807424)
		(end 167.130984 -21.566378)
		(width 0.14605)
		(layer "B.Cu")
		(net "PCIE_SCC_TO_COMP_C_1_DN")
	)
	(segment
		(start 168.9862 -30.570932)
		(end 168.9862 -28.45562)
		(width 0.09525)
		(layer "B.Cu")
		(net "PCIE_SCC_TO_COMP_C_1_DN")
	)
	(segment
		(start 167.37203 -26.77414)
		(end 167.37203 -21.807424)
		(width 0.14605)
		(layer "B.Cu")
		(net "PCIE_SCC_TO_COMP_C_1_DN")
	)
	(segment
		(start 168.599866 -31.199836)
		(end 168.9862 -30.570932)
		(width 0.09525)
		(layer "B.Cu")
		(net "PCIE_SCC_TO_COMP_C_1_DN")
	)
	(segment
		(start 167.27932 -21.08708)
		(end 167.27932 -20.852384)
		(width 0.14605)
		(layer "B.Cu")
		(net "PCIE_SCC_TO_COMP_C_1_DN")
	)
	(segment
		(start 168.9862 -28.45562)
		(end 168.67759 -28.146756)
		(width 0.09525)
		(layer "B.Cu")
		(net "PCIE_SCC_TO_COMP_C_1_DN")
	)
	(segment
		(start 168.67759 -28.146756)
		(end 168.571926 -28.041346)
		(width 0.09525)
		(layer "B.Cu")
		(net "PCIE_SCC_TO_COMP_C_1_DN")
	)
	(segment
		(start 168.571926 -28.041346)
		(end 168.397682 -27.867102)
		(width 0.09525)
		(layer "B.Cu")
		(net "PCIE_SCC_TO_COMP_C_1_DN")
	)
	(segment
		(start 168.199816 -30.80004)
		(end 167.799766 -30.39999)
		(width 0.14605)
		(layer "F.Cu")
		(net "PCIE_SCC_TO_COMP_C_0_DP")
	)
	(via
		(at 167.799766 -30.39999)
		(size 0.4572)
		(drill 0.2032)
		(layers "F.Cu" "B.Cu")
		(net "PCIE_SCC_TO_COMP_C_0_DP")
	)
	(segment
		(start 164.916358 -24.097234)
		(end 164.916358 -24.535384)
		(width 0.14605)
		(layer "B.Cu")
		(net "PCIE_SCC_TO_COMP_C_0_DP")
	)
	(segment
		(start 167.924734 -30.27426)
		(end 167.799766 -30.39999)
		(width 0.09525)
		(layer "B.Cu")
		(net "PCIE_SCC_TO_COMP_C_0_DP")
	)
	(segment
		(start 167.952166 -30.247082)
		(end 167.924734 -30.27426)
		(width 0.09525)
		(layer "B.Cu")
		(net "PCIE_SCC_TO_COMP_C_0_DP")
	)
	(segment
		(start 165.893496 -26.957274)
		(end 165.893496 -27.172666)
		(width 0.14605)
		(layer "B.Cu")
		(net "PCIE_SCC_TO_COMP_C_0_DP")
	)
	(segment
		(start 167.038528 -28.317698)
		(end 167.25392 -28.317698)
		(width 0.14605)
		(layer "B.Cu")
		(net "PCIE_SCC_TO_COMP_C_0_DP")
	)
	(segment
		(start 165.068758 -23.506684)
		(end 165.068758 -23.944834)
		(width 0.14605)
		(layer "B.Cu")
		(net "PCIE_SCC_TO_COMP_C_0_DP")
	)
	(segment
		(start 165.068758 -25.125934)
		(end 164.916358 -25.278334)
		(width 0.14605)
		(layer "B.Cu")
		(net "PCIE_SCC_TO_COMP_C_0_DP")
	)
	(segment
		(start 164.923978 -20.862544)
		(end 164.923978 -21.018246)
		(width 0.14605)
		(layer "B.Cu")
		(net "PCIE_SCC_TO_COMP_C_0_DP")
	)
	(segment
		(start 165.068758 -21.163026)
		(end 165.068758 -21.582634)
		(width 0.14605)
		(layer "B.Cu")
		(net "PCIE_SCC_TO_COMP_C_0_DP")
	)
	(segment
		(start 164.922962 -23.360888)
		(end 165.068758 -23.506684)
		(width 0.14605)
		(layer "B.Cu")
		(net "PCIE_SCC_TO_COMP_C_0_DP")
	)
	(segment
		(start 164.916358 -25.278334)
		(end 164.916358 -25.716484)
		(width 0.14605)
		(layer "B.Cu")
		(net "PCIE_SCC_TO_COMP_C_0_DP")
	)
	(segment
		(start 165.068758 -25.868884)
		(end 165.068758 -26.132536)
		(width 0.14605)
		(layer "B.Cu")
		(net "PCIE_SCC_TO_COMP_C_0_DP")
	)
	(segment
		(start 164.922962 -22.90953)
		(end 164.922962 -23.360888)
		(width 0.14605)
		(layer "B.Cu")
		(net "PCIE_SCC_TO_COMP_C_0_DP")
	)
	(segment
		(start 165.068758 -23.944834)
		(end 164.916358 -24.097234)
		(width 0.14605)
		(layer "B.Cu")
		(net "PCIE_SCC_TO_COMP_C_0_DP")
	)
	(segment
		(start 167.590978 -28.654502)
		(end 167.667432 -28.730956)
		(width 0.14605)
		(layer "B.Cu")
		(net "PCIE_SCC_TO_COMP_C_0_DP")
	)
	(segment
		(start 168.01465 -30.02915)
		(end 168.01465 -30.184852)
		(width 0.09525)
		(layer "B.Cu")
		(net "PCIE_SCC_TO_COMP_C_0_DP")
	)
	(segment
		(start 167.25392 -28.317698)
		(end 167.590724 -28.654502)
		(width 0.14605)
		(layer "B.Cu")
		(net "PCIE_SCC_TO_COMP_C_0_DP")
	)
	(segment
		(start 165.893496 -27.172666)
		(end 166.203376 -27.482546)
		(width 0.14605)
		(layer "B.Cu")
		(net "PCIE_SCC_TO_COMP_C_0_DP")
	)
	(segment
		(start 164.916358 -22.173184)
		(end 165.068758 -22.325584)
		(width 0.14605)
		(layer "B.Cu")
		(net "PCIE_SCC_TO_COMP_C_0_DP")
	)
	(segment
		(start 165.068758 -22.763734)
		(end 164.922962 -22.90953)
		(width 0.14605)
		(layer "B.Cu")
		(net "PCIE_SCC_TO_COMP_C_0_DP")
	)
	(segment
		(start 167.590724 -28.654502)
		(end 167.590978 -28.654502)
		(width 0.14605)
		(layer "B.Cu")
		(net "PCIE_SCC_TO_COMP_C_0_DP")
	)
	(segment
		(start 167.667432 -28.730956)
		(end 167.684196 -28.74772)
		(width 0.09525)
		(layer "B.Cu")
		(net "PCIE_SCC_TO_COMP_C_0_DP")
	)
	(segment
		(start 165.068758 -24.687784)
		(end 165.068758 -25.125934)
		(width 0.14605)
		(layer "B.Cu")
		(net "PCIE_SCC_TO_COMP_C_0_DP")
	)
	(segment
		(start 165.068758 -26.132536)
		(end 165.893496 -26.957274)
		(width 0.14605)
		(layer "B.Cu")
		(net "PCIE_SCC_TO_COMP_C_0_DP")
	)
	(segment
		(start 164.923978 -21.018246)
		(end 165.068758 -21.163026)
		(width 0.14605)
		(layer "B.Cu")
		(net "PCIE_SCC_TO_COMP_C_0_DP")
	)
	(segment
		(start 164.916358 -25.716484)
		(end 165.068758 -25.868884)
		(width 0.14605)
		(layer "B.Cu")
		(net "PCIE_SCC_TO_COMP_C_0_DP")
	)
	(segment
		(start 167.957246 -30.242256)
		(end 167.952166 -30.247082)
		(width 0.09525)
		(layer "B.Cu")
		(net "PCIE_SCC_TO_COMP_C_0_DP")
	)
	(segment
		(start 165.068758 -22.325584)
		(end 165.068758 -22.763734)
		(width 0.14605)
		(layer "B.Cu")
		(net "PCIE_SCC_TO_COMP_C_0_DP")
	)
	(segment
		(start 168.01465 -30.184852)
		(end 167.957246 -30.242256)
		(width 0.09525)
		(layer "B.Cu")
		(net "PCIE_SCC_TO_COMP_C_0_DP")
	)
	(segment
		(start 168.275 -29.7688)
		(end 168.01465 -30.02915)
		(width 0.09525)
		(layer "B.Cu")
		(net "PCIE_SCC_TO_COMP_C_0_DP")
	)
	(segment
		(start 167.684196 -28.74772)
		(end 167.774112 -28.74772)
		(width 0.09525)
		(layer "B.Cu")
		(net "PCIE_SCC_TO_COMP_C_0_DP")
	)
	(segment
		(start 167.774112 -28.74772)
		(end 167.931084 -28.9052)
		(width 0.09525)
		(layer "B.Cu")
		(net "PCIE_SCC_TO_COMP_C_0_DP")
	)
	(segment
		(start 164.916358 -24.535384)
		(end 165.068758 -24.687784)
		(width 0.14605)
		(layer "B.Cu")
		(net "PCIE_SCC_TO_COMP_C_0_DP")
	)
	(segment
		(start 166.728648 -27.792426)
		(end 166.728648 -28.007818)
		(width 0.14605)
		(layer "B.Cu")
		(net "PCIE_SCC_TO_COMP_C_0_DP")
	)
	(segment
		(start 166.203376 -27.482546)
		(end 166.418768 -27.482546)
		(width 0.14605)
		(layer "B.Cu")
		(net "PCIE_SCC_TO_COMP_C_0_DP")
	)
	(segment
		(start 165.068758 -21.582634)
		(end 164.916358 -21.735034)
		(width 0.14605)
		(layer "B.Cu")
		(net "PCIE_SCC_TO_COMP_C_0_DP")
	)
	(segment
		(start 166.728648 -28.007818)
		(end 167.038528 -28.317698)
		(width 0.14605)
		(layer "B.Cu")
		(net "PCIE_SCC_TO_COMP_C_0_DP")
	)
	(segment
		(start 168.275 -29.249116)
		(end 168.275 -29.7688)
		(width 0.09525)
		(layer "B.Cu")
		(net "PCIE_SCC_TO_COMP_C_0_DP")
	)
	(segment
		(start 164.916358 -21.735034)
		(end 164.916358 -22.173184)
		(width 0.14605)
		(layer "B.Cu")
		(net "PCIE_SCC_TO_COMP_C_0_DP")
	)
	(segment
		(start 167.931084 -28.9052)
		(end 168.275 -29.249116)
		(width 0.09525)
		(layer "B.Cu")
		(net "PCIE_SCC_TO_COMP_C_0_DP")
	)
	(segment
		(start 166.418768 -27.482546)
		(end 166.728648 -27.792426)
		(width 0.14605)
		(layer "B.Cu")
		(net "PCIE_SCC_TO_COMP_C_0_DP")
	)
	(segment
		(start 168.199816 -31.599632)
		(end 167.80002 -31.199836)
		(width 0.14605)
		(layer "F.Cu")
		(net "PCIE_SCC_TO_COMP_C_0_DN")
	)
	(segment
		(start 168.199816 -31.599886)
		(end 168.199816 -31.599632)
		(width 0.14605)
		(layer "F.Cu")
		(net "PCIE_SCC_TO_COMP_C_0_DN")
	)
	(via
		(at 167.80002 -31.199836)
		(size 0.4572)
		(drill 0.2032)
		(layers "F.Cu" "B.Cu")
		(net "PCIE_SCC_TO_COMP_C_0_DN")
	)
	(segment
		(start 165.379908 -21.217128)
		(end 165.558978 -21.038058)
		(width 0.14605)
		(layer "B.Cu")
		(net "PCIE_SCC_TO_COMP_C_0_DN")
	)
	(segment
		(start 168.199562 -30.234128)
		(end 168.199816 -30.233874)
		(width 0.09525)
		(layer "B.Cu")
		(net "PCIE_SCC_TO_COMP_C_0_DN")
	)
	(segment
		(start 167.88765 -28.511246)
		(end 165.379908 -26.003504)
		(width 0.14605)
		(layer "B.Cu")
		(net "PCIE_SCC_TO_COMP_C_0_DN")
	)
	(segment
		(start 168.199816 -30.233874)
		(end 168.1988 -30.232858)
		(width 0.09525)
		(layer "B.Cu")
		(net "PCIE_SCC_TO_COMP_C_0_DN")
	)
	(segment
		(start 168.20007 -30.54858)
		(end 168.199816 -30.418278)
		(width 0.09525)
		(layer "B.Cu")
		(net "PCIE_SCC_TO_COMP_C_0_DN")
	)
	(segment
		(start 167.80002 -31.199836)
		(end 168.20007 -30.54858)
		(width 0.09525)
		(layer "B.Cu")
		(net "PCIE_SCC_TO_COMP_C_0_DN")
	)
	(segment
		(start 168.45915 -29.845254)
		(end 168.45915 -29.172662)
		(width 0.09525)
		(layer "B.Cu")
		(net "PCIE_SCC_TO_COMP_C_0_DN")
	)
	(segment
		(start 168.45915 -29.172662)
		(end 168.06164 -28.774898)
		(width 0.09525)
		(layer "B.Cu")
		(net "PCIE_SCC_TO_COMP_C_0_DN")
	)
	(segment
		(start 167.90416 -28.61691)
		(end 167.904414 -28.52801)
		(width 0.09525)
		(layer "B.Cu")
		(net "PCIE_SCC_TO_COMP_C_0_DN")
	)
	(segment
		(start 168.06164 -28.774898)
		(end 167.90416 -28.61691)
		(width 0.09525)
		(layer "B.Cu")
		(net "PCIE_SCC_TO_COMP_C_0_DN")
	)
	(segment
		(start 168.199816 -30.234382)
		(end 168.199562 -30.234128)
		(width 0.09525)
		(layer "B.Cu")
		(net "PCIE_SCC_TO_COMP_C_0_DN")
	)
	(segment
		(start 167.904414 -28.52801)
		(end 167.88765 -28.511246)
		(width 0.09525)
		(layer "B.Cu")
		(net "PCIE_SCC_TO_COMP_C_0_DN")
	)
	(segment
		(start 165.379908 -26.003504)
		(end 165.379908 -21.217128)
		(width 0.14605)
		(layer "B.Cu")
		(net "PCIE_SCC_TO_COMP_C_0_DN")
	)
	(segment
		(start 168.1988 -30.232858)
		(end 168.1988 -30.105604)
		(width 0.09525)
		(layer "B.Cu")
		(net "PCIE_SCC_TO_COMP_C_0_DN")
	)
	(segment
		(start 168.199816 -30.418278)
		(end 168.199816 -30.234382)
		(width 0.09525)
		(layer "B.Cu")
		(net "PCIE_SCC_TO_COMP_C_0_DN")
	)
	(segment
		(start 165.558978 -21.038058)
		(end 165.558978 -20.862544)
		(width 0.14605)
		(layer "B.Cu")
		(net "PCIE_SCC_TO_COMP_C_0_DN")
	)
	(segment
		(start 168.1988 -30.105604)
		(end 168.45915 -29.845254)
		(width 0.09525)
		(layer "B.Cu")
		(net "PCIE_SCC_TO_COMP_C_0_DN")
	)
	(segment
		(start 191.544194 -10.92581)
		(end 191.544194 -13.822426)
		(width 0.14605)
		(layer "B.Cu")
		(net "PCIE_SCC_TO_COMP_7_DP")
	)
	(segment
		(start 191.544194 -13.822426)
		(end 191.373506 -14.62532)
		(width 0.14605)
		(layer "B.Cu")
		(net "PCIE_SCC_TO_COMP_7_DP")
	)
	(segment
		(start 181.801262 -21.40712)
		(end 181.669182 -21.27504)
		(width 0.14605)
		(layer "B.Cu")
		(net "PCIE_SCC_TO_COMP_7_DP")
	)
	(segment
		(start 189.568836 -17.403064)
		(end 184.131458 -21.07057)
		(width 0.14605)
		(layer "B.Cu")
		(net "PCIE_SCC_TO_COMP_7_DP")
	)
	(segment
		(start 192.599818 -9.800082)
		(end 192.599818 -10.168382)
		(width 0.14605)
		(layer "B.Cu")
		(net "PCIE_SCC_TO_COMP_7_DP")
	)
	(segment
		(start 181.669182 -21.27504)
		(end 181.54904 -21.27504)
		(width 0.14605)
		(layer "B.Cu")
		(net "PCIE_SCC_TO_COMP_7_DP")
	)
	(segment
		(start 191.373506 -14.62532)
		(end 189.568836 -17.403064)
		(width 0.14605)
		(layer "B.Cu")
		(net "PCIE_SCC_TO_COMP_7_DP")
	)
	(segment
		(start 182.402734 -21.40712)
		(end 181.801262 -21.40712)
		(width 0.14605)
		(layer "B.Cu")
		(net "PCIE_SCC_TO_COMP_7_DP")
	)
	(segment
		(start 184.131458 -21.07057)
		(end 182.402734 -21.40712)
		(width 0.14605)
		(layer "B.Cu")
		(net "PCIE_SCC_TO_COMP_7_DP")
	)
	(segment
		(start 192.423796 -10.344404)
		(end 192.1256 -10.344404)
		(width 0.14605)
		(layer "B.Cu")
		(net "PCIE_SCC_TO_COMP_7_DP")
	)
	(arc
		(start 192.1256 -10.344404)
		(mid 191.714484 -10.514694)
		(end 191.544194 -10.92581)
		(width 0.14605)
		(layer "B.Cu")
		(net "PCIE_SCC_TO_COMP_7_DP")
	)
	(arc
		(start 192.599818 -10.168382)
		(mid 192.548262 -10.292848)
		(end 192.423796 -10.344404)
		(width 0.14605)
		(layer "B.Cu")
		(net "PCIE_SCC_TO_COMP_7_DP")
	)
	(segment
		(start 184.253124 -21.36394)
		(end 182.43296 -21.71827)
		(width 0.14605)
		(layer "B.Cu")
		(net "PCIE_SCC_TO_COMP_7_DN")
	)
	(segment
		(start 181.838346 -21.71827)
		(end 181.714648 -21.841968)
		(width 0.14605)
		(layer "B.Cu")
		(net "PCIE_SCC_TO_COMP_7_DN")
	)
	(segment
		(start 181.714648 -21.841968)
		(end 181.548786 -21.841968)
		(width 0.14605)
		(layer "B.Cu")
		(net "PCIE_SCC_TO_COMP_7_DN")
	)
	(segment
		(start 191.855344 -10.92581)
		(end 191.855344 -13.855192)
		(width 0.14605)
		(layer "B.Cu")
		(net "PCIE_SCC_TO_COMP_7_DN")
	)
	(segment
		(start 192.599818 -11.20013)
		(end 192.599818 -10.83183)
		(width 0.14605)
		(layer "B.Cu")
		(net "PCIE_SCC_TO_COMP_7_DN")
	)
	(segment
		(start 191.855344 -13.855192)
		(end 191.66586 -14.746478)
		(width 0.14605)
		(layer "B.Cu")
		(net "PCIE_SCC_TO_COMP_7_DN")
	)
	(segment
		(start 192.423542 -10.655554)
		(end 192.1256 -10.655554)
		(width 0.14605)
		(layer "B.Cu")
		(net "PCIE_SCC_TO_COMP_7_DN")
	)
	(segment
		(start 189.795404 -17.625822)
		(end 184.253124 -21.36394)
		(width 0.14605)
		(layer "B.Cu")
		(net "PCIE_SCC_TO_COMP_7_DN")
	)
	(segment
		(start 191.66586 -14.746478)
		(end 189.795404 -17.625822)
		(width 0.14605)
		(layer "B.Cu")
		(net "PCIE_SCC_TO_COMP_7_DN")
	)
	(segment
		(start 182.43296 -21.71827)
		(end 181.838346 -21.71827)
		(width 0.14605)
		(layer "B.Cu")
		(net "PCIE_SCC_TO_COMP_7_DN")
	)
	(arc
		(start 192.1256 -10.655554)
		(mid 191.9345 -10.73471)
		(end 191.855344 -10.92581)
		(width 0.14605)
		(layer "B.Cu")
		(net "PCIE_SCC_TO_COMP_7_DN")
	)
	(arc
		(start 192.599818 -10.83183)
		(mid 192.548188 -10.707184)
		(end 192.423542 -10.655554)
		(width 0.14605)
		(layer "B.Cu")
		(net "PCIE_SCC_TO_COMP_7_DN")
	)
	(segment
		(start 186.600846 -17.826482)
		(end 184.479692 -19.203924)
		(width 0.14605)
		(layer "B.Cu")
		(net "PCIE_SCC_TO_COMP_6_DP")
	)
	(segment
		(start 180.950616 -20.02536)
		(end 178.90744 -20.693126)
		(width 0.14605)
		(layer "B.Cu")
		(net "PCIE_SCC_TO_COMP_6_DP")
	)
	(segment
		(start 189.712092 -13.916914)
		(end 187.591446 -17.183354)
		(width 0.14605)
		(layer "B.Cu")
		(net "PCIE_SCC_TO_COMP_6_DP")
	)
	(segment
		(start 183.200294 -19.520154)
		(end 181.921404 -19.836384)
		(width 0.14605)
		(layer "B.Cu")
		(net "PCIE_SCC_TO_COMP_6_DP")
	)
	(segment
		(start 178.812698 -20.693126)
		(end 178.699414 -20.579842)
		(width 0.14605)
		(layer "B.Cu")
		(net "PCIE_SCC_TO_COMP_6_DP")
	)
	(segment
		(start 189.74435 -13.765022)
		(end 189.712092 -13.916914)
		(width 0.14605)
		(layer "B.Cu")
		(net "PCIE_SCC_TO_COMP_6_DP")
	)
	(segment
		(start 186.645804 -17.615662)
		(end 186.600846 -17.826482)
		(width 0.14605)
		(layer "B.Cu")
		(net "PCIE_SCC_TO_COMP_6_DP")
	)
	(segment
		(start 190.623952 -11.5443)
		(end 190.325756 -11.5443)
		(width 0.14605)
		(layer "B.Cu")
		(net "PCIE_SCC_TO_COMP_6_DP")
	)
	(segment
		(start 190.799974 -10.999978)
		(end 190.799974 -11.368278)
		(width 0.14605)
		(layer "B.Cu")
		(net "PCIE_SCC_TO_COMP_6_DP")
	)
	(segment
		(start 189.74435 -12.125706)
		(end 189.74435 -13.765022)
		(width 0.14605)
		(layer "B.Cu")
		(net "PCIE_SCC_TO_COMP_6_DP")
	)
	(segment
		(start 178.90744 -20.693126)
		(end 178.812698 -20.693126)
		(width 0.14605)
		(layer "B.Cu")
		(net "PCIE_SCC_TO_COMP_6_DP")
	)
	(segment
		(start 181.921404 -19.836384)
		(end 180.950616 -20.02536)
		(width 0.14605)
		(layer "B.Cu")
		(net "PCIE_SCC_TO_COMP_6_DP")
	)
	(segment
		(start 187.223908 -17.42186)
		(end 187.013088 -17.377156)
		(width 0.14605)
		(layer "B.Cu")
		(net "PCIE_SCC_TO_COMP_6_DP")
	)
	(segment
		(start 187.591446 -17.183354)
		(end 187.223908 -17.42186)
		(width 0.14605)
		(layer "B.Cu")
		(net "PCIE_SCC_TO_COMP_6_DP")
	)
	(segment
		(start 187.013088 -17.377156)
		(end 186.645804 -17.615662)
		(width 0.14605)
		(layer "B.Cu")
		(net "PCIE_SCC_TO_COMP_6_DP")
	)
	(segment
		(start 184.479692 -19.203924)
		(end 183.200294 -19.520154)
		(width 0.14605)
		(layer "B.Cu")
		(net "PCIE_SCC_TO_COMP_6_DP")
	)
	(arc
		(start 190.325756 -11.5443)
		(mid 189.91464 -11.71459)
		(end 189.74435 -12.125706)
		(width 0.14605)
		(layer "B.Cu")
		(net "PCIE_SCC_TO_COMP_6_DP")
	)
	(arc
		(start 190.799974 -11.368278)
		(mid 190.748418 -11.492744)
		(end 190.623952 -11.5443)
		(width 0.14605)
		(layer "B.Cu")
		(net "PCIE_SCC_TO_COMP_6_DP")
	)
	(segment
		(start 190.623698 -11.85545)
		(end 190.325756 -11.85545)
		(width 0.14605)
		(layer "B.Cu")
		(net "PCIE_SCC_TO_COMP_6_DN")
	)
	(segment
		(start 190.0555 -13.797788)
		(end 190.004446 -14.038072)
		(width 0.14605)
		(layer "B.Cu")
		(net "PCIE_SCC_TO_COMP_6_DN")
	)
	(segment
		(start 187.81649 -17.408398)
		(end 184.605168 -19.493484)
		(width 0.14605)
		(layer "B.Cu")
		(net "PCIE_SCC_TO_COMP_6_DN")
	)
	(segment
		(start 181.029102 -20.327112)
		(end 179.009548 -20.987512)
		(width 0.14605)
		(layer "B.Cu")
		(net "PCIE_SCC_TO_COMP_6_DN")
	)
	(segment
		(start 179.009548 -20.987512)
		(end 178.84648 -21.15058)
		(width 0.14605)
		(layer "B.Cu")
		(net "PCIE_SCC_TO_COMP_6_DN")
	)
	(segment
		(start 190.799974 -12.400026)
		(end 190.799974 -12.031726)
		(width 0.14605)
		(layer "B.Cu")
		(net "PCIE_SCC_TO_COMP_6_DN")
	)
	(segment
		(start 178.84648 -21.15058)
		(end 178.700176 -21.15058)
		(width 0.14605)
		(layer "B.Cu")
		(net "PCIE_SCC_TO_COMP_6_DN")
	)
	(segment
		(start 184.605168 -19.493484)
		(end 181.98846 -20.140422)
		(width 0.14605)
		(layer "B.Cu")
		(net "PCIE_SCC_TO_COMP_6_DN")
	)
	(segment
		(start 181.98846 -20.140422)
		(end 181.029102 -20.327112)
		(width 0.14605)
		(layer "B.Cu")
		(net "PCIE_SCC_TO_COMP_6_DN")
	)
	(segment
		(start 190.0555 -12.125706)
		(end 190.0555 -13.797788)
		(width 0.14605)
		(layer "B.Cu")
		(net "PCIE_SCC_TO_COMP_6_DN")
	)
	(segment
		(start 190.004446 -14.038072)
		(end 187.81649 -17.408398)
		(width 0.14605)
		(layer "B.Cu")
		(net "PCIE_SCC_TO_COMP_6_DN")
	)
	(arc
		(start 190.325756 -11.85545)
		(mid 190.134656 -11.934606)
		(end 190.0555 -12.125706)
		(width 0.14605)
		(layer "B.Cu")
		(net "PCIE_SCC_TO_COMP_6_DN")
	)
	(arc
		(start 190.799974 -12.031726)
		(mid 190.748344 -11.90708)
		(end 190.623698 -11.85545)
		(width 0.14605)
		(layer "B.Cu")
		(net "PCIE_SCC_TO_COMP_6_DN")
	)
	(segment
		(start 186.218068 -16.281654)
		(end 182.992014 -18.3769)
		(width 0.14605)
		(layer "B.Cu")
		(net "PCIE_SCC_TO_COMP_5_DP")
	)
	(segment
		(start 175.158654 -20.260564)
		(end 175.158654 -20.560284)
		(width 0.14605)
		(layer "B.Cu")
		(net "PCIE_SCC_TO_COMP_5_DP")
	)
	(segment
		(start 187.944252 -13.170408)
		(end 187.80125 -13.843508)
		(width 0.14605)
		(layer "B.Cu")
		(net "PCIE_SCC_TO_COMP_5_DP")
	)
	(segment
		(start 187.80125 -13.843508)
		(end 186.218068 -16.281654)
		(width 0.14605)
		(layer "B.Cu")
		(net "PCIE_SCC_TO_COMP_5_DP")
	)
	(segment
		(start 182.992014 -18.3769)
		(end 181.1401 -18.770346)
		(width 0.14605)
		(layer "B.Cu")
		(net "PCIE_SCC_TO_COMP_5_DP")
	)
	(segment
		(start 181.1401 -18.770346)
		(end 179.287678 -19.164046)
		(width 0.14605)
		(layer "B.Cu")
		(net "PCIE_SCC_TO_COMP_5_DP")
	)
	(segment
		(start 188.823854 -10.344404)
		(end 188.525658 -10.344404)
		(width 0.14605)
		(layer "B.Cu")
		(net "PCIE_SCC_TO_COMP_5_DP")
	)
	(segment
		(start 179.287678 -19.164046)
		(end 175.436784 -19.982434)
		(width 0.14605)
		(layer "B.Cu")
		(net "PCIE_SCC_TO_COMP_5_DP")
	)
	(segment
		(start 175.158654 -20.560284)
		(end 175.043846 -20.675092)
		(width 0.14605)
		(layer "B.Cu")
		(net "PCIE_SCC_TO_COMP_5_DP")
	)
	(segment
		(start 188.999876 -9.800082)
		(end 188.999876 -10.168382)
		(width 0.14605)
		(layer "B.Cu")
		(net "PCIE_SCC_TO_COMP_5_DP")
	)
	(segment
		(start 187.944252 -10.92581)
		(end 187.944252 -13.170408)
		(width 0.14605)
		(layer "B.Cu")
		(net "PCIE_SCC_TO_COMP_5_DP")
	)
	(segment
		(start 175.436784 -19.982434)
		(end 175.158654 -20.260564)
		(width 0.14605)
		(layer "B.Cu")
		(net "PCIE_SCC_TO_COMP_5_DP")
	)
	(arc
		(start 188.525658 -10.344404)
		(mid 188.114542 -10.514694)
		(end 187.944252 -10.92581)
		(width 0.14605)
		(layer "B.Cu")
		(net "PCIE_SCC_TO_COMP_5_DP")
	)
	(arc
		(start 188.999876 -10.168382)
		(mid 188.94832 -10.292848)
		(end 188.823854 -10.344404)
		(width 0.14605)
		(layer "B.Cu")
		(net "PCIE_SCC_TO_COMP_5_DP")
	)
	(segment
		(start 175.469804 -20.389596)
		(end 175.469804 -20.534122)
		(width 0.14605)
		(layer "B.Cu")
		(net "PCIE_SCC_TO_COMP_5_DN")
	)
	(segment
		(start 186.443112 -16.506698)
		(end 186.078368 -16.74368)
		(width 0.14605)
		(layer "B.Cu")
		(net "PCIE_SCC_TO_COMP_5_DN")
	)
	(segment
		(start 188.8236 -10.655554)
		(end 188.525658 -10.655554)
		(width 0.14605)
		(layer "B.Cu")
		(net "PCIE_SCC_TO_COMP_5_DN")
	)
	(segment
		(start 188.255402 -13.203174)
		(end 188.093858 -13.964666)
		(width 0.14605)
		(layer "B.Cu")
		(net "PCIE_SCC_TO_COMP_5_DN")
	)
	(segment
		(start 184.675526 -17.836642)
		(end 184.464706 -17.791684)
		(width 0.14605)
		(layer "B.Cu")
		(net "PCIE_SCC_TO_COMP_5_DN")
	)
	(segment
		(start 175.469804 -20.534122)
		(end 175.611028 -20.675346)
		(width 0.14605)
		(layer "B.Cu")
		(net "PCIE_SCC_TO_COMP_5_DN")
	)
	(segment
		(start 175.591724 -20.267676)
		(end 175.469804 -20.389596)
		(width 0.14605)
		(layer "B.Cu")
		(net "PCIE_SCC_TO_COMP_5_DN")
	)
	(segment
		(start 186.078368 -16.74368)
		(end 186.03341 -16.9545)
		(width 0.14605)
		(layer "B.Cu")
		(net "PCIE_SCC_TO_COMP_5_DN")
	)
	(segment
		(start 184.464706 -17.791684)
		(end 183.113172 -18.669254)
		(width 0.14605)
		(layer "B.Cu")
		(net "PCIE_SCC_TO_COMP_5_DN")
	)
	(segment
		(start 179.352448 -19.468592)
		(end 175.591724 -20.267676)
		(width 0.14605)
		(layer "B.Cu")
		(net "PCIE_SCC_TO_COMP_5_DN")
	)
	(segment
		(start 188.255402 -10.92581)
		(end 188.255402 -13.203174)
		(width 0.14605)
		(layer "B.Cu")
		(net "PCIE_SCC_TO_COMP_5_DN")
	)
	(segment
		(start 185.666126 -17.19326)
		(end 185.455306 -17.148302)
		(width 0.14605)
		(layer "B.Cu")
		(net "PCIE_SCC_TO_COMP_5_DN")
	)
	(segment
		(start 188.999876 -11.20013)
		(end 188.999876 -10.83183)
		(width 0.14605)
		(layer "B.Cu")
		(net "PCIE_SCC_TO_COMP_5_DN")
	)
	(segment
		(start 183.113172 -18.669254)
		(end 179.352448 -19.468592)
		(width 0.14605)
		(layer "B.Cu")
		(net "PCIE_SCC_TO_COMP_5_DN")
	)
	(segment
		(start 185.455306 -17.148302)
		(end 185.087768 -17.387062)
		(width 0.14605)
		(layer "B.Cu")
		(net "PCIE_SCC_TO_COMP_5_DN")
	)
	(segment
		(start 187.131198 -15.726918)
		(end 186.892438 -16.094456)
		(width 0.14605)
		(layer "B.Cu")
		(net "PCIE_SCC_TO_COMP_5_DN")
	)
	(segment
		(start 185.04281 -17.597882)
		(end 184.675526 -17.836642)
		(width 0.14605)
		(layer "B.Cu")
		(net "PCIE_SCC_TO_COMP_5_DN")
	)
	(segment
		(start 188.093858 -13.964666)
		(end 187.086494 -15.516098)
		(width 0.14605)
		(layer "B.Cu")
		(net "PCIE_SCC_TO_COMP_5_DN")
	)
	(segment
		(start 186.892438 -16.094456)
		(end 186.681618 -16.13916)
		(width 0.14605)
		(layer "B.Cu")
		(net "PCIE_SCC_TO_COMP_5_DN")
	)
	(segment
		(start 185.087768 -17.387062)
		(end 185.04281 -17.597882)
		(width 0.14605)
		(layer "B.Cu")
		(net "PCIE_SCC_TO_COMP_5_DN")
	)
	(segment
		(start 187.086494 -15.516098)
		(end 187.131198 -15.726918)
		(width 0.14605)
		(layer "B.Cu")
		(net "PCIE_SCC_TO_COMP_5_DN")
	)
	(segment
		(start 186.681618 -16.13916)
		(end 186.443112 -16.506698)
		(width 0.14605)
		(layer "B.Cu")
		(net "PCIE_SCC_TO_COMP_5_DN")
	)
	(segment
		(start 186.03341 -16.9545)
		(end 185.666126 -17.19326)
		(width 0.14605)
		(layer "B.Cu")
		(net "PCIE_SCC_TO_COMP_5_DN")
	)
	(arc
		(start 188.525658 -10.655554)
		(mid 188.334558 -10.73471)
		(end 188.255402 -10.92581)
		(width 0.14605)
		(layer "B.Cu")
		(net "PCIE_SCC_TO_COMP_5_DN")
	)
	(arc
		(start 188.999876 -10.83183)
		(mid 188.948246 -10.707184)
		(end 188.8236 -10.655554)
		(width 0.14605)
		(layer "B.Cu")
		(net "PCIE_SCC_TO_COMP_5_DN")
	)
	(segment
		(start 181.5846 -17.453356)
		(end 181.487826 -17.516094)
		(width 0.14605)
		(layer "B.Cu")
		(net "PCIE_SCC_TO_COMP_4_DP")
	)
	(segment
		(start 185.315098 -15.030958)
		(end 181.5846 -17.453356)
		(width 0.14605)
		(layer "B.Cu")
		(net "PCIE_SCC_TO_COMP_4_DP")
	)
	(segment
		(start 173.17085 -20.481798)
		(end 173.045882 -20.606766)
		(width 0.14605)
		(layer "B.Cu")
		(net "PCIE_SCC_TO_COMP_4_DP")
	)
	(segment
		(start 173.17085 -19.871182)
		(end 173.17085 -20.481798)
		(width 0.14605)
		(layer "B.Cu")
		(net "PCIE_SCC_TO_COMP_4_DP")
	)
	(segment
		(start 173.659292 -19.180048)
		(end 173.17085 -19.871182)
		(width 0.14605)
		(layer "B.Cu")
		(net "PCIE_SCC_TO_COMP_4_DP")
	)
	(segment
		(start 187.199778 -10.999978)
		(end 187.199778 -11.368278)
		(width 0.14605)
		(layer "B.Cu")
		(net "PCIE_SCC_TO_COMP_4_DP")
	)
	(segment
		(start 186.144154 -13.755116)
		(end 185.315098 -15.030958)
		(width 0.14605)
		(layer "B.Cu")
		(net "PCIE_SCC_TO_COMP_4_DP")
	)
	(segment
		(start 187.023756 -11.5443)
		(end 186.72556 -11.5443)
		(width 0.14605)
		(layer "B.Cu")
		(net "PCIE_SCC_TO_COMP_4_DP")
	)
	(segment
		(start 186.144154 -12.125706)
		(end 186.144154 -13.755116)
		(width 0.14605)
		(layer "B.Cu")
		(net "PCIE_SCC_TO_COMP_4_DP")
	)
	(segment
		(start 181.487826 -17.516094)
		(end 173.659292 -19.180048)
		(width 0.14605)
		(layer "B.Cu")
		(net "PCIE_SCC_TO_COMP_4_DP")
	)
	(arc
		(start 187.199778 -11.368278)
		(mid 187.148222 -11.492744)
		(end 187.023756 -11.5443)
		(width 0.14605)
		(layer "B.Cu")
		(net "PCIE_SCC_TO_COMP_4_DP")
	)
	(arc
		(start 186.72556 -11.5443)
		(mid 186.314444 -11.71459)
		(end 186.144154 -12.125706)
		(width 0.14605)
		(layer "B.Cu")
		(net "PCIE_SCC_TO_COMP_4_DP")
	)
	(segment
		(start 182.187342 -17.6149)
		(end 181.976522 -17.570196)
		(width 0.14605)
		(layer "B.Cu")
		(net "PCIE_SCC_TO_COMP_4_DN")
	)
	(segment
		(start 182.554626 -17.376394)
		(end 182.187342 -17.6149)
		(width 0.14605)
		(layer "B.Cu")
		(net "PCIE_SCC_TO_COMP_4_DN")
	)
	(segment
		(start 183.957722 -16.283686)
		(end 183.590184 -16.522192)
		(width 0.14605)
		(layer "B.Cu")
		(net "PCIE_SCC_TO_COMP_4_DN")
	)
	(segment
		(start 187.199778 -12.400026)
		(end 187.199778 -12.031726)
		(width 0.14605)
		(layer "B.Cu")
		(net "PCIE_SCC_TO_COMP_4_DN")
	)
	(segment
		(start 173.482 -20.464018)
		(end 173.625002 -20.60702)
		(width 0.14605)
		(layer "B.Cu")
		(net "PCIE_SCC_TO_COMP_4_DN")
	)
	(segment
		(start 183.177942 -16.971772)
		(end 182.967122 -16.927068)
		(width 0.14605)
		(layer "B.Cu")
		(net "PCIE_SCC_TO_COMP_4_DN")
	)
	(segment
		(start 173.482 -19.970242)
		(end 173.482 -20.464018)
		(width 0.14605)
		(layer "B.Cu")
		(net "PCIE_SCC_TO_COMP_4_DN")
	)
	(segment
		(start 183.545226 -16.733012)
		(end 183.177942 -16.971772)
		(width 0.14605)
		(layer "B.Cu")
		(net "PCIE_SCC_TO_COMP_4_DN")
	)
	(segment
		(start 182.599584 -17.165574)
		(end 182.554626 -17.376394)
		(width 0.14605)
		(layer "B.Cu")
		(net "PCIE_SCC_TO_COMP_4_DN")
	)
	(segment
		(start 182.967122 -16.927068)
		(end 182.599584 -17.165574)
		(width 0.14605)
		(layer "B.Cu")
		(net "PCIE_SCC_TO_COMP_4_DN")
	)
	(segment
		(start 187.023502 -11.85545)
		(end 186.72556 -11.85545)
		(width 0.14605)
		(layer "B.Cu")
		(net "PCIE_SCC_TO_COMP_4_DN")
	)
	(segment
		(start 181.976522 -17.570196)
		(end 181.608984 -17.808702)
		(width 0.14605)
		(layer "B.Cu")
		(net "PCIE_SCC_TO_COMP_4_DN")
	)
	(segment
		(start 173.843188 -19.459194)
		(end 173.482 -19.970242)
		(width 0.14605)
		(layer "B.Cu")
		(net "PCIE_SCC_TO_COMP_4_DN")
	)
	(segment
		(start 184.535826 -16.089884)
		(end 184.168542 -16.32839)
		(width 0.14605)
		(layer "B.Cu")
		(net "PCIE_SCC_TO_COMP_4_DN")
	)
	(segment
		(start 185.540142 -15.256002)
		(end 184.580784 -15.879064)
		(width 0.14605)
		(layer "B.Cu")
		(net "PCIE_SCC_TO_COMP_4_DN")
	)
	(segment
		(start 184.580784 -15.879064)
		(end 184.535826 -16.089884)
		(width 0.14605)
		(layer "B.Cu")
		(net "PCIE_SCC_TO_COMP_4_DN")
	)
	(segment
		(start 183.590184 -16.522192)
		(end 183.545226 -16.733012)
		(width 0.14605)
		(layer "B.Cu")
		(net "PCIE_SCC_TO_COMP_4_DN")
	)
	(segment
		(start 184.168542 -16.32839)
		(end 183.957722 -16.283686)
		(width 0.14605)
		(layer "B.Cu")
		(net "PCIE_SCC_TO_COMP_4_DN")
	)
	(segment
		(start 186.455304 -13.847572)
		(end 185.540142 -15.256002)
		(width 0.14605)
		(layer "B.Cu")
		(net "PCIE_SCC_TO_COMP_4_DN")
	)
	(segment
		(start 181.608984 -17.808702)
		(end 173.843188 -19.459194)
		(width 0.14605)
		(layer "B.Cu")
		(net "PCIE_SCC_TO_COMP_4_DN")
	)
	(segment
		(start 186.455304 -12.125706)
		(end 186.455304 -13.847572)
		(width 0.14605)
		(layer "B.Cu")
		(net "PCIE_SCC_TO_COMP_4_DN")
	)
	(arc
		(start 187.199778 -12.031726)
		(mid 187.148148 -11.90708)
		(end 187.023502 -11.85545)
		(width 0.14605)
		(layer "B.Cu")
		(net "PCIE_SCC_TO_COMP_4_DN")
	)
	(arc
		(start 186.72556 -11.85545)
		(mid 186.53446 -11.934606)
		(end 186.455304 -12.125706)
		(width 0.14605)
		(layer "B.Cu")
		(net "PCIE_SCC_TO_COMP_4_DN")
	)
	(segment
		(start 185.399934 -9.800082)
		(end 185.399934 -10.168382)
		(width 0.14605)
		(layer "B.Cu")
		(net "PCIE_SCC_TO_COMP_3_DP")
	)
	(segment
		(start 171.534582 -19.214084)
		(end 171.080938 -20.182078)
		(width 0.14605)
		(layer "B.Cu")
		(net "PCIE_SCC_TO_COMP_3_DP")
	)
	(segment
		(start 185.223912 -10.344404)
		(end 184.925716 -10.344404)
		(width 0.14605)
		(layer "B.Cu")
		(net "PCIE_SCC_TO_COMP_3_DP")
	)
	(segment
		(start 184.23001 -13.894562)
		(end 183.88711 -14.403832)
		(width 0.14605)
		(layer "B.Cu")
		(net "PCIE_SCC_TO_COMP_3_DP")
	)
	(segment
		(start 183.88711 -14.403832)
		(end 181.17058 -16.236188)
		(width 0.14605)
		(layer "B.Cu")
		(net "PCIE_SCC_TO_COMP_3_DP")
	)
	(segment
		(start 184.34431 -13.309854)
		(end 184.23001 -13.894562)
		(width 0.14605)
		(layer "B.Cu")
		(net "PCIE_SCC_TO_COMP_3_DP")
	)
	(segment
		(start 171.080938 -20.182078)
		(end 171.080938 -20.449286)
		(width 0.14605)
		(layer "B.Cu")
		(net "PCIE_SCC_TO_COMP_3_DP")
	)
	(segment
		(start 181.17058 -16.236188)
		(end 173.83633 -17.662144)
		(width 0.14605)
		(layer "B.Cu")
		(net "PCIE_SCC_TO_COMP_3_DP")
	)
	(segment
		(start 173.83633 -17.662144)
		(end 171.534582 -19.214084)
		(width 0.14605)
		(layer "B.Cu")
		(net "PCIE_SCC_TO_COMP_3_DP")
	)
	(segment
		(start 184.34431 -10.92581)
		(end 184.34431 -13.309854)
		(width 0.14605)
		(layer "B.Cu")
		(net "PCIE_SCC_TO_COMP_3_DP")
	)
	(segment
		(start 171.080938 -20.449286)
		(end 170.923204 -20.60702)
		(width 0.14605)
		(layer "B.Cu")
		(net "PCIE_SCC_TO_COMP_3_DP")
	)
	(arc
		(start 185.399934 -10.168382)
		(mid 185.348378 -10.292848)
		(end 185.223912 -10.344404)
		(width 0.14605)
		(layer "B.Cu")
		(net "PCIE_SCC_TO_COMP_3_DP")
	)
	(arc
		(start 184.925716 -10.344404)
		(mid 184.5146 -10.514694)
		(end 184.34431 -10.92581)
		(width 0.14605)
		(layer "B.Cu")
		(net "PCIE_SCC_TO_COMP_3_DP")
	)
	(segment
		(start 184.523634 -14.016228)
		(end 184.111392 -14.62786)
		(width 0.14605)
		(layer "B.Cu")
		(net "PCIE_SCC_TO_COMP_3_DN")
	)
	(segment
		(start 171.779946 -19.424142)
		(end 171.392088 -20.25142)
		(width 0.14605)
		(layer "B.Cu")
		(net "PCIE_SCC_TO_COMP_3_DN")
	)
	(segment
		(start 177.315622 -17.458182)
		(end 176.8856 -17.541748)
		(width 0.14605)
		(layer "B.Cu")
		(net "PCIE_SCC_TO_COMP_3_DN")
	)
	(segment
		(start 174.388018 -17.872202)
		(end 173.957996 -17.955514)
		(width 0.14605)
		(layer "B.Cu")
		(net "PCIE_SCC_TO_COMP_3_DN")
	)
	(segment
		(start 185.399934 -11.20013)
		(end 185.399934 -10.83183)
		(width 0.14605)
		(layer "B.Cu")
		(net "PCIE_SCC_TO_COMP_3_DN")
	)
	(segment
		(start 185.223658 -10.655554)
		(end 184.925716 -10.655554)
		(width 0.14605)
		(layer "B.Cu")
		(net "PCIE_SCC_TO_COMP_3_DN")
	)
	(segment
		(start 177.866294 -17.196054)
		(end 177.436272 -17.27962)
		(width 0.14605)
		(layer "B.Cu")
		(net "PCIE_SCC_TO_COMP_3_DN")
	)
	(segment
		(start 174.996856 -17.909032)
		(end 174.566834 -17.992598)
		(width 0.14605)
		(layer "B.Cu")
		(net "PCIE_SCC_TO_COMP_3_DN")
	)
	(segment
		(start 184.111392 -14.62786)
		(end 181.292246 -16.529812)
		(width 0.14605)
		(layer "B.Cu")
		(net "PCIE_SCC_TO_COMP_3_DN")
	)
	(segment
		(start 176.276762 -17.504918)
		(end 176.156366 -17.683734)
		(width 0.14605)
		(layer "B.Cu")
		(net "PCIE_SCC_TO_COMP_3_DN")
	)
	(segment
		(start 173.957996 -17.955514)
		(end 171.779946 -19.424142)
		(width 0.14605)
		(layer "B.Cu")
		(net "PCIE_SCC_TO_COMP_3_DN")
	)
	(segment
		(start 184.65546 -13.34008)
		(end 184.523634 -14.016228)
		(width 0.14605)
		(layer "B.Cu")
		(net "PCIE_SCC_TO_COMP_3_DN")
	)
	(segment
		(start 176.706784 -17.421352)
		(end 176.276762 -17.504918)
		(width 0.14605)
		(layer "B.Cu")
		(net "PCIE_SCC_TO_COMP_3_DN")
	)
	(segment
		(start 171.392088 -20.466304)
		(end 171.532804 -20.60702)
		(width 0.14605)
		(layer "B.Cu")
		(net "PCIE_SCC_TO_COMP_3_DN")
	)
	(segment
		(start 184.65546 -10.92581)
		(end 184.65546 -13.34008)
		(width 0.14605)
		(layer "B.Cu")
		(net "PCIE_SCC_TO_COMP_3_DN")
	)
	(segment
		(start 175.547528 -17.64665)
		(end 175.117506 -17.73047)
		(width 0.14605)
		(layer "B.Cu")
		(net "PCIE_SCC_TO_COMP_3_DN")
	)
	(segment
		(start 178.595528 -17.054068)
		(end 178.475132 -17.232884)
		(width 0.14605)
		(layer "B.Cu")
		(net "PCIE_SCC_TO_COMP_3_DN")
	)
	(segment
		(start 176.8856 -17.541748)
		(end 176.706784 -17.421352)
		(width 0.14605)
		(layer "B.Cu")
		(net "PCIE_SCC_TO_COMP_3_DN")
	)
	(segment
		(start 178.475132 -17.232884)
		(end 178.044856 -17.31645)
		(width 0.14605)
		(layer "B.Cu")
		(net "PCIE_SCC_TO_COMP_3_DN")
	)
	(segment
		(start 174.566834 -17.992598)
		(end 174.388018 -17.872202)
		(width 0.14605)
		(layer "B.Cu")
		(net "PCIE_SCC_TO_COMP_3_DN")
	)
	(segment
		(start 175.72609 -17.7673)
		(end 175.547528 -17.64665)
		(width 0.14605)
		(layer "B.Cu")
		(net "PCIE_SCC_TO_COMP_3_DN")
	)
	(segment
		(start 178.044856 -17.31645)
		(end 177.866294 -17.196054)
		(width 0.14605)
		(layer "B.Cu")
		(net "PCIE_SCC_TO_COMP_3_DN")
	)
	(segment
		(start 175.117506 -17.73047)
		(end 174.996856 -17.909032)
		(width 0.14605)
		(layer "B.Cu")
		(net "PCIE_SCC_TO_COMP_3_DN")
	)
	(segment
		(start 176.156366 -17.683734)
		(end 175.72609 -17.7673)
		(width 0.14605)
		(layer "B.Cu")
		(net "PCIE_SCC_TO_COMP_3_DN")
	)
	(segment
		(start 171.392088 -20.25142)
		(end 171.392088 -20.466304)
		(width 0.14605)
		(layer "B.Cu")
		(net "PCIE_SCC_TO_COMP_3_DN")
	)
	(segment
		(start 181.292246 -16.529812)
		(end 178.595528 -17.054068)
		(width 0.14605)
		(layer "B.Cu")
		(net "PCIE_SCC_TO_COMP_3_DN")
	)
	(segment
		(start 177.436272 -17.27962)
		(end 177.315622 -17.458182)
		(width 0.14605)
		(layer "B.Cu")
		(net "PCIE_SCC_TO_COMP_3_DN")
	)
	(arc
		(start 184.925716 -10.655554)
		(mid 184.734616 -10.73471)
		(end 184.65546 -10.92581)
		(width 0.14605)
		(layer "B.Cu")
		(net "PCIE_SCC_TO_COMP_3_DN")
	)
	(arc
		(start 185.399934 -10.83183)
		(mid 185.348304 -10.707184)
		(end 185.223658 -10.655554)
		(width 0.14605)
		(layer "B.Cu")
		(net "PCIE_SCC_TO_COMP_3_DN")
	)
	(segment
		(start 182.544212 -12.666726)
		(end 182.544466 -12.66698)
		(width 0.14605)
		(layer "B.Cu")
		(net "PCIE_SCC_TO_COMP_2_DP")
	)
	(segment
		(start 182.544466 -12.66698)
		(end 182.386478 -13.410438)
		(width 0.14605)
		(layer "B.Cu")
		(net "PCIE_SCC_TO_COMP_2_DP")
	)
	(segment
		(start 169.122852 -20.586954)
		(end 168.98239 -20.727416)
		(width 0.14605)
		(layer "B.Cu")
		(net "PCIE_SCC_TO_COMP_2_DP")
	)
	(segment
		(start 181.666896 -14.51864)
		(end 180.66512 -15.169134)
		(width 0.14605)
		(layer "B.Cu")
		(net "PCIE_SCC_TO_COMP_2_DP")
	)
	(segment
		(start 182.386478 -13.410438)
		(end 181.666896 -14.51864)
		(width 0.14605)
		(layer "B.Cu")
		(net "PCIE_SCC_TO_COMP_2_DP")
	)
	(segment
		(start 180.66512 -15.169134)
		(end 179.254404 -15.443454)
		(width 0.14605)
		(layer "B.Cu")
		(net "PCIE_SCC_TO_COMP_2_DP")
	)
	(segment
		(start 179.254404 -15.443454)
		(end 178.414426 -15.280386)
		(width 0.14605)
		(layer "B.Cu")
		(net "PCIE_SCC_TO_COMP_2_DP")
	)
	(segment
		(start 169.122852 -20.140168)
		(end 169.122852 -20.586954)
		(width 0.14605)
		(layer "B.Cu")
		(net "PCIE_SCC_TO_COMP_2_DP")
	)
	(segment
		(start 169.388028 -19.34337)
		(end 169.122852 -20.140168)
		(width 0.14605)
		(layer "B.Cu")
		(net "PCIE_SCC_TO_COMP_2_DP")
	)
	(segment
		(start 178.414426 -15.280386)
		(end 173.348396 -16.265144)
		(width 0.14605)
		(layer "B.Cu")
		(net "PCIE_SCC_TO_COMP_2_DP")
	)
	(segment
		(start 169.502582 -18.9992)
		(end 169.388028 -19.34337)
		(width 0.14605)
		(layer "B.Cu")
		(net "PCIE_SCC_TO_COMP_2_DP")
	)
	(segment
		(start 183.423814 -11.5443)
		(end 183.125618 -11.5443)
		(width 0.14605)
		(layer "B.Cu")
		(net "PCIE_SCC_TO_COMP_2_DP")
	)
	(segment
		(start 183.599836 -10.999978)
		(end 183.599836 -11.368278)
		(width 0.14605)
		(layer "B.Cu")
		(net "PCIE_SCC_TO_COMP_2_DP")
	)
	(segment
		(start 173.348396 -16.265144)
		(end 169.502582 -18.9992)
		(width 0.14605)
		(layer "B.Cu")
		(net "PCIE_SCC_TO_COMP_2_DP")
	)
	(segment
		(start 182.544466 -12.125452)
		(end 182.544466 -12.666726)
		(width 0.14605)
		(layer "B.Cu")
		(net "PCIE_SCC_TO_COMP_2_DP")
	)
	(segment
		(start 182.544466 -12.666726)
		(end 182.544212 -12.666726)
		(width 0.14605)
		(layer "B.Cu")
		(net "PCIE_SCC_TO_COMP_2_DP")
	)
	(arc
		(start 183.599836 -11.368278)
		(mid 183.54828 -11.492744)
		(end 183.423814 -11.5443)
		(width 0.14605)
		(layer "B.Cu")
		(net "PCIE_SCC_TO_COMP_2_DP")
	)
	(arc
		(start 183.125618 -11.5443)
		(mid 182.714681 -11.714515)
		(end 182.544466 -12.125452)
		(width 0.14605)
		(layer "B.Cu")
		(net "PCIE_SCC_TO_COMP_2_DP")
	)
	(segment
		(start 169.434002 -20.601178)
		(end 169.5577 -20.724876)
		(width 0.14605)
		(layer "B.Cu")
		(net "PCIE_SCC_TO_COMP_2_DN")
	)
	(segment
		(start 176.401476 -16.143986)
		(end 176.22266 -16.023336)
		(width 0.14605)
		(layer "B.Cu")
		(net "PCIE_SCC_TO_COMP_2_DN")
	)
	(segment
		(start 176.831498 -16.06042)
		(end 176.401476 -16.143986)
		(width 0.14605)
		(layer "B.Cu")
		(net "PCIE_SCC_TO_COMP_2_DN")
	)
	(segment
		(start 172.04817 -17.571466)
		(end 171.691046 -17.825212)
		(width 0.14605)
		(layer "B.Cu")
		(net "PCIE_SCC_TO_COMP_2_DN")
	)
	(segment
		(start 175.672242 -16.285718)
		(end 175.241966 -16.369284)
		(width 0.14605)
		(layer "B.Cu")
		(net "PCIE_SCC_TO_COMP_2_DN")
	)
	(segment
		(start 171.297854 -18.291556)
		(end 171.08551 -18.255742)
		(width 0.14605)
		(layer "B.Cu")
		(net "PCIE_SCC_TO_COMP_2_DN")
	)
	(segment
		(start 172.617638 -17.353534)
		(end 172.260514 -17.60728)
		(width 0.14605)
		(layer "B.Cu")
		(net "PCIE_SCC_TO_COMP_2_DN")
	)
	(segment
		(start 175.792638 -16.106902)
		(end 175.672242 -16.285718)
		(width 0.14605)
		(layer "B.Cu")
		(net "PCIE_SCC_TO_COMP_2_DN")
	)
	(segment
		(start 171.08551 -18.255742)
		(end 169.765726 -19.194018)
		(width 0.14605)
		(layer "B.Cu")
		(net "PCIE_SCC_TO_COMP_2_DN")
	)
	(segment
		(start 173.473872 -16.557752)
		(end 172.653452 -17.14119)
		(width 0.14605)
		(layer "B.Cu")
		(net "PCIE_SCC_TO_COMP_2_DN")
	)
	(segment
		(start 183.42356 -11.85545)
		(end 183.125618 -11.85545)
		(width 0.14605)
		(layer "B.Cu")
		(net "PCIE_SCC_TO_COMP_2_DN")
	)
	(segment
		(start 182.678832 -13.531596)
		(end 182.679086 -13.531596)
		(width 0.14605)
		(layer "B.Cu")
		(net "PCIE_SCC_TO_COMP_2_DN")
	)
	(segment
		(start 172.260514 -17.60728)
		(end 172.04817 -17.571466)
		(width 0.14605)
		(layer "B.Cu")
		(net "PCIE_SCC_TO_COMP_2_DN")
	)
	(segment
		(start 182.85587 -12.699746)
		(end 182.678832 -13.531596)
		(width 0.14605)
		(layer "B.Cu")
		(net "PCIE_SCC_TO_COMP_2_DN")
	)
	(segment
		(start 169.765726 -19.194018)
		(end 169.683684 -19.441414)
		(width 0.14605)
		(layer "B.Cu")
		(net "PCIE_SCC_TO_COMP_2_DN")
	)
	(segment
		(start 175.241966 -16.369284)
		(end 175.063404 -16.248888)
		(width 0.14605)
		(layer "B.Cu")
		(net "PCIE_SCC_TO_COMP_2_DN")
	)
	(segment
		(start 182.679086 -13.531596)
		(end 181.89194 -14.743684)
		(width 0.14605)
		(layer "B.Cu")
		(net "PCIE_SCC_TO_COMP_2_DN")
	)
	(segment
		(start 169.683684 -19.441414)
		(end 169.68343 -19.441668)
		(width 0.14605)
		(layer "B.Cu")
		(net "PCIE_SCC_TO_COMP_2_DN")
	)
	(segment
		(start 176.952148 -15.881604)
		(end 176.831498 -16.06042)
		(width 0.14605)
		(layer "B.Cu")
		(net "PCIE_SCC_TO_COMP_2_DN")
	)
	(segment
		(start 171.654978 -18.03781)
		(end 171.297854 -18.291556)
		(width 0.14605)
		(layer "B.Cu")
		(net "PCIE_SCC_TO_COMP_2_DN")
	)
	(segment
		(start 181.89194 -14.743684)
		(end 180.783992 -15.463266)
		(width 0.14605)
		(layer "B.Cu")
		(net "PCIE_SCC_TO_COMP_2_DN")
	)
	(segment
		(start 171.691046 -17.825212)
		(end 171.654978 -18.03781)
		(width 0.14605)
		(layer "B.Cu")
		(net "PCIE_SCC_TO_COMP_2_DN")
	)
	(segment
		(start 182.855616 -12.699746)
		(end 182.85587 -12.699746)
		(width 0.14605)
		(layer "B.Cu")
		(net "PCIE_SCC_TO_COMP_2_DN")
	)
	(segment
		(start 172.653452 -17.140936)
		(end 172.617638 -17.353534)
		(width 0.14605)
		(layer "B.Cu")
		(net "PCIE_SCC_TO_COMP_2_DN")
	)
	(segment
		(start 182.855616 -12.125452)
		(end 182.855616 -12.699746)
		(width 0.14605)
		(layer "B.Cu")
		(net "PCIE_SCC_TO_COMP_2_DN")
	)
	(segment
		(start 169.68343 -19.441668)
		(end 169.434002 -20.190714)
		(width 0.14605)
		(layer "B.Cu")
		(net "PCIE_SCC_TO_COMP_2_DN")
	)
	(segment
		(start 169.434002 -20.190714)
		(end 169.434002 -20.601178)
		(width 0.14605)
		(layer "B.Cu")
		(net "PCIE_SCC_TO_COMP_2_DN")
	)
	(segment
		(start 180.783992 -15.463266)
		(end 179.254404 -15.760446)
		(width 0.14605)
		(layer "B.Cu")
		(net "PCIE_SCC_TO_COMP_2_DN")
	)
	(segment
		(start 176.22266 -16.023336)
		(end 175.792638 -16.106902)
		(width 0.14605)
		(layer "B.Cu")
		(net "PCIE_SCC_TO_COMP_2_DN")
	)
	(segment
		(start 172.653452 -17.14119)
		(end 172.653452 -17.140936)
		(width 0.14605)
		(layer "B.Cu")
		(net "PCIE_SCC_TO_COMP_2_DN")
	)
	(segment
		(start 175.063404 -16.248888)
		(end 173.473872 -16.557752)
		(width 0.14605)
		(layer "B.Cu")
		(net "PCIE_SCC_TO_COMP_2_DN")
	)
	(segment
		(start 179.254404 -15.760446)
		(end 178.414426 -15.597378)
		(width 0.14605)
		(layer "B.Cu")
		(net "PCIE_SCC_TO_COMP_2_DN")
	)
	(segment
		(start 178.414426 -15.597378)
		(end 176.952148 -15.881604)
		(width 0.14605)
		(layer "B.Cu")
		(net "PCIE_SCC_TO_COMP_2_DN")
	)
	(segment
		(start 183.599836 -12.400026)
		(end 183.599836 -12.031726)
		(width 0.14605)
		(layer "B.Cu")
		(net "PCIE_SCC_TO_COMP_2_DN")
	)
	(arc
		(start 183.599836 -12.031726)
		(mid 183.548206 -11.90708)
		(end 183.42356 -11.85545)
		(width 0.14605)
		(layer "B.Cu")
		(net "PCIE_SCC_TO_COMP_2_DN")
	)
	(arc
		(start 183.125618 -11.85545)
		(mid 182.934698 -11.934532)
		(end 182.855616 -12.125452)
		(width 0.14605)
		(layer "B.Cu")
		(net "PCIE_SCC_TO_COMP_2_DN")
	)
	(segment
		(start 178.467258 -14.056868)
		(end 172.677074 -15.181072)
		(width 0.14605)
		(layer "B.Cu")
		(net "PCIE_SCC_TO_COMP_1_DP")
	)
	(segment
		(start 179.413662 -14.240256)
		(end 178.467258 -14.056868)
		(width 0.14605)
		(layer "B.Cu")
		(net "PCIE_SCC_TO_COMP_1_DP")
	)
	(segment
		(start 166.7637 -19.932396)
		(end 166.7637 -20.174204)
		(width 0.14605)
		(layer "B.Cu")
		(net "PCIE_SCC_TO_COMP_1_DP")
	)
	(segment
		(start 167.325294 -18.78965)
		(end 166.84879 -19.495262)
		(width 0.14605)
		(layer "B.Cu")
		(net "PCIE_SCC_TO_COMP_1_DP")
	)
	(segment
		(start 181.799992 -9.800082)
		(end 181.799992 -10.168382)
		(width 0.14605)
		(layer "B.Cu")
		(net "PCIE_SCC_TO_COMP_1_DP")
	)
	(segment
		(start 180.194712 -14.061186)
		(end 179.413662 -14.240256)
		(width 0.14605)
		(layer "B.Cu")
		(net "PCIE_SCC_TO_COMP_1_DP")
	)
	(segment
		(start 180.687218 -13.565124)
		(end 180.458364 -13.917676)
		(width 0.14605)
		(layer "B.Cu")
		(net "PCIE_SCC_TO_COMP_1_DP")
	)
	(segment
		(start 172.677074 -15.181072)
		(end 167.325294 -18.78965)
		(width 0.14605)
		(layer "B.Cu")
		(net "PCIE_SCC_TO_COMP_1_DP")
	)
	(segment
		(start 180.744368 -10.92581)
		(end 180.744368 -13.297916)
		(width 0.14605)
		(layer "B.Cu")
		(net "PCIE_SCC_TO_COMP_1_DP")
	)
	(segment
		(start 181.62397 -10.344404)
		(end 181.325774 -10.344404)
		(width 0.14605)
		(layer "B.Cu")
		(net "PCIE_SCC_TO_COMP_1_DP")
	)
	(segment
		(start 180.744368 -13.297916)
		(end 180.687218 -13.565124)
		(width 0.14605)
		(layer "B.Cu")
		(net "PCIE_SCC_TO_COMP_1_DP")
	)
	(segment
		(start 166.7637 -20.174204)
		(end 166.64432 -20.293584)
		(width 0.14605)
		(layer "B.Cu")
		(net "PCIE_SCC_TO_COMP_1_DP")
	)
	(segment
		(start 166.84879 -19.495262)
		(end 166.7637 -19.932396)
		(width 0.14605)
		(layer "B.Cu")
		(net "PCIE_SCC_TO_COMP_1_DP")
	)
	(segment
		(start 180.458364 -13.917676)
		(end 180.194712 -14.061186)
		(width 0.14605)
		(layer "B.Cu")
		(net "PCIE_SCC_TO_COMP_1_DP")
	)
	(arc
		(start 181.799992 -10.168382)
		(mid 181.748436 -10.292848)
		(end 181.62397 -10.344404)
		(width 0.14605)
		(layer "B.Cu")
		(net "PCIE_SCC_TO_COMP_1_DP")
	)
	(arc
		(start 181.325774 -10.344404)
		(mid 180.914658 -10.514694)
		(end 180.744368 -10.92581)
		(width 0.14605)
		(layer "B.Cu")
		(net "PCIE_SCC_TO_COMP_1_DP")
	)
	(segment
		(start 180.67655 -14.153388)
		(end 180.305964 -14.355064)
		(width 0.14605)
		(layer "B.Cu")
		(net "PCIE_SCC_TO_COMP_1_DN")
	)
	(segment
		(start 168.588182 -18.49755)
		(end 168.224708 -18.742406)
		(width 0.14605)
		(layer "B.Cu")
		(net "PCIE_SCC_TO_COMP_1_DN")
	)
	(segment
		(start 168.013126 -18.701258)
		(end 167.548814 -19.014694)
		(width 0.14605)
		(layer "B.Cu")
		(net "PCIE_SCC_TO_COMP_1_DN")
	)
	(segment
		(start 168.224708 -18.742406)
		(end 168.013126 -18.701258)
		(width 0.14605)
		(layer "B.Cu")
		(net "PCIE_SCC_TO_COMP_1_DN")
	)
	(segment
		(start 178.467258 -14.37386)
		(end 172.79874 -15.474696)
		(width 0.14605)
		(layer "B.Cu")
		(net "PCIE_SCC_TO_COMP_1_DN")
	)
	(segment
		(start 167.07485 -19.962622)
		(end 167.07485 -20.089114)
		(width 0.14605)
		(layer "B.Cu")
		(net "PCIE_SCC_TO_COMP_1_DN")
	)
	(segment
		(start 170.546776 -17.177004)
		(end 170.183556 -17.42186)
		(width 0.14605)
		(layer "B.Cu")
		(net "PCIE_SCC_TO_COMP_1_DN")
	)
	(segment
		(start 168.99255 -18.040858)
		(end 168.62933 -18.285968)
		(width 0.14605)
		(layer "B.Cu")
		(net "PCIE_SCC_TO_COMP_1_DN")
	)
	(segment
		(start 180.979572 -13.686282)
		(end 180.67655 -14.153388)
		(width 0.14605)
		(layer "B.Cu")
		(net "PCIE_SCC_TO_COMP_1_DN")
	)
	(segment
		(start 169.567352 -17.83715)
		(end 169.204132 -18.08226)
		(width 0.14605)
		(layer "B.Cu")
		(net "PCIE_SCC_TO_COMP_1_DN")
	)
	(segment
		(start 170.183556 -17.42186)
		(end 169.971974 -17.380712)
		(width 0.14605)
		(layer "B.Cu")
		(net "PCIE_SCC_TO_COMP_1_DN")
	)
	(segment
		(start 167.07485 -20.089114)
		(end 167.27932 -20.293584)
		(width 0.14605)
		(layer "B.Cu")
		(net "PCIE_SCC_TO_COMP_1_DN")
	)
	(segment
		(start 167.14216 -19.616928)
		(end 167.07485 -19.962622)
		(width 0.14605)
		(layer "B.Cu")
		(net "PCIE_SCC_TO_COMP_1_DN")
	)
	(segment
		(start 181.055518 -13.330936)
		(end 180.979572 -13.686282)
		(width 0.14605)
		(layer "B.Cu")
		(net "PCIE_SCC_TO_COMP_1_DN")
	)
	(segment
		(start 181.055518 -10.92581)
		(end 181.055518 -13.330936)
		(width 0.14605)
		(layer "B.Cu")
		(net "PCIE_SCC_TO_COMP_1_DN")
	)
	(segment
		(start 172.79874 -15.474696)
		(end 170.587924 -16.965422)
		(width 0.14605)
		(layer "B.Cu")
		(net "PCIE_SCC_TO_COMP_1_DN")
	)
	(segment
		(start 168.62933 -18.285968)
		(end 168.588182 -18.49755)
		(width 0.14605)
		(layer "B.Cu")
		(net "PCIE_SCC_TO_COMP_1_DN")
	)
	(segment
		(start 169.204132 -18.08226)
		(end 168.99255 -18.040858)
		(width 0.14605)
		(layer "B.Cu")
		(net "PCIE_SCC_TO_COMP_1_DN")
	)
	(segment
		(start 169.6085 -17.625568)
		(end 169.567352 -17.83715)
		(width 0.14605)
		(layer "B.Cu")
		(net "PCIE_SCC_TO_COMP_1_DN")
	)
	(segment
		(start 167.548814 -19.014694)
		(end 167.14216 -19.616928)
		(width 0.14605)
		(layer "B.Cu")
		(net "PCIE_SCC_TO_COMP_1_DN")
	)
	(segment
		(start 169.971974 -17.380712)
		(end 169.6085 -17.625568)
		(width 0.14605)
		(layer "B.Cu")
		(net "PCIE_SCC_TO_COMP_1_DN")
	)
	(segment
		(start 179.418996 -14.558264)
		(end 178.467258 -14.37386)
		(width 0.14605)
		(layer "B.Cu")
		(net "PCIE_SCC_TO_COMP_1_DN")
	)
	(segment
		(start 170.587924 -16.965422)
		(end 170.546776 -17.177004)
		(width 0.14605)
		(layer "B.Cu")
		(net "PCIE_SCC_TO_COMP_1_DN")
	)
	(segment
		(start 181.799992 -11.20013)
		(end 181.799992 -10.83183)
		(width 0.14605)
		(layer "B.Cu")
		(net "PCIE_SCC_TO_COMP_1_DN")
	)
	(segment
		(start 180.305964 -14.355064)
		(end 179.418996 -14.558264)
		(width 0.14605)
		(layer "B.Cu")
		(net "PCIE_SCC_TO_COMP_1_DN")
	)
	(segment
		(start 181.623716 -10.655554)
		(end 181.325774 -10.655554)
		(width 0.14605)
		(layer "B.Cu")
		(net "PCIE_SCC_TO_COMP_1_DN")
	)
	(arc
		(start 181.799992 -10.83183)
		(mid 181.748362 -10.707184)
		(end 181.623716 -10.655554)
		(width 0.14605)
		(layer "B.Cu")
		(net "PCIE_SCC_TO_COMP_1_DN")
	)
	(arc
		(start 181.325774 -10.655554)
		(mid 181.134674 -10.73471)
		(end 181.055518 -10.92581)
		(width 0.14605)
		(layer "B.Cu")
		(net "PCIE_SCC_TO_COMP_1_DN")
	)
	(segment
		(start 165.071552 -19.668744)
		(end 165.071552 -20.023328)
		(width 0.14605)
		(layer "B.Cu")
		(net "PCIE_SCC_TO_COMP_0_DP")
	)
	(segment
		(start 179.999894 -10.999978)
		(end 179.999894 -11.368278)
		(width 0.14605)
		(layer "B.Cu")
		(net "PCIE_SCC_TO_COMP_0_DP")
	)
	(segment
		(start 165.126162 -19.413474)
		(end 165.071552 -19.668744)
		(width 0.14605)
		(layer "B.Cu")
		(net "PCIE_SCC_TO_COMP_0_DP")
	)
	(segment
		(start 169.601388 -15.655798)
		(end 169.601642 -15.655798)
		(width 0.14605)
		(layer "B.Cu")
		(net "PCIE_SCC_TO_COMP_0_DP")
	)
	(segment
		(start 165.071552 -20.023328)
		(end 164.923978 -20.170902)
		(width 0.14605)
		(layer "B.Cu")
		(net "PCIE_SCC_TO_COMP_0_DP")
	)
	(segment
		(start 178.869594 -11.5443)
		(end 174.412148 -12.410694)
		(width 0.14605)
		(layer "B.Cu")
		(net "PCIE_SCC_TO_COMP_0_DP")
	)
	(segment
		(start 165.979348 -18.099786)
		(end 165.126162 -19.413474)
		(width 0.14605)
		(layer "B.Cu")
		(net "PCIE_SCC_TO_COMP_0_DP")
	)
	(segment
		(start 179.823872 -11.5443)
		(end 178.869594 -11.5443)
		(width 0.14605)
		(layer "B.Cu")
		(net "PCIE_SCC_TO_COMP_0_DP")
	)
	(segment
		(start 169.601642 -15.655798)
		(end 165.98011 -18.09877)
		(width 0.14605)
		(layer "B.Cu")
		(net "PCIE_SCC_TO_COMP_0_DP")
	)
	(segment
		(start 174.412148 -12.410694)
		(end 171.38015 -14.456156)
		(width 0.14605)
		(layer "B.Cu")
		(net "PCIE_SCC_TO_COMP_0_DP")
	)
	(segment
		(start 171.38015 -14.456156)
		(end 171.379896 -14.456156)
		(width 0.14605)
		(layer "B.Cu")
		(net "PCIE_SCC_TO_COMP_0_DP")
	)
	(segment
		(start 171.379896 -14.456156)
		(end 169.601388 -15.655798)
		(width 0.14605)
		(layer "B.Cu")
		(net "PCIE_SCC_TO_COMP_0_DP")
	)
	(segment
		(start 164.923978 -20.170902)
		(end 164.923978 -20.303744)
		(width 0.14605)
		(layer "B.Cu")
		(net "PCIE_SCC_TO_COMP_0_DP")
	)
	(segment
		(start 165.98011 -18.09877)
		(end 165.979348 -18.099786)
		(width 0.14605)
		(layer "B.Cu")
		(net "PCIE_SCC_TO_COMP_0_DP")
	)
	(arc
		(start 179.999894 -11.368278)
		(mid 179.948338 -11.492744)
		(end 179.823872 -11.5443)
		(width 0.14605)
		(layer "B.Cu")
		(net "PCIE_SCC_TO_COMP_0_DP")
	)
	(segment
		(start 167.725598 -17.296892)
		(end 167.68445 -17.508474)
		(width 0.14605)
		(layer "B.Cu")
		(net "PCIE_SCC_TO_COMP_0_DN")
	)
	(segment
		(start 170.663108 -15.315438)
		(end 170.62196 -15.52702)
		(width 0.14605)
		(layer "B.Cu")
		(net "PCIE_SCC_TO_COMP_0_DN")
	)
	(segment
		(start 166.205916 -18.32229)
		(end 165.418516 -19.534886)
		(width 0.14605)
		(layer "B.Cu")
		(net "PCIE_SCC_TO_COMP_0_DN")
	)
	(segment
		(start 174.533814 -12.704318)
		(end 170.663108 -15.315438)
		(width 0.14605)
		(layer "B.Cu")
		(net "PCIE_SCC_TO_COMP_0_DN")
	)
	(segment
		(start 169.27957 -16.43253)
		(end 169.067988 -16.391382)
		(width 0.14605)
		(layer "B.Cu")
		(net "PCIE_SCC_TO_COMP_0_DN")
	)
	(segment
		(start 168.704768 -16.636492)
		(end 168.66362 -16.84782)
		(width 0.14605)
		(layer "B.Cu")
		(net "PCIE_SCC_TO_COMP_0_DN")
	)
	(segment
		(start 170.047158 -15.730982)
		(end 169.683938 -15.975838)
		(width 0.14605)
		(layer "B.Cu")
		(net "PCIE_SCC_TO_COMP_0_DN")
	)
	(segment
		(start 168.088818 -17.051782)
		(end 167.725598 -17.296892)
		(width 0.14605)
		(layer "B.Cu")
		(net "PCIE_SCC_TO_COMP_0_DN")
	)
	(segment
		(start 170.62196 -15.52702)
		(end 170.25874 -15.771876)
		(width 0.14605)
		(layer "B.Cu")
		(net "PCIE_SCC_TO_COMP_0_DN")
	)
	(segment
		(start 167.68445 -17.508474)
		(end 167.32123 -17.75333)
		(width 0.14605)
		(layer "B.Cu")
		(net "PCIE_SCC_TO_COMP_0_DN")
	)
	(segment
		(start 165.558978 -20.175728)
		(end 165.558978 -20.303744)
		(width 0.14605)
		(layer "B.Cu")
		(net "PCIE_SCC_TO_COMP_0_DN")
	)
	(segment
		(start 167.32123 -17.75333)
		(end 167.109648 -17.712436)
		(width 0.14605)
		(layer "B.Cu")
		(net "PCIE_SCC_TO_COMP_0_DN")
	)
	(segment
		(start 165.382702 -19.701764)
		(end 165.382702 -19.999452)
		(width 0.14605)
		(layer "B.Cu")
		(net "PCIE_SCC_TO_COMP_0_DN")
	)
	(segment
		(start 179.999894 -12.400026)
		(end 179.999894 -12.031726)
		(width 0.14605)
		(layer "B.Cu")
		(net "PCIE_SCC_TO_COMP_0_DN")
	)
	(segment
		(start 178.899566 -11.85545)
		(end 174.533814 -12.704318)
		(width 0.14605)
		(layer "B.Cu")
		(net "PCIE_SCC_TO_COMP_0_DN")
	)
	(segment
		(start 168.66362 -16.84782)
		(end 168.3004 -17.09293)
		(width 0.14605)
		(layer "B.Cu")
		(net "PCIE_SCC_TO_COMP_0_DN")
	)
	(segment
		(start 170.25874 -15.771876)
		(end 170.047158 -15.730982)
		(width 0.14605)
		(layer "B.Cu")
		(net "PCIE_SCC_TO_COMP_0_DN")
	)
	(segment
		(start 169.64279 -16.18742)
		(end 169.27957 -16.43253)
		(width 0.14605)
		(layer "B.Cu")
		(net "PCIE_SCC_TO_COMP_0_DN")
	)
	(segment
		(start 179.823618 -11.85545)
		(end 178.899566 -11.85545)
		(width 0.14605)
		(layer "B.Cu")
		(net "PCIE_SCC_TO_COMP_0_DN")
	)
	(segment
		(start 165.418516 -19.534886)
		(end 165.382702 -19.701764)
		(width 0.14605)
		(layer "B.Cu")
		(net "PCIE_SCC_TO_COMP_0_DN")
	)
	(segment
		(start 165.382702 -19.999452)
		(end 165.558978 -20.175728)
		(width 0.14605)
		(layer "B.Cu")
		(net "PCIE_SCC_TO_COMP_0_DN")
	)
	(segment
		(start 167.109648 -17.712436)
		(end 166.433246 -18.168874)
		(width 0.14605)
		(layer "B.Cu")
		(net "PCIE_SCC_TO_COMP_0_DN")
	)
	(segment
		(start 168.3004 -17.09293)
		(end 168.088818 -17.051782)
		(width 0.14605)
		(layer "B.Cu")
		(net "PCIE_SCC_TO_COMP_0_DN")
	)
	(segment
		(start 169.683938 -15.975838)
		(end 169.64279 -16.18742)
		(width 0.14605)
		(layer "B.Cu")
		(net "PCIE_SCC_TO_COMP_0_DN")
	)
	(segment
		(start 166.433246 -18.168874)
		(end 166.205916 -18.32229)
		(width 0.14605)
		(layer "B.Cu")
		(net "PCIE_SCC_TO_COMP_0_DN")
	)
	(segment
		(start 169.067988 -16.391382)
		(end 168.704768 -16.636492)
		(width 0.14605)
		(layer "B.Cu")
		(net "PCIE_SCC_TO_COMP_0_DN")
	)
	(arc
		(start 179.999894 -12.031726)
		(mid 179.948264 -11.90708)
		(end 179.823618 -11.85545)
		(width 0.14605)
		(layer "B.Cu")
		(net "PCIE_SCC_TO_COMP_0_DN")
	)
	(segment
		(start 179.82438 -23.885398)
		(end 180.14696 -23.885398)
		(width 0.14605)
		(layer "F.Cu")
		(net "PCIE_COMP_TO_SCC_7_DP")
	)
	(segment
		(start 176.1998 -28.399994)
		(end 176.241202 -28.358592)
		(width 0.14605)
		(layer "F.Cu")
		(net "PCIE_COMP_TO_SCC_7_DP")
	)
	(segment
		(start 178.146202 -25.849834)
		(end 178.792124 -25.849834)
		(width 0.14605)
		(layer "F.Cu")
		(net "PCIE_COMP_TO_SCC_7_DP")
	)
	(segment
		(start 176.241202 -28.358592)
		(end 176.241202 -27.754834)
		(width 0.14605)
		(layer "F.Cu")
		(net "PCIE_COMP_TO_SCC_7_DP")
	)
	(segment
		(start 179.31638 -25.325578)
		(end 179.31638 -24.393398)
		(width 0.14605)
		(layer "F.Cu")
		(net "PCIE_COMP_TO_SCC_7_DP")
	)
	(segment
		(start 178.792124 -25.849834)
		(end 179.31638 -25.325578)
		(width 0.14605)
		(layer "F.Cu")
		(net "PCIE_COMP_TO_SCC_7_DP")
	)
	(segment
		(start 176.241202 -27.754834)
		(end 178.146202 -25.849834)
		(width 0.14605)
		(layer "F.Cu")
		(net "PCIE_COMP_TO_SCC_7_DP")
	)
	(arc
		(start 179.31638 -24.393398)
		(mid 179.46517 -24.034188)
		(end 179.82438 -23.885398)
		(width 0.14605)
		(layer "F.Cu")
		(net "PCIE_COMP_TO_SCC_7_DP")
	)
	(arc
		(start 180.14696 -23.885398)
		(mid 180.351351 -23.800737)
		(end 180.436012 -23.596346)
		(width 0.14605)
		(layer "F.Cu")
		(net "PCIE_COMP_TO_SCC_7_DP")
	)
	(segment
		(start 192.433194 -3.135122)
		(end 192.149222 -3.135122)
		(width 0.1397)
		(layer "In5.Cu")
		(net "PCIE_COMP_TO_SCC_7_DP")
	)
	(segment
		(start 186.063636 -18.79219)
		(end 186.029092 -19.04111)
		(width 0.1397)
		(layer "In5.Cu")
		(net "PCIE_COMP_TO_SCC_7_DP")
	)
	(segment
		(start 187.599066 -17.854168)
		(end 187.350146 -17.819624)
		(width 0.1397)
		(layer "In5.Cu")
		(net "PCIE_COMP_TO_SCC_7_DP")
	)
	(segment
		(start 191.534796 -13.063728)
		(end 191.47536 -13.343382)
		(width 0.1397)
		(layer "In5.Cu")
		(net "PCIE_COMP_TO_SCC_7_DP")
	)
	(segment
		(start 185.076846 -19.7612)
		(end 183.049672 -21.293836)
		(width 0.1397)
		(layer "In5.Cu")
		(net "PCIE_COMP_TO_SCC_7_DP")
	)
	(segment
		(start 185.694828 -19.29384)
		(end 185.445654 -19.259296)
		(width 0.1397)
		(layer "In5.Cu")
		(net "PCIE_COMP_TO_SCC_7_DP")
	)
	(segment
		(start 187.350146 -17.819624)
		(end 187.015882 -18.072354)
		(width 0.1397)
		(layer "In5.Cu")
		(net "PCIE_COMP_TO_SCC_7_DP")
	)
	(segment
		(start 192.599818 -2.600198)
		(end 192.599818 -2.968498)
		(width 0.1397)
		(layer "In5.Cu")
		(net "PCIE_COMP_TO_SCC_7_DP")
	)
	(segment
		(start 186.981338 -18.321274)
		(end 186.647074 -18.574004)
		(width 0.1397)
		(layer "In5.Cu")
		(net "PCIE_COMP_TO_SCC_7_DP")
	)
	(segment
		(start 186.029092 -19.04111)
		(end 185.694828 -19.29384)
		(width 0.1397)
		(layer "In5.Cu")
		(net "PCIE_COMP_TO_SCC_7_DP")
	)
	(segment
		(start 190.696342 -14.730222)
		(end 190.557658 -14.94409)
		(width 0.1397)
		(layer "In5.Cu")
		(net "PCIE_COMP_TO_SCC_7_DP")
	)
	(segment
		(start 189.983364 -15.829026)
		(end 189.698884 -16.266668)
		(width 0.1397)
		(layer "In5.Cu")
		(net "PCIE_COMP_TO_SCC_7_DP")
	)
	(segment
		(start 189.698884 -16.266668)
		(end 187.599066 -17.854168)
		(width 0.1397)
		(layer "In5.Cu")
		(net "PCIE_COMP_TO_SCC_7_DP")
	)
	(segment
		(start 190.557658 -14.94409)
		(end 190.267336 -15.39113)
		(width 0.1397)
		(layer "In5.Cu")
		(net "PCIE_COMP_TO_SCC_7_DP")
	)
	(segment
		(start 185.445654 -19.259296)
		(end 185.11139 -19.512026)
		(width 0.1397)
		(layer "In5.Cu")
		(net "PCIE_COMP_TO_SCC_7_DP")
	)
	(segment
		(start 181.678072 -23.4061)
		(end 181.498748 -23.585424)
		(width 0.1397)
		(layer "In5.Cu")
		(net "PCIE_COMP_TO_SCC_7_DP")
	)
	(segment
		(start 181.009036 -23.875746)
		(end 180.715412 -23.875746)
		(width 0.1397)
		(layer "In5.Cu")
		(net "PCIE_COMP_TO_SCC_7_DP")
	)
	(segment
		(start 190.267336 -15.39113)
		(end 189.983364 -15.829026)
		(width 0.1397)
		(layer "In5.Cu")
		(net "PCIE_COMP_TO_SCC_7_DP")
	)
	(segment
		(start 186.3979 -18.53946)
		(end 186.063636 -18.79219)
		(width 0.1397)
		(layer "In5.Cu")
		(net "PCIE_COMP_TO_SCC_7_DP")
	)
	(segment
		(start 190.986918 -14.282928)
		(end 190.696342 -14.730222)
		(width 0.1397)
		(layer "In5.Cu")
		(net "PCIE_COMP_TO_SCC_7_DP")
	)
	(segment
		(start 185.11139 -19.512026)
		(end 185.076846 -19.7612)
		(width 0.1397)
		(layer "In5.Cu")
		(net "PCIE_COMP_TO_SCC_7_DP")
	)
	(segment
		(start 191.416178 -13.622274)
		(end 190.986918 -14.282928)
		(width 0.1397)
		(layer "In5.Cu")
		(net "PCIE_COMP_TO_SCC_7_DP")
	)
	(segment
		(start 191.47536 -13.343382)
		(end 191.416178 -13.622274)
		(width 0.1397)
		(layer "In5.Cu")
		(net "PCIE_COMP_TO_SCC_7_DP")
	)
	(segment
		(start 186.647074 -18.574004)
		(end 186.3979 -18.53946)
		(width 0.1397)
		(layer "In5.Cu")
		(net "PCIE_COMP_TO_SCC_7_DP")
	)
	(segment
		(start 183.049672 -21.293836)
		(end 181.678072 -23.4061)
		(width 0.1397)
		(layer "In5.Cu")
		(net "PCIE_COMP_TO_SCC_7_DP")
	)
	(segment
		(start 187.015882 -18.072354)
		(end 186.981338 -18.321274)
		(width 0.1397)
		(layer "In5.Cu")
		(net "PCIE_COMP_TO_SCC_7_DP")
	)
	(segment
		(start 181.498748 -23.585424)
		(end 181.349142 -23.734522)
		(width 0.1397)
		(layer "In5.Cu")
		(net "PCIE_COMP_TO_SCC_7_DP")
	)
	(segment
		(start 191.534796 -3.749548)
		(end 191.534796 -13.063728)
		(width 0.1397)
		(layer "In5.Cu")
		(net "PCIE_COMP_TO_SCC_7_DP")
	)
	(arc
		(start 192.149222 -3.135122)
		(mid 191.714757 -3.315083)
		(end 191.534796 -3.749548)
		(width 0.1397)
		(layer "In5.Cu")
		(net "PCIE_COMP_TO_SCC_7_DP")
	)
	(arc
		(start 181.349142 -23.734522)
		(mid 181.193144 -23.838976)
		(end 181.009036 -23.875746)
		(width 0.1397)
		(layer "In5.Cu")
		(net "PCIE_COMP_TO_SCC_7_DP")
	)
	(arc
		(start 180.715412 -23.875746)
		(mid 180.517846 -23.793912)
		(end 180.436012 -23.596346)
		(width 0.1397)
		(layer "In5.Cu")
		(net "PCIE_COMP_TO_SCC_7_DP")
	)
	(arc
		(start 192.599818 -2.968498)
		(mid 192.551015 -3.086319)
		(end 192.433194 -3.135122)
		(width 0.1397)
		(layer "In5.Cu")
		(net "PCIE_COMP_TO_SCC_7_DP")
	)
	(segment
		(start 176.552352 -27.883866)
		(end 178.275234 -26.160984)
		(width 0.14605)
		(layer "F.Cu")
		(net "PCIE_COMP_TO_SCC_7_DN")
	)
	(segment
		(start 178.921156 -26.160984)
		(end 179.62753 -25.45461)
		(width 0.14605)
		(layer "F.Cu")
		(net "PCIE_COMP_TO_SCC_7_DN")
	)
	(segment
		(start 176.552352 -28.847288)
		(end 176.552352 -27.883866)
		(width 0.14605)
		(layer "F.Cu")
		(net "PCIE_COMP_TO_SCC_7_DN")
	)
	(segment
		(start 178.275234 -26.160984)
		(end 178.921156 -26.160984)
		(width 0.14605)
		(layer "F.Cu")
		(net "PCIE_COMP_TO_SCC_7_DN")
	)
	(segment
		(start 179.82438 -24.196548)
		(end 180.147214 -24.196548)
		(width 0.14605)
		(layer "F.Cu")
		(net "PCIE_COMP_TO_SCC_7_DN")
	)
	(segment
		(start 176.1998 -29.19984)
		(end 176.552352 -28.847288)
		(width 0.14605)
		(layer "F.Cu")
		(net "PCIE_COMP_TO_SCC_7_DN")
	)
	(segment
		(start 179.62753 -25.45461)
		(end 179.62753 -24.393398)
		(width 0.14605)
		(layer "F.Cu")
		(net "PCIE_COMP_TO_SCC_7_DN")
	)
	(arc
		(start 179.62753 -24.393398)
		(mid 179.685186 -24.254204)
		(end 179.82438 -24.196548)
		(width 0.14605)
		(layer "F.Cu")
		(net "PCIE_COMP_TO_SCC_7_DN")
	)
	(arc
		(start 180.147214 -24.196548)
		(mid 180.351425 -24.281135)
		(end 180.436012 -24.485346)
		(width 0.14605)
		(layer "F.Cu")
		(net "PCIE_COMP_TO_SCC_7_DN")
	)
	(segment
		(start 181.00929 -24.205946)
		(end 180.715412 -24.205946)
		(width 0.1397)
		(layer "In5.Cu")
		(net "PCIE_COMP_TO_SCC_7_DN")
	)
	(segment
		(start 189.944502 -16.495268)
		(end 185.276236 -20.024598)
		(width 0.1397)
		(layer "In5.Cu")
		(net "PCIE_COMP_TO_SCC_7_DN")
	)
	(segment
		(start 185.275982 -20.024598)
		(end 183.29529 -21.522436)
		(width 0.1397)
		(layer "In5.Cu")
		(net "PCIE_COMP_TO_SCC_7_DN")
	)
	(segment
		(start 181.732174 -23.819358)
		(end 181.582568 -23.968202)
		(width 0.1397)
		(layer "In5.Cu")
		(net "PCIE_COMP_TO_SCC_7_DN")
	)
	(segment
		(start 192.433448 -3.465322)
		(end 192.149222 -3.465322)
		(width 0.1397)
		(layer "In5.Cu")
		(net "PCIE_COMP_TO_SCC_7_DN")
	)
	(segment
		(start 181.936136 -23.615142)
		(end 181.732174 -23.819104)
		(width 0.1397)
		(layer "In5.Cu")
		(net "PCIE_COMP_TO_SCC_7_DN")
	)
	(segment
		(start 191.864996 -13.098526)
		(end 191.726566 -13.750798)
		(width 0.1397)
		(layer "In5.Cu")
		(net "PCIE_COMP_TO_SCC_7_DN")
	)
	(segment
		(start 181.732174 -23.819104)
		(end 181.732174 -23.819358)
		(width 0.1397)
		(layer "In5.Cu")
		(net "PCIE_COMP_TO_SCC_7_DN")
	)
	(segment
		(start 183.29529 -21.522436)
		(end 181.936136 -23.615142)
		(width 0.1397)
		(layer "In5.Cu")
		(net "PCIE_COMP_TO_SCC_7_DN")
	)
	(segment
		(start 192.599818 -3.999992)
		(end 192.599818 -3.631692)
		(width 0.1397)
		(layer "In5.Cu")
		(net "PCIE_COMP_TO_SCC_7_DN")
	)
	(segment
		(start 185.276236 -20.024598)
		(end 185.275982 -20.024598)
		(width 0.1397)
		(layer "In5.Cu")
		(net "PCIE_COMP_TO_SCC_7_DN")
	)
	(segment
		(start 191.864996 -3.749548)
		(end 191.864996 -13.098526)
		(width 0.1397)
		(layer "In5.Cu")
		(net "PCIE_COMP_TO_SCC_7_DN")
	)
	(segment
		(start 191.726566 -13.750798)
		(end 189.944502 -16.495268)
		(width 0.1397)
		(layer "In5.Cu")
		(net "PCIE_COMP_TO_SCC_7_DN")
	)
	(arc
		(start 192.599818 -3.631692)
		(mid 192.551089 -3.514051)
		(end 192.433448 -3.465322)
		(width 0.1397)
		(layer "In5.Cu")
		(net "PCIE_COMP_TO_SCC_7_DN")
	)
	(arc
		(start 192.149222 -3.465322)
		(mid 191.948244 -3.54857)
		(end 191.864996 -3.749548)
		(width 0.1397)
		(layer "In5.Cu")
		(net "PCIE_COMP_TO_SCC_7_DN")
	)
	(arc
		(start 181.582568 -23.968202)
		(mid 181.319576 -24.144114)
		(end 181.00929 -24.205946)
		(width 0.1397)
		(layer "In5.Cu")
		(net "PCIE_COMP_TO_SCC_7_DN")
	)
	(arc
		(start 180.715412 -24.205946)
		(mid 180.517846 -24.28778)
		(end 180.436012 -24.485346)
		(width 0.1397)
		(layer "In5.Cu")
		(net "PCIE_COMP_TO_SCC_7_DN")
	)
	(segment
		(start 177.287682 -23.913592)
		(end 177.287682 -25.274778)
		(width 0.14605)
		(layer "F.Cu")
		(net "PCIE_COMP_TO_SCC_6_DP")
	)
	(segment
		(start 175.50003 -27.06243)
		(end 175.50003 -28.299918)
		(width 0.14605)
		(layer "F.Cu")
		(net "PCIE_COMP_TO_SCC_6_DP")
	)
	(segment
		(start 175.50003 -28.299918)
		(end 175.399954 -28.399994)
		(width 0.14605)
		(layer "F.Cu")
		(net "PCIE_COMP_TO_SCC_6_DP")
	)
	(segment
		(start 178.118262 -23.405592)
		(end 177.795682 -23.405592)
		(width 0.14605)
		(layer "F.Cu")
		(net "PCIE_COMP_TO_SCC_6_DP")
	)
	(segment
		(start 177.287682 -25.274778)
		(end 175.50003 -27.06243)
		(width 0.14605)
		(layer "F.Cu")
		(net "PCIE_COMP_TO_SCC_6_DP")
	)
	(arc
		(start 177.795682 -23.405592)
		(mid 177.436472 -23.554382)
		(end 177.287682 -23.913592)
		(width 0.14605)
		(layer "F.Cu")
		(net "PCIE_COMP_TO_SCC_6_DP")
	)
	(arc
		(start 178.407314 -23.11654)
		(mid 178.322653 -23.320931)
		(end 178.118262 -23.405592)
		(width 0.14605)
		(layer "F.Cu")
		(net "PCIE_COMP_TO_SCC_6_DP")
	)
	(segment
		(start 189.39129 -13.516102)
		(end 187.84189 -15.9004)
		(width 0.1397)
		(layer "In5.Cu")
		(net "PCIE_COMP_TO_SCC_6_DP")
	)
	(segment
		(start 183.900572 -18.559272)
		(end 183.653684 -18.511266)
		(width 0.1397)
		(layer "In5.Cu")
		(net "PCIE_COMP_TO_SCC_6_DP")
	)
	(segment
		(start 189.734952 -11.89736)
		(end 189.39129 -13.516102)
		(width 0.1397)
		(layer "In5.Cu")
		(net "PCIE_COMP_TO_SCC_6_DP")
	)
	(segment
		(start 183.653684 -18.511266)
		(end 183.306466 -18.745708)
		(width 0.1397)
		(layer "In5.Cu")
		(net "PCIE_COMP_TO_SCC_6_DP")
	)
	(segment
		(start 185.87974 -17.223994)
		(end 185.632852 -17.175988)
		(width 0.1397)
		(layer "In5.Cu")
		(net "PCIE_COMP_TO_SCC_6_DP")
	)
	(segment
		(start 178.995324 -23.39594)
		(end 178.686714 -23.39594)
		(width 0.1397)
		(layer "In5.Cu")
		(net "PCIE_COMP_TO_SCC_6_DP")
	)
	(segment
		(start 183.25846 -18.992342)
		(end 179.897786 -21.259546)
		(width 0.1397)
		(layer "In5.Cu")
		(net "PCIE_COMP_TO_SCC_6_DP")
	)
	(segment
		(start 190.799974 -3.800094)
		(end 190.799974 -4.168394)
		(width 0.1397)
		(layer "In5.Cu")
		(net "PCIE_COMP_TO_SCC_6_DP")
	)
	(segment
		(start 183.306466 -18.745708)
		(end 183.25846 -18.992342)
		(width 0.1397)
		(layer "In5.Cu")
		(net "PCIE_COMP_TO_SCC_6_DP")
	)
	(segment
		(start 179.361846 -22.257258)
		(end 179.312824 -22.487382)
		(width 0.1397)
		(layer "In5.Cu")
		(net "PCIE_COMP_TO_SCC_6_DP")
	)
	(segment
		(start 179.897786 -21.259546)
		(end 179.416202 -22.001226)
		(width 0.1397)
		(layer "In5.Cu")
		(net "PCIE_COMP_TO_SCC_6_DP")
	)
	(segment
		(start 184.643268 -17.843754)
		(end 184.29605 -18.078196)
		(width 0.1397)
		(layer "In5.Cu")
		(net "PCIE_COMP_TO_SCC_6_DP")
	)
	(segment
		(start 184.29605 -18.078196)
		(end 184.248044 -18.32483)
		(width 0.1397)
		(layer "In5.Cu")
		(net "PCIE_COMP_TO_SCC_6_DP")
	)
	(segment
		(start 189.734952 -4.898644)
		(end 189.734952 -11.89736)
		(width 0.1397)
		(layer "In5.Cu")
		(net "PCIE_COMP_TO_SCC_6_DP")
	)
	(segment
		(start 190.63335 -4.335018)
		(end 190.298578 -4.335018)
		(width 0.1397)
		(layer "In5.Cu")
		(net "PCIE_COMP_TO_SCC_6_DP")
	)
	(segment
		(start 179.312824 -22.487382)
		(end 179.312824 -23.07844)
		(width 0.1397)
		(layer "In5.Cu")
		(net "PCIE_COMP_TO_SCC_6_DP")
	)
	(segment
		(start 185.632852 -17.175988)
		(end 185.28538 -17.41043)
		(width 0.1397)
		(layer "In5.Cu")
		(net "PCIE_COMP_TO_SCC_6_DP")
	)
	(segment
		(start 179.416202 -22.001226)
		(end 179.361846 -22.257258)
		(width 0.1397)
		(layer "In5.Cu")
		(net "PCIE_COMP_TO_SCC_6_DP")
	)
	(segment
		(start 184.890156 -17.89176)
		(end 184.643268 -17.843754)
		(width 0.1397)
		(layer "In5.Cu")
		(net "PCIE_COMP_TO_SCC_6_DP")
	)
	(segment
		(start 185.237628 -17.657318)
		(end 184.890156 -17.89176)
		(width 0.1397)
		(layer "In5.Cu")
		(net "PCIE_COMP_TO_SCC_6_DP")
	)
	(segment
		(start 185.28538 -17.41043)
		(end 185.237628 -17.657318)
		(width 0.1397)
		(layer "In5.Cu")
		(net "PCIE_COMP_TO_SCC_6_DP")
	)
	(segment
		(start 187.84189 -15.9004)
		(end 185.87974 -17.223994)
		(width 0.1397)
		(layer "In5.Cu")
		(net "PCIE_COMP_TO_SCC_6_DP")
	)
	(segment
		(start 184.248044 -18.32483)
		(end 183.900572 -18.559272)
		(width 0.1397)
		(layer "In5.Cu")
		(net "PCIE_COMP_TO_SCC_6_DP")
	)
	(arc
		(start 190.298578 -4.335018)
		(mid 189.900034 -4.5001)
		(end 189.734952 -4.898644)
		(width 0.1397)
		(layer "In5.Cu")
		(net "PCIE_COMP_TO_SCC_6_DP")
	)
	(arc
		(start 178.686714 -23.39594)
		(mid 178.489148 -23.314106)
		(end 178.407314 -23.11654)
		(width 0.1397)
		(layer "In5.Cu")
		(net "PCIE_COMP_TO_SCC_6_DP")
	)
	(arc
		(start 179.312824 -23.07844)
		(mid 179.21983 -23.302946)
		(end 178.995324 -23.39594)
		(width 0.1397)
		(layer "In5.Cu")
		(net "PCIE_COMP_TO_SCC_6_DP")
	)
	(arc
		(start 190.799974 -4.168394)
		(mid 190.751171 -4.286215)
		(end 190.63335 -4.335018)
		(width 0.1397)
		(layer "In5.Cu")
		(net "PCIE_COMP_TO_SCC_6_DP")
	)
	(segment
		(start 177.598832 -25.40381)
		(end 177.598832 -23.913592)
		(width 0.14605)
		(layer "F.Cu")
		(net "PCIE_COMP_TO_SCC_6_DN")
	)
	(segment
		(start 177.795682 -23.716742)
		(end 178.118516 -23.716742)
		(width 0.14605)
		(layer "F.Cu")
		(net "PCIE_COMP_TO_SCC_6_DN")
	)
	(segment
		(start 175.81118 -28.516072)
		(end 175.81118 -27.191462)
		(width 0.14605)
		(layer "F.Cu")
		(net "PCIE_COMP_TO_SCC_6_DN")
	)
	(segment
		(start 175.81118 -27.191462)
		(end 177.598832 -25.40381)
		(width 0.14605)
		(layer "F.Cu")
		(net "PCIE_COMP_TO_SCC_6_DN")
	)
	(segment
		(start 175.457358 -28.869894)
		(end 175.81118 -28.516072)
		(width 0.14605)
		(layer "F.Cu")
		(net "PCIE_COMP_TO_SCC_6_DN")
	)
	(segment
		(start 175.399954 -29.19984)
		(end 175.457358 -29.142436)
		(width 0.14605)
		(layer "F.Cu")
		(net "PCIE_COMP_TO_SCC_6_DN")
	)
	(segment
		(start 175.457358 -29.142436)
		(end 175.457358 -28.869894)
		(width 0.14605)
		(layer "F.Cu")
		(net "PCIE_COMP_TO_SCC_6_DN")
	)
	(arc
		(start 178.118516 -23.716742)
		(mid 178.322727 -23.801329)
		(end 178.407314 -24.00554)
		(width 0.14605)
		(layer "F.Cu")
		(net "PCIE_COMP_TO_SCC_6_DN")
	)
	(arc
		(start 177.598832 -23.913592)
		(mid 177.656488 -23.774398)
		(end 177.795682 -23.716742)
		(width 0.14605)
		(layer "F.Cu")
		(net "PCIE_COMP_TO_SCC_6_DN")
	)
	(segment
		(start 190.065152 -11.932158)
		(end 189.701678 -13.644626)
		(width 0.1397)
		(layer "In5.Cu")
		(net "PCIE_COMP_TO_SCC_6_DN")
	)
	(segment
		(start 190.63335 -4.665218)
		(end 190.298578 -4.665218)
		(width 0.1397)
		(layer "In5.Cu")
		(net "PCIE_COMP_TO_SCC_6_DN")
	)
	(segment
		(start 178.995324 -23.72614)
		(end 178.686714 -23.72614)
		(width 0.1397)
		(layer "In5.Cu")
		(net "PCIE_COMP_TO_SCC_6_DN")
	)
	(segment
		(start 190.065152 -4.898644)
		(end 190.065152 -11.932158)
		(width 0.1397)
		(layer "In5.Cu")
		(net "PCIE_COMP_TO_SCC_6_DN")
	)
	(segment
		(start 188.082428 -16.136874)
		(end 180.138324 -21.49602)
		(width 0.1397)
		(layer "In5.Cu")
		(net "PCIE_COMP_TO_SCC_6_DN")
	)
	(segment
		(start 189.701678 -13.644626)
		(end 188.082428 -16.136874)
		(width 0.1397)
		(layer "In5.Cu")
		(net "PCIE_COMP_TO_SCC_6_DN")
	)
	(segment
		(start 190.799974 -5.200142)
		(end 190.799974 -4.831842)
		(width 0.1397)
		(layer "In5.Cu")
		(net "PCIE_COMP_TO_SCC_6_DN")
	)
	(segment
		(start 179.643024 -22.522434)
		(end 179.643024 -23.07844)
		(width 0.1397)
		(layer "In5.Cu")
		(net "PCIE_COMP_TO_SCC_6_DN")
	)
	(segment
		(start 179.72659 -22.130004)
		(end 179.643024 -22.522434)
		(width 0.1397)
		(layer "In5.Cu")
		(net "PCIE_COMP_TO_SCC_6_DN")
	)
	(segment
		(start 180.138324 -21.49602)
		(end 179.72659 -22.130004)
		(width 0.1397)
		(layer "In5.Cu")
		(net "PCIE_COMP_TO_SCC_6_DN")
	)
	(arc
		(start 190.799974 -4.831842)
		(mid 190.751171 -4.714021)
		(end 190.63335 -4.665218)
		(width 0.1397)
		(layer "In5.Cu")
		(net "PCIE_COMP_TO_SCC_6_DN")
	)
	(arc
		(start 179.643024 -23.07844)
		(mid 179.453317 -23.536433)
		(end 178.995324 -23.72614)
		(width 0.1397)
		(layer "In5.Cu")
		(net "PCIE_COMP_TO_SCC_6_DN")
	)
	(arc
		(start 178.686714 -23.72614)
		(mid 178.489148 -23.807974)
		(end 178.407314 -24.00554)
		(width 0.1397)
		(layer "In5.Cu")
		(net "PCIE_COMP_TO_SCC_6_DN")
	)
	(arc
		(start 190.298578 -4.665218)
		(mid 190.133521 -4.733587)
		(end 190.065152 -4.898644)
		(width 0.1397)
		(layer "In5.Cu")
		(net "PCIE_COMP_TO_SCC_6_DN")
	)
	(segment
		(start 175.194976 -23.954486)
		(end 175.194976 -25.697434)
		(width 0.14605)
		(layer "F.Cu")
		(net "PCIE_COMP_TO_SCC_5_DP")
	)
	(segment
		(start 176.079658 -23.392384)
		(end 175.757078 -23.392384)
		(width 0.14605)
		(layer "F.Cu")
		(net "PCIE_COMP_TO_SCC_5_DP")
	)
	(segment
		(start 173.84141 -27.051)
		(end 173.84141 -28.358592)
		(width 0.14605)
		(layer "F.Cu")
		(net "PCIE_COMP_TO_SCC_5_DP")
	)
	(segment
		(start 175.194976 -25.697434)
		(end 173.84141 -27.051)
		(width 0.14605)
		(layer "F.Cu")
		(net "PCIE_COMP_TO_SCC_5_DP")
	)
	(segment
		(start 173.84141 -28.358592)
		(end 173.800008 -28.399994)
		(width 0.14605)
		(layer "F.Cu")
		(net "PCIE_COMP_TO_SCC_5_DP")
	)
	(arc
		(start 175.757078 -23.392384)
		(mid 175.359612 -23.55702)
		(end 175.194976 -23.954486)
		(width 0.14605)
		(layer "F.Cu")
		(net "PCIE_COMP_TO_SCC_5_DP")
	)
	(arc
		(start 176.36871 -23.103332)
		(mid 176.284049 -23.307723)
		(end 176.079658 -23.392384)
		(width 0.14605)
		(layer "F.Cu")
		(net "PCIE_COMP_TO_SCC_5_DP")
	)
	(segment
		(start 184.720738 -16.710914)
		(end 184.47385 -16.662908)
		(width 0.1397)
		(layer "In5.Cu")
		(net "PCIE_COMP_TO_SCC_5_DP")
	)
	(segment
		(start 188.833252 -3.135122)
		(end 188.54928 -3.135122)
		(width 0.1397)
		(layer "In5.Cu")
		(net "PCIE_COMP_TO_SCC_5_DP")
	)
	(segment
		(start 177.78095 -19.882358)
		(end 177.565304 -20.214336)
		(width 0.1397)
		(layer "In5.Cu")
		(net "PCIE_COMP_TO_SCC_5_DP")
	)
	(segment
		(start 178.19624 -19.612356)
		(end 178.032664 -19.718782)
		(width 0.1397)
		(layer "In5.Cu")
		(net "PCIE_COMP_TO_SCC_5_DP")
	)
	(segment
		(start 184.126378 -16.897096)
		(end 184.078372 -17.143984)
		(width 0.1397)
		(layer "In5.Cu")
		(net "PCIE_COMP_TO_SCC_5_DP")
	)
	(segment
		(start 186.817 -15.296896)
		(end 185.710576 -16.043148)
		(width 0.1397)
		(layer "In5.Cu")
		(net "PCIE_COMP_TO_SCC_5_DP")
	)
	(segment
		(start 178.032664 -19.718782)
		(end 178.029362 -19.720814)
		(width 0.1397)
		(layer "In5.Cu")
		(net "PCIE_COMP_TO_SCC_5_DP")
	)
	(segment
		(start 183.088534 -17.811496)
		(end 181.441344 -18.922492)
		(width 0.1397)
		(layer "In5.Cu")
		(net "PCIE_COMP_TO_SCC_5_DP")
	)
	(segment
		(start 178.00066 -19.73961)
		(end 178.000406 -19.73961)
		(width 0.1397)
		(layer "In5.Cu")
		(net "PCIE_COMP_TO_SCC_5_DP")
	)
	(segment
		(start 185.06821 -16.476472)
		(end 184.720738 -16.710914)
		(width 0.1397)
		(layer "In5.Cu")
		(net "PCIE_COMP_TO_SCC_5_DP")
	)
	(segment
		(start 185.710576 -16.043148)
		(end 185.463688 -15.995142)
		(width 0.1397)
		(layer "In5.Cu")
		(net "PCIE_COMP_TO_SCC_5_DP")
	)
	(segment
		(start 184.47385 -16.662908)
		(end 184.126378 -16.897096)
		(width 0.1397)
		(layer "In5.Cu")
		(net "PCIE_COMP_TO_SCC_5_DP")
	)
	(segment
		(start 187.785248 -13.804646)
		(end 186.817 -15.296896)
		(width 0.1397)
		(layer "In5.Cu")
		(net "PCIE_COMP_TO_SCC_5_DP")
	)
	(segment
		(start 185.463688 -15.995142)
		(end 185.116216 -16.229584)
		(width 0.1397)
		(layer "In5.Cu")
		(net "PCIE_COMP_TO_SCC_5_DP")
	)
	(segment
		(start 183.13654 -17.564608)
		(end 183.088534 -17.811496)
		(width 0.1397)
		(layer "In5.Cu")
		(net "PCIE_COMP_TO_SCC_5_DP")
	)
	(segment
		(start 178.029362 -19.720814)
		(end 178.00066 -19.73961)
		(width 0.1397)
		(layer "In5.Cu")
		(net "PCIE_COMP_TO_SCC_5_DP")
	)
	(segment
		(start 176.95926 -23.382732)
		(end 176.64811 -23.382732)
		(width 0.1397)
		(layer "In5.Cu")
		(net "PCIE_COMP_TO_SCC_5_DP")
	)
	(segment
		(start 185.116216 -16.229584)
		(end 185.06821 -16.476472)
		(width 0.1397)
		(layer "In5.Cu")
		(net "PCIE_COMP_TO_SCC_5_DP")
	)
	(segment
		(start 187.934854 -13.101066)
		(end 187.785248 -13.804646)
		(width 0.1397)
		(layer "In5.Cu")
		(net "PCIE_COMP_TO_SCC_5_DP")
	)
	(segment
		(start 183.484012 -17.33042)
		(end 183.13654 -17.564608)
		(width 0.1397)
		(layer "In5.Cu")
		(net "PCIE_COMP_TO_SCC_5_DP")
	)
	(segment
		(start 184.078372 -17.143984)
		(end 183.7309 -17.378426)
		(width 0.1397)
		(layer "In5.Cu")
		(net "PCIE_COMP_TO_SCC_5_DP")
	)
	(segment
		(start 187.934854 -3.749548)
		(end 187.934854 -13.101066)
		(width 0.1397)
		(layer "In5.Cu")
		(net "PCIE_COMP_TO_SCC_5_DP")
	)
	(segment
		(start 177.565304 -20.214336)
		(end 177.234596 -21.770594)
		(width 0.1397)
		(layer "In5.Cu")
		(net "PCIE_COMP_TO_SCC_5_DP")
	)
	(segment
		(start 181.441344 -18.922492)
		(end 178.19624 -19.612356)
		(width 0.1397)
		(layer "In5.Cu")
		(net "PCIE_COMP_TO_SCC_5_DP")
	)
	(segment
		(start 183.7309 -17.378426)
		(end 183.484012 -17.33042)
		(width 0.1397)
		(layer "In5.Cu")
		(net "PCIE_COMP_TO_SCC_5_DP")
	)
	(segment
		(start 177.234596 -21.770594)
		(end 177.234596 -23.107396)
		(width 0.1397)
		(layer "In5.Cu")
		(net "PCIE_COMP_TO_SCC_5_DP")
	)
	(segment
		(start 178.000406 -19.73961)
		(end 177.78095 -19.882358)
		(width 0.1397)
		(layer "In5.Cu")
		(net "PCIE_COMP_TO_SCC_5_DP")
	)
	(segment
		(start 188.999876 -2.600198)
		(end 188.999876 -2.968498)
		(width 0.1397)
		(layer "In5.Cu")
		(net "PCIE_COMP_TO_SCC_5_DP")
	)
	(arc
		(start 176.64811 -23.382732)
		(mid 176.450544 -23.300898)
		(end 176.36871 -23.103332)
		(width 0.1397)
		(layer "In5.Cu")
		(net "PCIE_COMP_TO_SCC_5_DP")
	)
	(arc
		(start 188.999876 -2.968498)
		(mid 188.951073 -3.086319)
		(end 188.833252 -3.135122)
		(width 0.1397)
		(layer "In5.Cu")
		(net "PCIE_COMP_TO_SCC_5_DP")
	)
	(arc
		(start 188.54928 -3.135122)
		(mid 188.114815 -3.315083)
		(end 187.934854 -3.749548)
		(width 0.1397)
		(layer "In5.Cu")
		(net "PCIE_COMP_TO_SCC_5_DP")
	)
	(arc
		(start 177.234596 -23.107396)
		(mid 177.153952 -23.302088)
		(end 176.95926 -23.382732)
		(width 0.1397)
		(layer "In5.Cu")
		(net "PCIE_COMP_TO_SCC_5_DP")
	)
	(segment
		(start 173.800008 -28.917392)
		(end 174.15256 -28.56484)
		(width 0.14605)
		(layer "F.Cu")
		(net "PCIE_COMP_TO_SCC_5_DN")
	)
	(segment
		(start 175.506126 -25.826466)
		(end 175.506126 -23.954486)
		(width 0.14605)
		(layer "F.Cu")
		(net "PCIE_COMP_TO_SCC_5_DN")
	)
	(segment
		(start 173.800008 -29.19984)
		(end 173.800008 -28.917392)
		(width 0.14605)
		(layer "F.Cu")
		(net "PCIE_COMP_TO_SCC_5_DN")
	)
	(segment
		(start 174.15256 -28.56484)
		(end 174.15256 -27.180032)
		(width 0.14605)
		(layer "F.Cu")
		(net "PCIE_COMP_TO_SCC_5_DN")
	)
	(segment
		(start 174.15256 -27.180032)
		(end 175.506126 -25.826466)
		(width 0.14605)
		(layer "F.Cu")
		(net "PCIE_COMP_TO_SCC_5_DN")
	)
	(segment
		(start 175.757078 -23.703534)
		(end 176.079912 -23.703534)
		(width 0.14605)
		(layer "F.Cu")
		(net "PCIE_COMP_TO_SCC_5_DN")
	)
	(arc
		(start 176.079912 -23.703534)
		(mid 176.284123 -23.788121)
		(end 176.36871 -23.992332)
		(width 0.14605)
		(layer "F.Cu")
		(net "PCIE_COMP_TO_SCC_5_DN")
	)
	(arc
		(start 175.506126 -23.954486)
		(mid 175.579628 -23.777036)
		(end 175.757078 -23.703534)
		(width 0.14605)
		(layer "F.Cu")
		(net "PCIE_COMP_TO_SCC_5_DN")
	)
	(segment
		(start 178.213004 -19.995642)
		(end 178.211226 -19.996912)
		(width 0.1397)
		(layer "In5.Cu")
		(net "PCIE_COMP_TO_SCC_5_DN")
	)
	(segment
		(start 178.209956 -19.997674)
		(end 178.209702 -19.997928)
		(width 0.1397)
		(layer "In5.Cu")
		(net "PCIE_COMP_TO_SCC_5_DN")
	)
	(segment
		(start 177.755042 -20.910296)
		(end 177.564796 -21.805392)
		(width 0.1397)
		(layer "In5.Cu")
		(net "PCIE_COMP_TO_SCC_5_DN")
	)
	(segment
		(start 178.01971 -20.121372)
		(end 178.01971 -20.121118)
		(width 0.1397)
		(layer "In5.Cu")
		(net "PCIE_COMP_TO_SCC_5_DN")
	)
	(segment
		(start 178.211226 -19.996912)
		(end 178.209956 -19.997674)
		(width 0.1397)
		(layer "In5.Cu")
		(net "PCIE_COMP_TO_SCC_5_DN")
	)
	(segment
		(start 178.209702 -19.997928)
		(end 178.093878 -20.073366)
		(width 0.1397)
		(layer "In5.Cu")
		(net "PCIE_COMP_TO_SCC_5_DN")
	)
	(segment
		(start 177.948082 -20.231862)
		(end 177.875692 -20.343114)
		(width 0.1397)
		(layer "In5.Cu")
		(net "PCIE_COMP_TO_SCC_5_DN")
	)
	(segment
		(start 188.265054 -13.135864)
		(end 188.095636 -13.93317)
		(width 0.1397)
		(layer "In5.Cu")
		(net "PCIE_COMP_TO_SCC_5_DN")
	)
	(segment
		(start 188.265054 -3.749548)
		(end 188.265054 -13.135864)
		(width 0.1397)
		(layer "In5.Cu")
		(net "PCIE_COMP_TO_SCC_5_DN")
	)
	(segment
		(start 177.875692 -20.34286)
		(end 177.76698 -20.854416)
		(width 0.1397)
		(layer "In5.Cu")
		(net "PCIE_COMP_TO_SCC_5_DN")
	)
	(segment
		(start 181.572916 -19.232372)
		(end 178.329336 -19.921728)
		(width 0.1397)
		(layer "In5.Cu")
		(net "PCIE_COMP_TO_SCC_5_DN")
	)
	(segment
		(start 188.833506 -3.465322)
		(end 188.54928 -3.465322)
		(width 0.1397)
		(layer "In5.Cu")
		(net "PCIE_COMP_TO_SCC_5_DN")
	)
	(segment
		(start 187.057538 -15.533116)
		(end 181.572916 -19.232372)
		(width 0.1397)
		(layer "In5.Cu")
		(net "PCIE_COMP_TO_SCC_5_DN")
	)
	(segment
		(start 188.999876 -3.999992)
		(end 188.999876 -3.631692)
		(width 0.1397)
		(layer "In5.Cu")
		(net "PCIE_COMP_TO_SCC_5_DN")
	)
	(segment
		(start 177.76698 -20.854416)
		(end 177.755042 -20.910296)
		(width 0.1397)
		(layer "In5.Cu")
		(net "PCIE_COMP_TO_SCC_5_DN")
	)
	(segment
		(start 176.95926 -23.712932)
		(end 176.64811 -23.712932)
		(width 0.1397)
		(layer "In5.Cu")
		(net "PCIE_COMP_TO_SCC_5_DN")
	)
	(segment
		(start 177.875692 -20.343114)
		(end 177.875692 -20.34286)
		(width 0.1397)
		(layer "In5.Cu")
		(net "PCIE_COMP_TO_SCC_5_DN")
	)
	(segment
		(start 178.093878 -20.073366)
		(end 178.07051 -20.088352)
		(width 0.1397)
		(layer "In5.Cu")
		(net "PCIE_COMP_TO_SCC_5_DN")
	)
	(segment
		(start 188.095636 -13.93317)
		(end 187.057538 -15.533116)
		(width 0.1397)
		(layer "In5.Cu")
		(net "PCIE_COMP_TO_SCC_5_DN")
	)
	(segment
		(start 178.329336 -19.921728)
		(end 178.226212 -19.98726)
		(width 0.1397)
		(layer "In5.Cu")
		(net "PCIE_COMP_TO_SCC_5_DN")
	)
	(segment
		(start 178.01971 -20.121118)
		(end 177.948082 -20.231862)
		(width 0.1397)
		(layer "In5.Cu")
		(net "PCIE_COMP_TO_SCC_5_DN")
	)
	(segment
		(start 177.564796 -21.805392)
		(end 177.564796 -23.107396)
		(width 0.1397)
		(layer "In5.Cu")
		(net "PCIE_COMP_TO_SCC_5_DN")
	)
	(segment
		(start 178.07051 -20.088352)
		(end 178.01971 -20.121372)
		(width 0.1397)
		(layer "In5.Cu")
		(net "PCIE_COMP_TO_SCC_5_DN")
	)
	(segment
		(start 178.226212 -19.98726)
		(end 178.213004 -19.995642)
		(width 0.1397)
		(layer "In5.Cu")
		(net "PCIE_COMP_TO_SCC_5_DN")
	)
	(arc
		(start 176.64811 -23.712932)
		(mid 176.450544 -23.794766)
		(end 176.36871 -23.992332)
		(width 0.1397)
		(layer "In5.Cu")
		(net "PCIE_COMP_TO_SCC_5_DN")
	)
	(arc
		(start 177.564796 -23.107396)
		(mid 177.387439 -23.535575)
		(end 176.95926 -23.712932)
		(width 0.1397)
		(layer "In5.Cu")
		(net "PCIE_COMP_TO_SCC_5_DN")
	)
	(arc
		(start 188.999876 -3.631692)
		(mid 188.951147 -3.514051)
		(end 188.833506 -3.465322)
		(width 0.1397)
		(layer "In5.Cu")
		(net "PCIE_COMP_TO_SCC_5_DN")
	)
	(arc
		(start 188.54928 -3.465322)
		(mid 188.348302 -3.54857)
		(end 188.265054 -3.749548)
		(width 0.1397)
		(layer "In5.Cu")
		(net "PCIE_COMP_TO_SCC_5_DN")
	)
	(segment
		(start 173.703234 -23.401528)
		(end 174.025814 -23.401528)
		(width 0.14605)
		(layer "F.Cu")
		(net "PCIE_COMP_TO_SCC_4_DP")
	)
	(segment
		(start 172.999908 -26.049986)
		(end 173.162468 -25.887426)
		(width 0.14605)
		(layer "F.Cu")
		(net "PCIE_COMP_TO_SCC_4_DP")
	)
	(segment
		(start 172.999908 -28.399994)
		(end 172.999908 -26.049986)
		(width 0.14605)
		(layer "F.Cu")
		(net "PCIE_COMP_TO_SCC_4_DP")
	)
	(segment
		(start 173.162468 -25.887426)
		(end 173.162468 -23.942294)
		(width 0.14605)
		(layer "F.Cu")
		(net "PCIE_COMP_TO_SCC_4_DP")
	)
	(arc
		(start 173.162468 -23.942294)
		(mid 173.320855 -23.559915)
		(end 173.703234 -23.401528)
		(width 0.14605)
		(layer "F.Cu")
		(net "PCIE_COMP_TO_SCC_4_DP")
	)
	(arc
		(start 174.025814 -23.401528)
		(mid 174.230205 -23.316867)
		(end 174.314866 -23.112476)
		(width 0.14605)
		(layer "F.Cu")
		(net "PCIE_COMP_TO_SCC_4_DP")
	)
	(segment
		(start 182.931562 -16.21536)
		(end 182.58409 -16.449548)
		(width 0.1397)
		(layer "In5.Cu")
		(net "PCIE_COMP_TO_SCC_4_DP")
	)
	(segment
		(start 175.221138 -22.098508)
		(end 175.221138 -23.12289)
		(width 0.1397)
		(layer "In5.Cu")
		(net "PCIE_COMP_TO_SCC_4_DP")
	)
	(segment
		(start 178.173126 -18.545556)
		(end 177.367184 -19.089116)
		(width 0.1397)
		(layer "In5.Cu")
		(net "PCIE_COMP_TO_SCC_4_DP")
	)
	(segment
		(start 181.941978 -16.882872)
		(end 181.594506 -17.11706)
		(width 0.1397)
		(layer "In5.Cu")
		(net "PCIE_COMP_TO_SCC_4_DP")
	)
	(segment
		(start 182.536338 -16.696436)
		(end 182.188866 -16.930878)
		(width 0.1397)
		(layer "In5.Cu")
		(net "PCIE_COMP_TO_SCC_4_DP")
	)
	(segment
		(start 183.9214 -15.547848)
		(end 183.573928 -15.782036)
		(width 0.1397)
		(layer "In5.Cu")
		(net "PCIE_COMP_TO_SCC_4_DP")
	)
	(segment
		(start 184.168288 -15.595854)
		(end 183.9214 -15.547848)
		(width 0.1397)
		(layer "In5.Cu")
		(net "PCIE_COMP_TO_SCC_4_DP")
	)
	(segment
		(start 186.134756 -4.898644)
		(end 186.134756 -12.04976)
		(width 0.1397)
		(layer "In5.Cu")
		(net "PCIE_COMP_TO_SCC_4_DP")
	)
	(segment
		(start 187.033154 -4.335018)
		(end 186.698382 -4.335018)
		(width 0.1397)
		(layer "In5.Cu")
		(net "PCIE_COMP_TO_SCC_4_DP")
	)
	(segment
		(start 177.367184 -19.089116)
		(end 176.025302 -20.430998)
		(width 0.1397)
		(layer "In5.Cu")
		(net "PCIE_COMP_TO_SCC_4_DP")
	)
	(segment
		(start 181.594506 -17.11706)
		(end 181.546754 -17.363948)
		(width 0.1397)
		(layer "In5.Cu")
		(net "PCIE_COMP_TO_SCC_4_DP")
	)
	(segment
		(start 186.134756 -12.04976)
		(end 185.885836 -13.330174)
		(width 0.1397)
		(layer "In5.Cu")
		(net "PCIE_COMP_TO_SCC_4_DP")
	)
	(segment
		(start 182.58409 -16.449548)
		(end 182.536338 -16.696436)
		(width 0.1397)
		(layer "In5.Cu")
		(net "PCIE_COMP_TO_SCC_4_DP")
	)
	(segment
		(start 184.51576 -15.361412)
		(end 184.168288 -15.595854)
		(width 0.1397)
		(layer "In5.Cu")
		(net "PCIE_COMP_TO_SCC_4_DP")
	)
	(segment
		(start 176.025302 -21.294344)
		(end 175.221138 -22.098508)
		(width 0.1397)
		(layer "In5.Cu")
		(net "PCIE_COMP_TO_SCC_4_DP")
	)
	(segment
		(start 183.525922 -16.028924)
		(end 183.17845 -16.263366)
		(width 0.1397)
		(layer "In5.Cu")
		(net "PCIE_COMP_TO_SCC_4_DP")
	)
	(segment
		(start 176.025302 -20.430998)
		(end 176.025302 -21.294344)
		(width 0.1397)
		(layer "In5.Cu")
		(net "PCIE_COMP_TO_SCC_4_DP")
	)
	(segment
		(start 182.188866 -16.930878)
		(end 181.941978 -16.882872)
		(width 0.1397)
		(layer "In5.Cu")
		(net "PCIE_COMP_TO_SCC_4_DP")
	)
	(segment
		(start 185.24474 -14.280642)
		(end 184.51576 -15.361412)
		(width 0.1397)
		(layer "In5.Cu")
		(net "PCIE_COMP_TO_SCC_4_DP")
	)
	(segment
		(start 183.17845 -16.263366)
		(end 182.931562 -16.21536)
		(width 0.1397)
		(layer "In5.Cu")
		(net "PCIE_COMP_TO_SCC_4_DP")
	)
	(segment
		(start 174.952152 -23.391876)
		(end 174.594266 -23.391876)
		(width 0.1397)
		(layer "In5.Cu")
		(net "PCIE_COMP_TO_SCC_4_DP")
	)
	(segment
		(start 183.573928 -15.782036)
		(end 183.525922 -16.028924)
		(width 0.1397)
		(layer "In5.Cu")
		(net "PCIE_COMP_TO_SCC_4_DP")
	)
	(segment
		(start 185.885836 -13.330174)
		(end 185.24474 -14.280642)
		(width 0.1397)
		(layer "In5.Cu")
		(net "PCIE_COMP_TO_SCC_4_DP")
	)
	(segment
		(start 181.546754 -17.363948)
		(end 180.452014 -18.102326)
		(width 0.1397)
		(layer "In5.Cu")
		(net "PCIE_COMP_TO_SCC_4_DP")
	)
	(segment
		(start 187.199778 -3.800094)
		(end 187.199778 -4.168394)
		(width 0.1397)
		(layer "In5.Cu")
		(net "PCIE_COMP_TO_SCC_4_DP")
	)
	(segment
		(start 180.452014 -18.102326)
		(end 178.173126 -18.545556)
		(width 0.1397)
		(layer "In5.Cu")
		(net "PCIE_COMP_TO_SCC_4_DP")
	)
	(arc
		(start 187.199778 -4.168394)
		(mid 187.150975 -4.286215)
		(end 187.033154 -4.335018)
		(width 0.1397)
		(layer "In5.Cu")
		(net "PCIE_COMP_TO_SCC_4_DP")
	)
	(arc
		(start 175.221138 -23.12289)
		(mid 175.142354 -23.313092)
		(end 174.952152 -23.391876)
		(width 0.1397)
		(layer "In5.Cu")
		(net "PCIE_COMP_TO_SCC_4_DP")
	)
	(arc
		(start 186.698382 -4.335018)
		(mid 186.299838 -4.5001)
		(end 186.134756 -4.898644)
		(width 0.1397)
		(layer "In5.Cu")
		(net "PCIE_COMP_TO_SCC_4_DP")
	)
	(arc
		(start 174.594266 -23.391876)
		(mid 174.3967 -23.310042)
		(end 174.314866 -23.112476)
		(width 0.1397)
		(layer "In5.Cu")
		(net "PCIE_COMP_TO_SCC_4_DP")
	)
	(segment
		(start 172.999908 -29.19984)
		(end 172.999908 -28.91409)
		(width 0.14605)
		(layer "F.Cu")
		(net "PCIE_COMP_TO_SCC_4_DN")
	)
	(segment
		(start 173.311058 -26.179018)
		(end 173.473618 -26.016458)
		(width 0.14605)
		(layer "F.Cu")
		(net "PCIE_COMP_TO_SCC_4_DN")
	)
	(segment
		(start 173.473618 -26.016458)
		(end 173.473618 -23.942294)
		(width 0.14605)
		(layer "F.Cu")
		(net "PCIE_COMP_TO_SCC_4_DN")
	)
	(segment
		(start 173.703234 -23.712678)
		(end 174.026068 -23.712678)
		(width 0.14605)
		(layer "F.Cu")
		(net "PCIE_COMP_TO_SCC_4_DN")
	)
	(segment
		(start 172.999908 -28.91409)
		(end 173.35246 -28.561538)
		(width 0.14605)
		(layer "F.Cu")
		(net "PCIE_COMP_TO_SCC_4_DN")
	)
	(segment
		(start 173.311058 -28.17749)
		(end 173.311058 -26.179018)
		(width 0.14605)
		(layer "F.Cu")
		(net "PCIE_COMP_TO_SCC_4_DN")
	)
	(segment
		(start 173.35246 -28.218892)
		(end 173.311058 -28.17749)
		(width 0.14605)
		(layer "F.Cu")
		(net "PCIE_COMP_TO_SCC_4_DN")
	)
	(segment
		(start 173.35246 -28.561538)
		(end 173.35246 -28.218892)
		(width 0.14605)
		(layer "F.Cu")
		(net "PCIE_COMP_TO_SCC_4_DN")
	)
	(arc
		(start 174.026068 -23.712678)
		(mid 174.230279 -23.797265)
		(end 174.314866 -24.001476)
		(width 0.14605)
		(layer "F.Cu")
		(net "PCIE_COMP_TO_SCC_4_DN")
	)
	(arc
		(start 173.473618 -23.942294)
		(mid 173.540871 -23.779931)
		(end 173.703234 -23.712678)
		(width 0.14605)
		(layer "F.Cu")
		(net "PCIE_COMP_TO_SCC_4_DN")
	)
	(segment
		(start 177.578258 -19.345148)
		(end 176.355502 -20.567904)
		(width 0.1397)
		(layer "In5.Cu")
		(net "PCIE_COMP_TO_SCC_4_DN")
	)
	(segment
		(start 174.952152 -23.722076)
		(end 174.594266 -23.722076)
		(width 0.1397)
		(layer "In5.Cu")
		(net "PCIE_COMP_TO_SCC_4_DN")
	)
	(segment
		(start 187.199778 -5.200142)
		(end 187.199778 -4.831842)
		(width 0.1397)
		(layer "In5.Cu")
		(net "PCIE_COMP_TO_SCC_4_DN")
	)
	(segment
		(start 186.464956 -4.898644)
		(end 186.464956 -12.081764)
		(width 0.1397)
		(layer "In5.Cu")
		(net "PCIE_COMP_TO_SCC_4_DN")
	)
	(segment
		(start 176.355502 -20.567904)
		(end 176.355502 -21.43125)
		(width 0.1397)
		(layer "In5.Cu")
		(net "PCIE_COMP_TO_SCC_4_DN")
	)
	(segment
		(start 186.464956 -12.081764)
		(end 186.19724 -13.459206)
		(width 0.1397)
		(layer "In5.Cu")
		(net "PCIE_COMP_TO_SCC_4_DN")
	)
	(segment
		(start 184.753758 -15.59941)
		(end 180.581046 -18.41373)
		(width 0.1397)
		(layer "In5.Cu")
		(net "PCIE_COMP_TO_SCC_4_DN")
	)
	(segment
		(start 180.581046 -18.41373)
		(end 178.302158 -18.85696)
		(width 0.1397)
		(layer "In5.Cu")
		(net "PCIE_COMP_TO_SCC_4_DN")
	)
	(segment
		(start 178.302158 -18.85696)
		(end 177.578258 -19.345148)
		(width 0.1397)
		(layer "In5.Cu")
		(net "PCIE_COMP_TO_SCC_4_DN")
	)
	(segment
		(start 186.19724 -13.459206)
		(end 185.8391 -13.990066)
		(width 0.1397)
		(layer "In5.Cu")
		(net "PCIE_COMP_TO_SCC_4_DN")
	)
	(segment
		(start 187.033154 -4.665218)
		(end 186.698382 -4.665218)
		(width 0.1397)
		(layer "In5.Cu")
		(net "PCIE_COMP_TO_SCC_4_DN")
	)
	(segment
		(start 185.518552 -14.4653)
		(end 184.753758 -15.59941)
		(width 0.1397)
		(layer "In5.Cu")
		(net "PCIE_COMP_TO_SCC_4_DN")
	)
	(segment
		(start 185.8391 -13.990066)
		(end 185.518552 -14.4653)
		(width 0.1397)
		(layer "In5.Cu")
		(net "PCIE_COMP_TO_SCC_4_DN")
	)
	(segment
		(start 175.551338 -22.235414)
		(end 175.551338 -23.12289)
		(width 0.1397)
		(layer "In5.Cu")
		(net "PCIE_COMP_TO_SCC_4_DN")
	)
	(segment
		(start 176.355502 -21.43125)
		(end 175.551338 -22.235414)
		(width 0.1397)
		(layer "In5.Cu")
		(net "PCIE_COMP_TO_SCC_4_DN")
	)
	(arc
		(start 175.551338 -23.12289)
		(mid 175.37584 -23.546578)
		(end 174.952152 -23.722076)
		(width 0.1397)
		(layer "In5.Cu")
		(net "PCIE_COMP_TO_SCC_4_DN")
	)
	(arc
		(start 186.698382 -4.665218)
		(mid 186.533325 -4.733587)
		(end 186.464956 -4.898644)
		(width 0.1397)
		(layer "In5.Cu")
		(net "PCIE_COMP_TO_SCC_4_DN")
	)
	(arc
		(start 187.199778 -4.831842)
		(mid 187.150975 -4.714021)
		(end 187.033154 -4.665218)
		(width 0.1397)
		(layer "In5.Cu")
		(net "PCIE_COMP_TO_SCC_4_DN")
	)
	(arc
		(start 174.594266 -23.722076)
		(mid 174.3967 -23.80391)
		(end 174.314866 -24.001476)
		(width 0.1397)
		(layer "In5.Cu")
		(net "PCIE_COMP_TO_SCC_4_DN")
	)
	(segment
		(start 171.148248 -26.305764)
		(end 171.148248 -23.911306)
		(width 0.14605)
		(layer "F.Cu")
		(net "PCIE_COMP_TO_SCC_3_DP")
	)
	(segment
		(start 171.657518 -23.402036)
		(end 171.980098 -23.402036)
		(width 0.14605)
		(layer "F.Cu")
		(net "PCIE_COMP_TO_SCC_3_DP")
	)
	(segment
		(start 171.445428 -28.354528)
		(end 171.445428 -26.602944)
		(width 0.14605)
		(layer "F.Cu")
		(net "PCIE_COMP_TO_SCC_3_DP")
	)
	(segment
		(start 171.399962 -28.399994)
		(end 171.445428 -28.354528)
		(width 0.14605)
		(layer "F.Cu")
		(net "PCIE_COMP_TO_SCC_3_DP")
	)
	(segment
		(start 171.445428 -26.602944)
		(end 171.148248 -26.305764)
		(width 0.14605)
		(layer "F.Cu")
		(net "PCIE_COMP_TO_SCC_3_DP")
	)
	(arc
		(start 171.980098 -23.402036)
		(mid 172.184489 -23.317375)
		(end 172.26915 -23.112984)
		(width 0.14605)
		(layer "F.Cu")
		(net "PCIE_COMP_TO_SCC_3_DP")
	)
	(arc
		(start 171.148248 -23.911306)
		(mid 171.29741 -23.551198)
		(end 171.657518 -23.402036)
		(width 0.14605)
		(layer "F.Cu")
		(net "PCIE_COMP_TO_SCC_3_DP")
	)
	(segment
		(start 185.399934 -2.600198)
		(end 185.399934 -2.968498)
		(width 0.1397)
		(layer "In5.Cu")
		(net "PCIE_COMP_TO_SCC_3_DP")
	)
	(segment
		(start 176.199038 -18.751042)
		(end 175.854106 -18.98904)
		(width 0.1397)
		(layer "In5.Cu")
		(net "PCIE_COMP_TO_SCC_3_DP")
	)
	(segment
		(start 176.589436 -18.265648)
		(end 176.244504 -18.5039)
		(width 0.1397)
		(layer "In5.Cu")
		(net "PCIE_COMP_TO_SCC_3_DP")
	)
	(segment
		(start 176.244504 -18.5039)
		(end 176.199038 -18.751042)
		(width 0.1397)
		(layer "In5.Cu")
		(net "PCIE_COMP_TO_SCC_3_DP")
	)
	(segment
		(start 177.22723 -17.82572)
		(end 177.181764 -18.073116)
		(width 0.1397)
		(layer "In5.Cu")
		(net "PCIE_COMP_TO_SCC_3_DP")
	)
	(segment
		(start 176.836832 -18.311114)
		(end 176.589436 -18.265648)
		(width 0.1397)
		(layer "In5.Cu")
		(net "PCIE_COMP_TO_SCC_3_DP")
	)
	(segment
		(start 174.577248 -19.870166)
		(end 174.282862 -20.330922)
		(width 0.1397)
		(layer "In5.Cu")
		(net "PCIE_COMP_TO_SCC_3_DP")
	)
	(segment
		(start 174.068486 -21.067014)
		(end 173.192694 -22.220682)
		(width 0.1397)
		(layer "In5.Cu")
		(net "PCIE_COMP_TO_SCC_3_DP")
	)
	(segment
		(start 177.181764 -18.073116)
		(end 176.836832 -18.311114)
		(width 0.1397)
		(layer "In5.Cu")
		(net "PCIE_COMP_TO_SCC_3_DP")
	)
	(segment
		(start 175.261778 -19.181826)
		(end 175.216566 -19.428968)
		(width 0.1397)
		(layer "In5.Cu")
		(net "PCIE_COMP_TO_SCC_3_DP")
	)
	(segment
		(start 184.263792 -13.839444)
		(end 183.986678 -14.250924)
		(width 0.1397)
		(layer "In5.Cu")
		(net "PCIE_COMP_TO_SCC_3_DP")
	)
	(segment
		(start 177.572162 -17.587722)
		(end 177.22723 -17.82572)
		(width 0.1397)
		(layer "In5.Cu")
		(net "PCIE_COMP_TO_SCC_3_DP")
	)
	(segment
		(start 173.192694 -22.220682)
		(end 173.192694 -23.05685)
		(width 0.1397)
		(layer "In5.Cu")
		(net "PCIE_COMP_TO_SCC_3_DP")
	)
	(segment
		(start 175.854106 -18.98904)
		(end 175.60671 -18.943828)
		(width 0.1397)
		(layer "In5.Cu")
		(net "PCIE_COMP_TO_SCC_3_DP")
	)
	(segment
		(start 185.23331 -3.135122)
		(end 184.949338 -3.135122)
		(width 0.1397)
		(layer "In5.Cu")
		(net "PCIE_COMP_TO_SCC_3_DP")
	)
	(segment
		(start 178.16449 -17.39519)
		(end 177.819558 -17.633188)
		(width 0.1397)
		(layer "In5.Cu")
		(net "PCIE_COMP_TO_SCC_3_DP")
	)
	(segment
		(start 175.60671 -18.943828)
		(end 175.261778 -19.181826)
		(width 0.1397)
		(layer "In5.Cu")
		(net "PCIE_COMP_TO_SCC_3_DP")
	)
	(segment
		(start 183.986678 -14.251178)
		(end 183.78932 -14.544802)
		(width 0.1397)
		(layer "In5.Cu")
		(net "PCIE_COMP_TO_SCC_3_DP")
	)
	(segment
		(start 174.282862 -20.330922)
		(end 174.068486 -21.067014)
		(width 0.1397)
		(layer "In5.Cu")
		(net "PCIE_COMP_TO_SCC_3_DP")
	)
	(segment
		(start 184.334658 -13.473938)
		(end 184.263792 -13.839444)
		(width 0.1397)
		(layer "In5.Cu")
		(net "PCIE_COMP_TO_SCC_3_DP")
	)
	(segment
		(start 183.986678 -14.250924)
		(end 183.986678 -14.251178)
		(width 0.1397)
		(layer "In5.Cu")
		(net "PCIE_COMP_TO_SCC_3_DP")
	)
	(segment
		(start 183.78932 -14.544802)
		(end 180.135784 -16.9164)
		(width 0.1397)
		(layer "In5.Cu")
		(net "PCIE_COMP_TO_SCC_3_DP")
	)
	(segment
		(start 177.819558 -17.633188)
		(end 177.572162 -17.587722)
		(width 0.1397)
		(layer "In5.Cu")
		(net "PCIE_COMP_TO_SCC_3_DP")
	)
	(segment
		(start 172.85716 -23.392384)
		(end 172.54855 -23.392384)
		(width 0.1397)
		(layer "In5.Cu")
		(net "PCIE_COMP_TO_SCC_3_DP")
	)
	(segment
		(start 180.135784 -16.9164)
		(end 178.16449 -17.39519)
		(width 0.1397)
		(layer "In5.Cu")
		(net "PCIE_COMP_TO_SCC_3_DP")
	)
	(segment
		(start 184.334658 -3.749802)
		(end 184.334658 -13.473938)
		(width 0.1397)
		(layer "In5.Cu")
		(net "PCIE_COMP_TO_SCC_3_DP")
	)
	(segment
		(start 175.216566 -19.428968)
		(end 174.577248 -19.870166)
		(width 0.1397)
		(layer "In5.Cu")
		(net "PCIE_COMP_TO_SCC_3_DP")
	)
	(arc
		(start 185.399934 -2.968498)
		(mid 185.351131 -3.086319)
		(end 185.23331 -3.135122)
		(width 0.1397)
		(layer "In5.Cu")
		(net "PCIE_COMP_TO_SCC_3_DP")
	)
	(arc
		(start 184.949338 -3.135122)
		(mid 184.514694 -3.315158)
		(end 184.334658 -3.749802)
		(width 0.1397)
		(layer "In5.Cu")
		(net "PCIE_COMP_TO_SCC_3_DP")
	)
	(arc
		(start 173.192694 -23.05685)
		(mid 173.094418 -23.294108)
		(end 172.85716 -23.392384)
		(width 0.1397)
		(layer "In5.Cu")
		(net "PCIE_COMP_TO_SCC_3_DP")
	)
	(arc
		(start 172.54855 -23.392384)
		(mid 172.350984 -23.31055)
		(end 172.26915 -23.112984)
		(width 0.1397)
		(layer "In5.Cu")
		(net "PCIE_COMP_TO_SCC_3_DP")
	)
	(segment
		(start 171.752514 -28.487624)
		(end 171.756578 -28.48356)
		(width 0.14605)
		(layer "F.Cu")
		(net "PCIE_COMP_TO_SCC_3_DN")
	)
	(segment
		(start 171.399962 -29.19984)
		(end 171.752514 -28.847288)
		(width 0.14605)
		(layer "F.Cu")
		(net "PCIE_COMP_TO_SCC_3_DN")
	)
	(segment
		(start 171.459398 -26.176732)
		(end 171.459398 -23.911306)
		(width 0.14605)
		(layer "F.Cu")
		(net "PCIE_COMP_TO_SCC_3_DN")
	)
	(segment
		(start 171.657518 -23.713186)
		(end 171.980352 -23.713186)
		(width 0.14605)
		(layer "F.Cu")
		(net "PCIE_COMP_TO_SCC_3_DN")
	)
	(segment
		(start 171.752514 -28.847288)
		(end 171.752514 -28.487624)
		(width 0.14605)
		(layer "F.Cu")
		(net "PCIE_COMP_TO_SCC_3_DN")
	)
	(segment
		(start 171.756578 -26.473912)
		(end 171.459398 -26.176732)
		(width 0.14605)
		(layer "F.Cu")
		(net "PCIE_COMP_TO_SCC_3_DN")
	)
	(segment
		(start 171.756578 -28.48356)
		(end 171.756578 -26.473912)
		(width 0.14605)
		(layer "F.Cu")
		(net "PCIE_COMP_TO_SCC_3_DN")
	)
	(arc
		(start 171.980352 -23.713186)
		(mid 172.184563 -23.797773)
		(end 172.26915 -24.001984)
		(width 0.14605)
		(layer "F.Cu")
		(net "PCIE_COMP_TO_SCC_3_DN")
	)
	(arc
		(start 171.459398 -23.911306)
		(mid 171.517426 -23.771214)
		(end 171.657518 -23.713186)
		(width 0.14605)
		(layer "F.Cu")
		(net "PCIE_COMP_TO_SCC_3_DN")
	)
	(segment
		(start 178.30165 -17.701768)
		(end 174.819818 -20.104354)
		(width 0.1397)
		(layer "In5.Cu")
		(net "PCIE_COMP_TO_SCC_3_DN")
	)
	(segment
		(start 184.025794 -14.785086)
		(end 180.268372 -17.224248)
		(width 0.1397)
		(layer "In5.Cu")
		(net "PCIE_COMP_TO_SCC_3_DN")
	)
	(segment
		(start 174.49292 -20.790916)
		(end 174.368714 -21.217636)
		(width 0.1397)
		(layer "In5.Cu")
		(net "PCIE_COMP_TO_SCC_3_DN")
	)
	(segment
		(start 185.233564 -3.465322)
		(end 184.949338 -3.465322)
		(width 0.1397)
		(layer "In5.Cu")
		(net "PCIE_COMP_TO_SCC_3_DN")
	)
	(segment
		(start 184.623456 -13.71981)
		(end 184.575196 -13.968222)
		(width 0.1397)
		(layer "In5.Cu")
		(net "PCIE_COMP_TO_SCC_3_DN")
	)
	(segment
		(start 174.586646 -20.468844)
		(end 174.49292 -20.790916)
		(width 0.1397)
		(layer "In5.Cu")
		(net "PCIE_COMP_TO_SCC_3_DN")
	)
	(segment
		(start 174.368714 -21.217636)
		(end 173.522894 -22.331934)
		(width 0.1397)
		(layer "In5.Cu")
		(net "PCIE_COMP_TO_SCC_3_DN")
	)
	(segment
		(start 185.399934 -3.999992)
		(end 185.399934 -3.631692)
		(width 0.1397)
		(layer "In5.Cu")
		(net "PCIE_COMP_TO_SCC_3_DN")
	)
	(segment
		(start 184.575196 -13.968222)
		(end 184.025794 -14.785086)
		(width 0.1397)
		(layer "In5.Cu")
		(net "PCIE_COMP_TO_SCC_3_DN")
	)
	(segment
		(start 184.664858 -3.749802)
		(end 184.664858 -13.505688)
		(width 0.1397)
		(layer "In5.Cu")
		(net "PCIE_COMP_TO_SCC_3_DN")
	)
	(segment
		(start 173.522894 -22.331934)
		(end 173.522894 -23.05685)
		(width 0.1397)
		(layer "In5.Cu")
		(net "PCIE_COMP_TO_SCC_3_DN")
	)
	(segment
		(start 184.664858 -13.505688)
		(end 184.623456 -13.71981)
		(width 0.1397)
		(layer "In5.Cu")
		(net "PCIE_COMP_TO_SCC_3_DN")
	)
	(segment
		(start 172.85716 -23.722584)
		(end 172.54855 -23.722584)
		(width 0.1397)
		(layer "In5.Cu")
		(net "PCIE_COMP_TO_SCC_3_DN")
	)
	(segment
		(start 174.819818 -20.104354)
		(end 174.586646 -20.468844)
		(width 0.1397)
		(layer "In5.Cu")
		(net "PCIE_COMP_TO_SCC_3_DN")
	)
	(segment
		(start 180.268372 -17.224248)
		(end 178.30165 -17.701768)
		(width 0.1397)
		(layer "In5.Cu")
		(net "PCIE_COMP_TO_SCC_3_DN")
	)
	(arc
		(start 185.399934 -3.631692)
		(mid 185.351205 -3.514051)
		(end 185.233564 -3.465322)
		(width 0.1397)
		(layer "In5.Cu")
		(net "PCIE_COMP_TO_SCC_3_DN")
	)
	(arc
		(start 173.522894 -23.05685)
		(mid 173.327905 -23.527595)
		(end 172.85716 -23.722584)
		(width 0.1397)
		(layer "In5.Cu")
		(net "PCIE_COMP_TO_SCC_3_DN")
	)
	(arc
		(start 172.54855 -23.722584)
		(mid 172.350984 -23.804418)
		(end 172.26915 -24.001984)
		(width 0.1397)
		(layer "In5.Cu")
		(net "PCIE_COMP_TO_SCC_3_DN")
	)
	(arc
		(start 184.949338 -3.465322)
		(mid 184.74818 -3.548644)
		(end 184.664858 -3.749802)
		(width 0.1397)
		(layer "In5.Cu")
		(net "PCIE_COMP_TO_SCC_3_DN")
	)
	(segment
		(start 170.641264 -27.223974)
		(end 169.106088 -25.688798)
		(width 0.14605)
		(layer "F.Cu")
		(net "PCIE_COMP_TO_SCC_2_DP")
	)
	(segment
		(start 169.605452 -23.404322)
		(end 169.928032 -23.404322)
		(width 0.14605)
		(layer "F.Cu")
		(net "PCIE_COMP_TO_SCC_2_DP")
	)
	(segment
		(start 169.106088 -25.688798)
		(end 169.106088 -23.903686)
		(width 0.14605)
		(layer "F.Cu")
		(net "PCIE_COMP_TO_SCC_2_DP")
	)
	(segment
		(start 170.599862 -28.399994)
		(end 170.641264 -28.358592)
		(width 0.14605)
		(layer "F.Cu")
		(net "PCIE_COMP_TO_SCC_2_DP")
	)
	(segment
		(start 170.641264 -28.358592)
		(end 170.641264 -27.223974)
		(width 0.14605)
		(layer "F.Cu")
		(net "PCIE_COMP_TO_SCC_2_DP")
	)
	(arc
		(start 169.106088 -23.903686)
		(mid 169.252348 -23.550582)
		(end 169.605452 -23.404322)
		(width 0.14605)
		(layer "F.Cu")
		(net "PCIE_COMP_TO_SCC_2_DP")
	)
	(arc
		(start 169.928032 -23.404322)
		(mid 170.132423 -23.319661)
		(end 170.217084 -23.11527)
		(width 0.14605)
		(layer "F.Cu")
		(net "PCIE_COMP_TO_SCC_2_DP")
	)
	(segment
		(start 183.433212 -4.335018)
		(end 183.09844 -4.335018)
		(width 0.1397)
		(layer "In5.Cu")
		(net "PCIE_COMP_TO_SCC_2_DP")
	)
	(segment
		(start 177.224436 -16.617442)
		(end 176.977548 -16.569436)
		(width 0.1397)
		(layer "In5.Cu")
		(net "PCIE_COMP_TO_SCC_2_DP")
	)
	(segment
		(start 181.34965 -14.672056)
		(end 181.062884 -14.865604)
		(width 0.1397)
		(layer "In5.Cu")
		(net "PCIE_COMP_TO_SCC_2_DP")
	)
	(segment
		(start 180.2003 -15.447772)
		(end 178.455066 -15.78737)
		(width 0.1397)
		(layer "In5.Cu")
		(net "PCIE_COMP_TO_SCC_2_DP")
	)
	(segment
		(start 176.582324 -17.050512)
		(end 176.234852 -17.284954)
		(width 0.1397)
		(layer "In5.Cu")
		(net "PCIE_COMP_TO_SCC_2_DP")
	)
	(segment
		(start 174.998126 -17.90446)
		(end 174.650654 -18.138648)
		(width 0.1397)
		(layer "In5.Cu")
		(net "PCIE_COMP_TO_SCC_2_DP")
	)
	(segment
		(start 178.455066 -15.78737)
		(end 177.224436 -16.617442)
		(width 0.1397)
		(layer "In5.Cu")
		(net "PCIE_COMP_TO_SCC_2_DP")
	)
	(segment
		(start 175.987964 -17.236948)
		(end 175.640492 -17.471136)
		(width 0.1397)
		(layer "In5.Cu")
		(net "PCIE_COMP_TO_SCC_2_DP")
	)
	(segment
		(start 182.534814 -4.898644)
		(end 182.534814 -12.5095)
		(width 0.1397)
		(layer "In5.Cu")
		(net "PCIE_COMP_TO_SCC_2_DP")
	)
	(segment
		(start 174.650654 -18.138648)
		(end 174.602902 -18.385536)
		(width 0.1397)
		(layer "In5.Cu")
		(net "PCIE_COMP_TO_SCC_2_DP")
	)
	(segment
		(start 176.630076 -16.803878)
		(end 176.582324 -17.050512)
		(width 0.1397)
		(layer "In5.Cu")
		(net "PCIE_COMP_TO_SCC_2_DP")
	)
	(segment
		(start 175.245014 -17.952466)
		(end 174.998126 -17.90446)
		(width 0.1397)
		(layer "In5.Cu")
		(net "PCIE_COMP_TO_SCC_2_DP")
	)
	(segment
		(start 182.30088 -13.262864)
		(end 182.300626 -13.26261)
		(width 0.1397)
		(layer "In5.Cu")
		(net "PCIE_COMP_TO_SCC_2_DP")
	)
	(segment
		(start 176.977548 -16.569436)
		(end 176.630076 -16.803878)
		(width 0.1397)
		(layer "In5.Cu")
		(net "PCIE_COMP_TO_SCC_2_DP")
	)
	(segment
		(start 181.062884 -14.865604)
		(end 180.2003 -15.447772)
		(width 0.1397)
		(layer "In5.Cu")
		(net "PCIE_COMP_TO_SCC_2_DP")
	)
	(segment
		(start 174.602902 -18.385536)
		(end 173.086776 -19.40814)
		(width 0.1397)
		(layer "In5.Cu")
		(net "PCIE_COMP_TO_SCC_2_DP")
	)
	(segment
		(start 176.234852 -17.284954)
		(end 175.987964 -17.236948)
		(width 0.1397)
		(layer "In5.Cu")
		(net "PCIE_COMP_TO_SCC_2_DP")
	)
	(segment
		(start 183.599836 -3.800094)
		(end 183.599836 -4.168394)
		(width 0.1397)
		(layer "In5.Cu")
		(net "PCIE_COMP_TO_SCC_2_DP")
	)
	(segment
		(start 175.640492 -17.471136)
		(end 175.592486 -17.718024)
		(width 0.1397)
		(layer "In5.Cu")
		(net "PCIE_COMP_TO_SCC_2_DP")
	)
	(segment
		(start 175.592486 -17.718024)
		(end 175.245014 -17.952466)
		(width 0.1397)
		(layer "In5.Cu")
		(net "PCIE_COMP_TO_SCC_2_DP")
	)
	(segment
		(start 182.534814 -12.5095)
		(end 182.30088 -13.262864)
		(width 0.1397)
		(layer "In5.Cu")
		(net "PCIE_COMP_TO_SCC_2_DP")
	)
	(segment
		(start 173.086776 -19.40814)
		(end 171.142152 -22.338284)
		(width 0.1397)
		(layer "In5.Cu")
		(net "PCIE_COMP_TO_SCC_2_DP")
	)
	(segment
		(start 182.300626 -13.26261)
		(end 181.34965 -14.672056)
		(width 0.1397)
		(layer "In5.Cu")
		(net "PCIE_COMP_TO_SCC_2_DP")
	)
	(segment
		(start 170.762422 -23.39467)
		(end 170.496484 -23.39467)
		(width 0.1397)
		(layer "In5.Cu")
		(net "PCIE_COMP_TO_SCC_2_DP")
	)
	(segment
		(start 171.142152 -22.338284)
		(end 171.142152 -23.01494)
		(width 0.1397)
		(layer "In5.Cu")
		(net "PCIE_COMP_TO_SCC_2_DP")
	)
	(arc
		(start 183.09844 -4.335018)
		(mid 182.699896 -4.5001)
		(end 182.534814 -4.898644)
		(width 0.1397)
		(layer "In5.Cu")
		(net "PCIE_COMP_TO_SCC_2_DP")
	)
	(arc
		(start 170.496484 -23.39467)
		(mid 170.298918 -23.312836)
		(end 170.217084 -23.11527)
		(width 0.1397)
		(layer "In5.Cu")
		(net "PCIE_COMP_TO_SCC_2_DP")
	)
	(arc
		(start 183.599836 -4.168394)
		(mid 183.551033 -4.286215)
		(end 183.433212 -4.335018)
		(width 0.1397)
		(layer "In5.Cu")
		(net "PCIE_COMP_TO_SCC_2_DP")
	)
	(arc
		(start 171.142152 -23.01494)
		(mid 171.030932 -23.28345)
		(end 170.762422 -23.39467)
		(width 0.1397)
		(layer "In5.Cu")
		(net "PCIE_COMP_TO_SCC_2_DP")
	)
	(segment
		(start 169.605452 -23.715472)
		(end 169.928286 -23.715472)
		(width 0.14605)
		(layer "F.Cu")
		(net "PCIE_COMP_TO_SCC_2_DN")
	)
	(segment
		(start 170.599862 -29.19984)
		(end 170.952414 -28.847288)
		(width 0.14605)
		(layer "F.Cu")
		(net "PCIE_COMP_TO_SCC_2_DN")
	)
	(segment
		(start 169.417238 -25.559766)
		(end 169.417238 -23.903686)
		(width 0.14605)
		(layer "F.Cu")
		(net "PCIE_COMP_TO_SCC_2_DN")
	)
	(segment
		(start 170.952414 -28.847288)
		(end 170.952414 -27.094942)
		(width 0.14605)
		(layer "F.Cu")
		(net "PCIE_COMP_TO_SCC_2_DN")
	)
	(segment
		(start 170.952414 -27.094942)
		(end 169.417238 -25.559766)
		(width 0.14605)
		(layer "F.Cu")
		(net "PCIE_COMP_TO_SCC_2_DN")
	)
	(arc
		(start 169.928286 -23.715472)
		(mid 170.132497 -23.800059)
		(end 170.217084 -24.00427)
		(width 0.14605)
		(layer "F.Cu")
		(net "PCIE_COMP_TO_SCC_2_DN")
	)
	(arc
		(start 169.417238 -23.903686)
		(mid 169.472365 -23.770599)
		(end 169.605452 -23.715472)
		(width 0.14605)
		(layer "F.Cu")
		(net "PCIE_COMP_TO_SCC_2_DN")
	)
	(segment
		(start 170.762422 -23.72487)
		(end 170.496484 -23.72487)
		(width 0.1397)
		(layer "In5.Cu")
		(net "PCIE_COMP_TO_SCC_2_DN")
	)
	(segment
		(start 173.32579 -19.645376)
		(end 171.472352 -22.438106)
		(width 0.1397)
		(layer "In5.Cu")
		(net "PCIE_COMP_TO_SCC_2_DN")
	)
	(segment
		(start 182.60187 -13.407136)
		(end 181.587648 -14.910054)
		(width 0.1397)
		(layer "In5.Cu")
		(net "PCIE_COMP_TO_SCC_2_DN")
	)
	(segment
		(start 178.584098 -16.098774)
		(end 173.32579 -19.645376)
		(width 0.1397)
		(layer "In5.Cu")
		(net "PCIE_COMP_TO_SCC_2_DN")
	)
	(segment
		(start 183.599836 -5.200142)
		(end 183.599836 -4.831842)
		(width 0.1397)
		(layer "In5.Cu")
		(net "PCIE_COMP_TO_SCC_2_DN")
	)
	(segment
		(start 180.329332 -15.759176)
		(end 178.584098 -16.098774)
		(width 0.1397)
		(layer "In5.Cu")
		(net "PCIE_COMP_TO_SCC_2_DN")
	)
	(segment
		(start 181.587648 -14.910054)
		(end 180.329332 -15.759176)
		(width 0.1397)
		(layer "In5.Cu")
		(net "PCIE_COMP_TO_SCC_2_DN")
	)
	(segment
		(start 182.865014 -4.898644)
		(end 182.865014 -12.559792)
		(width 0.1397)
		(layer "In5.Cu")
		(net "PCIE_COMP_TO_SCC_2_DN")
	)
	(segment
		(start 182.865014 -12.559792)
		(end 182.60187 -13.407136)
		(width 0.1397)
		(layer "In5.Cu")
		(net "PCIE_COMP_TO_SCC_2_DN")
	)
	(segment
		(start 183.433212 -4.665218)
		(end 183.09844 -4.665218)
		(width 0.1397)
		(layer "In5.Cu")
		(net "PCIE_COMP_TO_SCC_2_DN")
	)
	(segment
		(start 171.472352 -22.438106)
		(end 171.472352 -23.01494)
		(width 0.1397)
		(layer "In5.Cu")
		(net "PCIE_COMP_TO_SCC_2_DN")
	)
	(arc
		(start 183.599836 -4.831842)
		(mid 183.551033 -4.714021)
		(end 183.433212 -4.665218)
		(width 0.1397)
		(layer "In5.Cu")
		(net "PCIE_COMP_TO_SCC_2_DN")
	)
	(arc
		(start 170.496484 -23.72487)
		(mid 170.298918 -23.806704)
		(end 170.217084 -24.00427)
		(width 0.1397)
		(layer "In5.Cu")
		(net "PCIE_COMP_TO_SCC_2_DN")
	)
	(arc
		(start 171.472352 -23.01494)
		(mid 171.264418 -23.516936)
		(end 170.762422 -23.72487)
		(width 0.1397)
		(layer "In5.Cu")
		(net "PCIE_COMP_TO_SCC_2_DN")
	)
	(arc
		(start 183.09844 -4.665218)
		(mid 182.933383 -4.733587)
		(end 182.865014 -4.898644)
		(width 0.1397)
		(layer "In5.Cu")
		(net "PCIE_COMP_TO_SCC_2_DN")
	)
	(segment
		(start 169.041318 -28.358592)
		(end 169.041318 -27.270202)
		(width 0.14605)
		(layer "F.Cu")
		(net "PCIE_COMP_TO_SCC_1_DP")
	)
	(segment
		(start 167.02151 -25.250394)
		(end 167.02151 -23.939754)
		(width 0.14605)
		(layer "F.Cu")
		(net "PCIE_COMP_TO_SCC_1_DP")
	)
	(segment
		(start 168.999916 -28.399994)
		(end 169.041318 -28.358592)
		(width 0.14605)
		(layer "F.Cu")
		(net "PCIE_COMP_TO_SCC_1_DP")
	)
	(segment
		(start 167.548306 -23.412958)
		(end 167.870886 -23.412958)
		(width 0.14605)
		(layer "F.Cu")
		(net "PCIE_COMP_TO_SCC_1_DP")
	)
	(segment
		(start 169.041318 -27.270202)
		(end 167.02151 -25.250394)
		(width 0.14605)
		(layer "F.Cu")
		(net "PCIE_COMP_TO_SCC_1_DP")
	)
	(arc
		(start 167.02151 -23.939754)
		(mid 167.175805 -23.567253)
		(end 167.548306 -23.412958)
		(width 0.14605)
		(layer "F.Cu")
		(net "PCIE_COMP_TO_SCC_1_DP")
	)
	(arc
		(start 167.870886 -23.412958)
		(mid 168.075277 -23.328297)
		(end 168.159938 -23.123906)
		(width 0.14605)
		(layer "F.Cu")
		(net "PCIE_COMP_TO_SCC_1_DP")
	)
	(segment
		(start 168.412922 -20.262342)
		(end 168.264586 -20.968208)
		(width 0.1397)
		(layer "In5.Cu")
		(net "PCIE_COMP_TO_SCC_1_DP")
	)
	(segment
		(start 168.672256 -19.862546)
		(end 168.412922 -20.262342)
		(width 0.1397)
		(layer "In5.Cu")
		(net "PCIE_COMP_TO_SCC_1_DP")
	)
	(segment
		(start 177.377598 -14.912086)
		(end 175.56988 -16.131286)
		(width 0.1397)
		(layer "In5.Cu")
		(net "PCIE_COMP_TO_SCC_1_DP")
	)
	(segment
		(start 168.760394 -23.403306)
		(end 168.439338 -23.403306)
		(width 0.1397)
		(layer "In5.Cu")
		(net "PCIE_COMP_TO_SCC_1_DP")
	)
	(segment
		(start 172.774102 -18.016728)
		(end 172.320712 -18.32229)
		(width 0.1397)
		(layer "In5.Cu")
		(net "PCIE_COMP_TO_SCC_1_DP")
	)
	(segment
		(start 174.97552 -16.317722)
		(end 174.927514 -16.564356)
		(width 0.1397)
		(layer "In5.Cu")
		(net "PCIE_COMP_TO_SCC_1_DP")
	)
	(segment
		(start 175.56988 -16.131286)
		(end 175.322992 -16.08328)
		(width 0.1397)
		(layer "In5.Cu")
		(net "PCIE_COMP_TO_SCC_1_DP")
	)
	(segment
		(start 174.927514 -16.564356)
		(end 174.580042 -16.798798)
		(width 0.1397)
		(layer "In5.Cu")
		(net "PCIE_COMP_TO_SCC_1_DP")
	)
	(segment
		(start 168.264586 -20.968208)
		(end 168.373044 -21.478494)
		(width 0.1397)
		(layer "In5.Cu")
		(net "PCIE_COMP_TO_SCC_1_DP")
	)
	(segment
		(start 175.322992 -16.08328)
		(end 174.97552 -16.317722)
		(width 0.1397)
		(layer "In5.Cu")
		(net "PCIE_COMP_TO_SCC_1_DP")
	)
	(segment
		(start 180.429408 -14.047724)
		(end 179.86375 -14.429994)
		(width 0.1397)
		(layer "In5.Cu")
		(net "PCIE_COMP_TO_SCC_1_DP")
	)
	(segment
		(start 180.616606 -13.759434)
		(end 180.429408 -14.047724)
		(width 0.1397)
		(layer "In5.Cu")
		(net "PCIE_COMP_TO_SCC_1_DP")
	)
	(segment
		(start 173.590204 -17.46631)
		(end 173.343316 -17.418304)
		(width 0.1397)
		(layer "In5.Cu")
		(net "PCIE_COMP_TO_SCC_1_DP")
	)
	(segment
		(start 172.995844 -17.652746)
		(end 172.947838 -17.89938)
		(width 0.1397)
		(layer "In5.Cu")
		(net "PCIE_COMP_TO_SCC_1_DP")
	)
	(segment
		(start 174.580042 -16.798798)
		(end 174.333154 -16.750792)
		(width 0.1397)
		(layer "In5.Cu")
		(net "PCIE_COMP_TO_SCC_1_DP")
	)
	(segment
		(start 173.937676 -17.231868)
		(end 173.590204 -17.46631)
		(width 0.1397)
		(layer "In5.Cu")
		(net "PCIE_COMP_TO_SCC_1_DP")
	)
	(segment
		(start 172.947838 -17.89938)
		(end 172.774102 -18.016728)
		(width 0.1397)
		(layer "In5.Cu")
		(net "PCIE_COMP_TO_SCC_1_DP")
	)
	(segment
		(start 181.633368 -3.135122)
		(end 181.349396 -3.135122)
		(width 0.1397)
		(layer "In5.Cu")
		(net "PCIE_COMP_TO_SCC_1_DP")
	)
	(segment
		(start 169.002964 -22.605746)
		(end 169.002964 -23.160736)
		(width 0.1397)
		(layer "In5.Cu")
		(net "PCIE_COMP_TO_SCC_1_DP")
	)
	(segment
		(start 172.320712 -18.32229)
		(end 168.672256 -19.862546)
		(width 0.1397)
		(layer "In5.Cu")
		(net "PCIE_COMP_TO_SCC_1_DP")
	)
	(segment
		(start 180.734716 -3.749802)
		(end 180.734716 -13.203936)
		(width 0.1397)
		(layer "In5.Cu")
		(net "PCIE_COMP_TO_SCC_1_DP")
	)
	(segment
		(start 179.86375 -14.429994)
		(end 177.377598 -14.912086)
		(width 0.1397)
		(layer "In5.Cu")
		(net "PCIE_COMP_TO_SCC_1_DP")
	)
	(segment
		(start 168.373044 -21.478494)
		(end 169.002964 -22.605746)
		(width 0.1397)
		(layer "In5.Cu")
		(net "PCIE_COMP_TO_SCC_1_DP")
	)
	(segment
		(start 174.333154 -16.750792)
		(end 173.985682 -16.985234)
		(width 0.1397)
		(layer "In5.Cu")
		(net "PCIE_COMP_TO_SCC_1_DP")
	)
	(segment
		(start 173.343316 -17.418304)
		(end 172.995844 -17.652746)
		(width 0.1397)
		(layer "In5.Cu")
		(net "PCIE_COMP_TO_SCC_1_DP")
	)
	(segment
		(start 180.734716 -13.203936)
		(end 180.616606 -13.759434)
		(width 0.1397)
		(layer "In5.Cu")
		(net "PCIE_COMP_TO_SCC_1_DP")
	)
	(segment
		(start 181.799992 -2.600198)
		(end 181.799992 -2.968498)
		(width 0.1397)
		(layer "In5.Cu")
		(net "PCIE_COMP_TO_SCC_1_DP")
	)
	(segment
		(start 173.985682 -16.985234)
		(end 173.937676 -17.231868)
		(width 0.1397)
		(layer "In5.Cu")
		(net "PCIE_COMP_TO_SCC_1_DP")
	)
	(arc
		(start 181.799992 -2.968498)
		(mid 181.751189 -3.086319)
		(end 181.633368 -3.135122)
		(width 0.1397)
		(layer "In5.Cu")
		(net "PCIE_COMP_TO_SCC_1_DP")
	)
	(arc
		(start 169.002964 -23.160736)
		(mid 168.931917 -23.332259)
		(end 168.760394 -23.403306)
		(width 0.1397)
		(layer "In5.Cu")
		(net "PCIE_COMP_TO_SCC_1_DP")
	)
	(arc
		(start 181.349396 -3.135122)
		(mid 180.914752 -3.315158)
		(end 180.734716 -3.749802)
		(width 0.1397)
		(layer "In5.Cu")
		(net "PCIE_COMP_TO_SCC_1_DP")
	)
	(arc
		(start 168.439338 -23.403306)
		(mid 168.241772 -23.321472)
		(end 168.159938 -23.123906)
		(width 0.1397)
		(layer "In5.Cu")
		(net "PCIE_COMP_TO_SCC_1_DP")
	)
	(segment
		(start 167.33266 -25.121362)
		(end 167.33266 -23.939754)
		(width 0.14605)
		(layer "F.Cu")
		(net "PCIE_COMP_TO_SCC_1_DN")
	)
	(segment
		(start 168.999916 -29.19984)
		(end 169.352468 -28.847288)
		(width 0.14605)
		(layer "F.Cu")
		(net "PCIE_COMP_TO_SCC_1_DN")
	)
	(segment
		(start 169.352468 -27.14117)
		(end 167.33266 -25.121362)
		(width 0.14605)
		(layer "F.Cu")
		(net "PCIE_COMP_TO_SCC_1_DN")
	)
	(segment
		(start 169.352468 -28.847288)
		(end 169.352468 -27.14117)
		(width 0.14605)
		(layer "F.Cu")
		(net "PCIE_COMP_TO_SCC_1_DN")
	)
	(segment
		(start 167.548306 -23.724108)
		(end 167.87114 -23.724108)
		(width 0.14605)
		(layer "F.Cu")
		(net "PCIE_COMP_TO_SCC_1_DN")
	)
	(arc
		(start 167.87114 -23.724108)
		(mid 168.075351 -23.808695)
		(end 168.159938 -24.012906)
		(width 0.14605)
		(layer "F.Cu")
		(net "PCIE_COMP_TO_SCC_1_DN")
	)
	(arc
		(start 167.33266 -23.939754)
		(mid 167.395821 -23.787269)
		(end 167.548306 -23.724108)
		(width 0.14605)
		(layer "F.Cu")
		(net "PCIE_COMP_TO_SCC_1_DN")
	)
	(segment
		(start 168.602152 -20.967954)
		(end 168.665144 -21.262848)
		(width 0.1397)
		(layer "In5.Cu")
		(net "PCIE_COMP_TO_SCC_1_DN")
	)
	(segment
		(start 181.064916 -13.238734)
		(end 180.926994 -13.887958)
		(width 0.1397)
		(layer "In5.Cu")
		(net "PCIE_COMP_TO_SCC_1_DN")
	)
	(segment
		(start 169.333164 -22.51964)
		(end 169.333164 -23.160736)
		(width 0.1397)
		(layer "In5.Cu")
		(net "PCIE_COMP_TO_SCC_1_DN")
	)
	(segment
		(start 181.064916 -3.749802)
		(end 181.064916 -13.238734)
		(width 0.1397)
		(layer "In5.Cu")
		(net "PCIE_COMP_TO_SCC_1_DN")
	)
	(segment
		(start 168.723564 -20.390612)
		(end 168.602152 -20.967954)
		(width 0.1397)
		(layer "In5.Cu")
		(net "PCIE_COMP_TO_SCC_1_DN")
	)
	(segment
		(start 177.50663 -15.223744)
		(end 172.478954 -18.614136)
		(width 0.1397)
		(layer "In5.Cu")
		(net "PCIE_COMP_TO_SCC_1_DN")
	)
	(segment
		(start 168.665144 -21.262848)
		(end 168.685972 -21.360892)
		(width 0.1397)
		(layer "In5.Cu")
		(net "PCIE_COMP_TO_SCC_1_DN")
	)
	(segment
		(start 179.992782 -14.741398)
		(end 177.50663 -15.223744)
		(width 0.1397)
		(layer "In5.Cu")
		(net "PCIE_COMP_TO_SCC_1_DN")
	)
	(segment
		(start 181.799992 -3.999992)
		(end 181.799992 -3.631692)
		(width 0.1397)
		(layer "In5.Cu")
		(net "PCIE_COMP_TO_SCC_1_DN")
	)
	(segment
		(start 172.478954 -18.614136)
		(end 168.894252 -20.127468)
		(width 0.1397)
		(layer "In5.Cu")
		(net "PCIE_COMP_TO_SCC_1_DN")
	)
	(segment
		(start 181.633622 -3.465322)
		(end 181.349396 -3.465322)
		(width 0.1397)
		(layer "In5.Cu")
		(net "PCIE_COMP_TO_SCC_1_DN")
	)
	(segment
		(start 168.894252 -20.127468)
		(end 168.723564 -20.390612)
		(width 0.1397)
		(layer "In5.Cu")
		(net "PCIE_COMP_TO_SCC_1_DN")
	)
	(segment
		(start 168.685972 -21.360892)
		(end 169.333164 -22.51964)
		(width 0.1397)
		(layer "In5.Cu")
		(net "PCIE_COMP_TO_SCC_1_DN")
	)
	(segment
		(start 180.669946 -14.283944)
		(end 179.992782 -14.741398)
		(width 0.1397)
		(layer "In5.Cu")
		(net "PCIE_COMP_TO_SCC_1_DN")
	)
	(segment
		(start 168.760394 -23.733506)
		(end 168.439338 -23.733506)
		(width 0.1397)
		(layer "In5.Cu")
		(net "PCIE_COMP_TO_SCC_1_DN")
	)
	(segment
		(start 180.926994 -13.887958)
		(end 180.669946 -14.283944)
		(width 0.1397)
		(layer "In5.Cu")
		(net "PCIE_COMP_TO_SCC_1_DN")
	)
	(arc
		(start 168.439338 -23.733506)
		(mid 168.241772 -23.81534)
		(end 168.159938 -24.012906)
		(width 0.1397)
		(layer "In5.Cu")
		(net "PCIE_COMP_TO_SCC_1_DN")
	)
	(arc
		(start 181.799992 -3.631692)
		(mid 181.751263 -3.514051)
		(end 181.633622 -3.465322)
		(width 0.1397)
		(layer "In5.Cu")
		(net "PCIE_COMP_TO_SCC_1_DN")
	)
	(arc
		(start 181.349396 -3.465322)
		(mid 181.148238 -3.548644)
		(end 181.064916 -3.749802)
		(width 0.1397)
		(layer "In5.Cu")
		(net "PCIE_COMP_TO_SCC_1_DN")
	)
	(arc
		(start 169.333164 -23.160736)
		(mid 169.165404 -23.565746)
		(end 168.760394 -23.733506)
		(width 0.1397)
		(layer "In5.Cu")
		(net "PCIE_COMP_TO_SCC_1_DN")
	)
	(segment
		(start 168.199816 -28.399994)
		(end 168.199816 -28.329128)
		(width 0.14605)
		(layer "F.Cu")
		(net "PCIE_COMP_TO_SCC_0_DP")
	)
	(segment
		(start 165.615874 -23.455884)
		(end 165.836346 -23.455884)
		(width 0.14605)
		(layer "F.Cu")
		(net "PCIE_COMP_TO_SCC_0_DP")
	)
	(segment
		(start 165.158674 -25.287986)
		(end 165.158674 -23.913084)
		(width 0.14605)
		(layer "F.Cu")
		(net "PCIE_COMP_TO_SCC_0_DP")
	)
	(segment
		(start 168.199816 -28.329128)
		(end 165.158674 -25.287986)
		(width 0.14605)
		(layer "F.Cu")
		(net "PCIE_COMP_TO_SCC_0_DP")
	)
	(arc
		(start 165.836346 -23.455884)
		(mid 166.040737 -23.371223)
		(end 166.125398 -23.166832)
		(width 0.14605)
		(layer "F.Cu")
		(net "PCIE_COMP_TO_SCC_0_DP")
	)
	(arc
		(start 165.158674 -23.913084)
		(mid 165.292585 -23.589795)
		(end 165.615874 -23.455884)
		(width 0.14605)
		(layer "F.Cu")
		(net "PCIE_COMP_TO_SCC_0_DP")
	)
	(segment
		(start 166.292784 -19.539458)
		(end 166.081456 -20.088098)
		(width 0.1397)
		(layer "In5.Cu")
		(net "PCIE_COMP_TO_SCC_0_DP")
	)
	(segment
		(start 173.636432 -15.464282)
		(end 168.916604 -18.64741)
		(width 0.1397)
		(layer "In5.Cu")
		(net "PCIE_COMP_TO_SCC_0_DP")
	)
	(segment
		(start 166.675562 -23.446232)
		(end 166.404798 -23.446232)
		(width 0.1397)
		(layer "In5.Cu")
		(net "PCIE_COMP_TO_SCC_0_DP")
	)
	(segment
		(start 165.938454 -20.778724)
		(end 165.955472 -20.870418)
		(width 0.1397)
		(layer "In5.Cu")
		(net "PCIE_COMP_TO_SCC_0_DP")
	)
	(segment
		(start 175.763428 -11.863832)
		(end 175.815752 -12.109704)
		(width 0.1397)
		(layer "In5.Cu")
		(net "PCIE_COMP_TO_SCC_0_DP")
	)
	(segment
		(start 166.007034 -20.281646)
		(end 165.992556 -20.319746)
		(width 0.1397)
		(layer "In5.Cu")
		(net "PCIE_COMP_TO_SCC_0_DP")
	)
	(segment
		(start 174.462694 -13.86586)
		(end 174.515018 -14.111732)
		(width 0.1397)
		(layer "In5.Cu")
		(net "PCIE_COMP_TO_SCC_0_DP")
	)
	(segment
		(start 179.999894 -3.800094)
		(end 179.999894 -4.168648)
		(width 0.1397)
		(layer "In5.Cu")
		(net "PCIE_COMP_TO_SCC_0_DP")
	)
	(segment
		(start 165.955472 -20.870418)
		(end 166.021258 -21.223986)
		(width 0.1397)
		(layer "In5.Cu")
		(net "PCIE_COMP_TO_SCC_0_DP")
	)
	(segment
		(start 179.83327 -4.335272)
		(end 179.266088 -4.335272)
		(width 0.1397)
		(layer "In5.Cu")
		(net "PCIE_COMP_TO_SCC_0_DP")
	)
	(segment
		(start 176.826164 -10.554208)
		(end 176.826164 -10.554462)
		(width 0.1397)
		(layer "In5.Cu")
		(net "PCIE_COMP_TO_SCC_0_DP")
	)
	(segment
		(start 175.991774 -11.512296)
		(end 175.763428 -11.863832)
		(width 0.1397)
		(layer "In5.Cu")
		(net "PCIE_COMP_TO_SCC_0_DP")
	)
	(segment
		(start 177.905156 -5.479034)
		(end 177.904902 -5.479034)
		(width 0.1397)
		(layer "In5.Cu")
		(net "PCIE_COMP_TO_SCC_0_DP")
	)
	(segment
		(start 179.266088 -4.335272)
		(end 178.796188 -4.435094)
		(width 0.1397)
		(layer "In5.Cu")
		(net "PCIE_COMP_TO_SCC_0_DP")
	)
	(segment
		(start 168.916604 -18.64741)
		(end 166.292784 -19.539458)
		(width 0.1397)
		(layer "In5.Cu")
		(net "PCIE_COMP_TO_SCC_0_DP")
	)
	(segment
		(start 174.515018 -14.111732)
		(end 173.636432 -15.464282)
		(width 0.1397)
		(layer "In5.Cu")
		(net "PCIE_COMP_TO_SCC_0_DP")
	)
	(segment
		(start 166.021258 -21.223986)
		(end 166.909242 -22.387814)
		(width 0.1397)
		(layer "In5.Cu")
		(net "PCIE_COMP_TO_SCC_0_DP")
	)
	(segment
		(start 165.992556 -20.319746)
		(end 165.97757 -20.358354)
		(width 0.1397)
		(layer "In5.Cu")
		(net "PCIE_COMP_TO_SCC_0_DP")
	)
	(segment
		(start 166.909242 -22.387814)
		(end 167.025574 -22.885908)
		(width 0.1397)
		(layer "In5.Cu")
		(net "PCIE_COMP_TO_SCC_0_DP")
	)
	(segment
		(start 174.937166 -13.462254)
		(end 174.69104 -13.514324)
		(width 0.1397)
		(layer "In5.Cu")
		(net "PCIE_COMP_TO_SCC_0_DP")
	)
	(segment
		(start 175.815752 -12.109704)
		(end 175.587406 -12.46124)
		(width 0.1397)
		(layer "In5.Cu")
		(net "PCIE_COMP_TO_SCC_0_DP")
	)
	(segment
		(start 178.796188 -4.435094)
		(end 178.428142 -4.674108)
		(width 0.1397)
		(layer "In5.Cu")
		(net "PCIE_COMP_TO_SCC_0_DP")
	)
	(segment
		(start 167.025574 -22.885908)
		(end 167.025574 -23.09622)
		(width 0.1397)
		(layer "In5.Cu")
		(net "PCIE_COMP_TO_SCC_0_DP")
	)
	(segment
		(start 175.113188 -12.864846)
		(end 175.165512 -13.110718)
		(width 0.1397)
		(layer "In5.Cu")
		(net "PCIE_COMP_TO_SCC_0_DP")
	)
	(segment
		(start 176.237646 -11.460226)
		(end 175.991774 -11.512296)
		(width 0.1397)
		(layer "In5.Cu")
		(net "PCIE_COMP_TO_SCC_0_DP")
	)
	(segment
		(start 176.826164 -10.554462)
		(end 176.237646 -11.460226)
		(width 0.1397)
		(layer "In5.Cu")
		(net "PCIE_COMP_TO_SCC_0_DP")
	)
	(segment
		(start 165.97757 -20.358354)
		(end 165.898322 -20.56384)
		(width 0.1397)
		(layer "In5.Cu")
		(net "PCIE_COMP_TO_SCC_0_DP")
	)
	(segment
		(start 177.904902 -5.479034)
		(end 176.826164 -10.554208)
		(width 0.1397)
		(layer "In5.Cu")
		(net "PCIE_COMP_TO_SCC_0_DP")
	)
	(segment
		(start 166.081456 -20.088098)
		(end 166.007034 -20.281646)
		(width 0.1397)
		(layer "In5.Cu")
		(net "PCIE_COMP_TO_SCC_0_DP")
	)
	(segment
		(start 174.69104 -13.514324)
		(end 174.462694 -13.86586)
		(width 0.1397)
		(layer "In5.Cu")
		(net "PCIE_COMP_TO_SCC_0_DP")
	)
	(segment
		(start 175.587406 -12.46124)
		(end 175.341534 -12.51331)
		(width 0.1397)
		(layer "In5.Cu")
		(net "PCIE_COMP_TO_SCC_0_DP")
	)
	(segment
		(start 175.165512 -13.110718)
		(end 174.937166 -13.462254)
		(width 0.1397)
		(layer "In5.Cu")
		(net "PCIE_COMP_TO_SCC_0_DP")
	)
	(segment
		(start 178.428142 -4.674108)
		(end 177.905156 -5.479034)
		(width 0.1397)
		(layer "In5.Cu")
		(net "PCIE_COMP_TO_SCC_0_DP")
	)
	(segment
		(start 165.898322 -20.56384)
		(end 165.938454 -20.778724)
		(width 0.1397)
		(layer "In5.Cu")
		(net "PCIE_COMP_TO_SCC_0_DP")
	)
	(segment
		(start 175.341534 -12.51331)
		(end 175.113188 -12.864846)
		(width 0.1397)
		(layer "In5.Cu")
		(net "PCIE_COMP_TO_SCC_0_DP")
	)
	(arc
		(start 166.404798 -23.446232)
		(mid 166.207232 -23.364398)
		(end 166.125398 -23.166832)
		(width 0.1397)
		(layer "In5.Cu")
		(net "PCIE_COMP_TO_SCC_0_DP")
	)
	(arc
		(start 179.999894 -4.168648)
		(mid 179.951091 -4.286469)
		(end 179.83327 -4.335272)
		(width 0.1397)
		(layer "In5.Cu")
		(net "PCIE_COMP_TO_SCC_0_DP")
	)
	(arc
		(start 167.025574 -23.09622)
		(mid 166.923058 -23.343716)
		(end 166.675562 -23.446232)
		(width 0.1397)
		(layer "In5.Cu")
		(net "PCIE_COMP_TO_SCC_0_DP")
	)
	(segment
		(start 165.469824 -25.158954)
		(end 165.469824 -23.913084)
		(width 0.14605)
		(layer "F.Cu")
		(net "PCIE_COMP_TO_SCC_0_DN")
	)
	(segment
		(start 168.5798 -28.580588)
		(end 168.5798 -28.26893)
		(width 0.14605)
		(layer "F.Cu")
		(net "PCIE_COMP_TO_SCC_0_DN")
	)
	(segment
		(start 168.199816 -29.19984)
		(end 168.5798 -28.580588)
		(width 0.14605)
		(layer "F.Cu")
		(net "PCIE_COMP_TO_SCC_0_DN")
	)
	(segment
		(start 168.5798 -28.26893)
		(end 165.469824 -25.158954)
		(width 0.14605)
		(layer "F.Cu")
		(net "PCIE_COMP_TO_SCC_0_DN")
	)
	(segment
		(start 165.615874 -23.767034)
		(end 165.8366 -23.767034)
		(width 0.14605)
		(layer "F.Cu")
		(net "PCIE_COMP_TO_SCC_0_DN")
	)
	(arc
		(start 165.469824 -23.913084)
		(mid 165.512601 -23.809811)
		(end 165.615874 -23.767034)
		(width 0.14605)
		(layer "F.Cu")
		(net "PCIE_COMP_TO_SCC_0_DN")
	)
	(arc
		(start 165.8366 -23.767034)
		(mid 166.040811 -23.851621)
		(end 166.125398 -24.055832)
		(width 0.14605)
		(layer "F.Cu")
		(net "PCIE_COMP_TO_SCC_0_DN")
	)
	(segment
		(start 166.240206 -20.595336)
		(end 166.331646 -21.086064)
		(width 0.1397)
		(layer "In5.Cu")
		(net "PCIE_COMP_TO_SCC_0_DN")
	)
	(segment
		(start 177.136552 -10.682986)
		(end 173.87697 -15.700756)
		(width 0.1397)
		(layer "In5.Cu")
		(net "PCIE_COMP_TO_SCC_0_DN")
	)
	(segment
		(start 178.924712 -4.745482)
		(end 178.666902 -4.912868)
		(width 0.1397)
		(layer "In5.Cu")
		(net "PCIE_COMP_TO_SCC_0_DN")
	)
	(segment
		(start 169.064686 -18.94586)
		(end 166.545514 -19.802602)
		(width 0.1397)
		(layer "In5.Cu")
		(net "PCIE_COMP_TO_SCC_0_DN")
	)
	(segment
		(start 166.329868 -20.362164)
		(end 166.312342 -20.408646)
		(width 0.1397)
		(layer "In5.Cu")
		(net "PCIE_COMP_TO_SCC_0_DN")
	)
	(segment
		(start 178.666902 -4.912868)
		(end 178.441604 -5.260086)
		(width 0.1397)
		(layer "In5.Cu")
		(net "PCIE_COMP_TO_SCC_0_DN")
	)
	(segment
		(start 166.256462 -20.553426)
		(end 166.240206 -20.595336)
		(width 0.1397)
		(layer "In5.Cu")
		(net "PCIE_COMP_TO_SCC_0_DN")
	)
	(segment
		(start 179.833524 -4.665472)
		(end 179.300886 -4.665472)
		(width 0.1397)
		(layer "In5.Cu")
		(net "PCIE_COMP_TO_SCC_0_DN")
	)
	(segment
		(start 166.773098 -21.66493)
		(end 167.214804 -22.243796)
		(width 0.1397)
		(layer "In5.Cu")
		(net "PCIE_COMP_TO_SCC_0_DN")
	)
	(segment
		(start 173.87697 -15.700756)
		(end 169.064686 -18.94586)
		(width 0.1397)
		(layer "In5.Cu")
		(net "PCIE_COMP_TO_SCC_0_DN")
	)
	(segment
		(start 178.215544 -5.607558)
		(end 177.136552 -10.682986)
		(width 0.1397)
		(layer "In5.Cu")
		(net "PCIE_COMP_TO_SCC_0_DN")
	)
	(segment
		(start 167.214804 -22.243796)
		(end 167.355774 -22.847808)
		(width 0.1397)
		(layer "In5.Cu")
		(net "PCIE_COMP_TO_SCC_0_DN")
	)
	(segment
		(start 166.675562 -23.776432)
		(end 166.404798 -23.776432)
		(width 0.1397)
		(layer "In5.Cu")
		(net "PCIE_COMP_TO_SCC_0_DN")
	)
	(segment
		(start 166.545514 -19.802602)
		(end 166.389812 -20.206716)
		(width 0.1397)
		(layer "In5.Cu")
		(net "PCIE_COMP_TO_SCC_0_DN")
	)
	(segment
		(start 167.355774 -22.847808)
		(end 167.355774 -23.09622)
		(width 0.1397)
		(layer "In5.Cu")
		(net "PCIE_COMP_TO_SCC_0_DN")
	)
	(segment
		(start 178.441604 -5.260086)
		(end 178.215544 -5.607812)
		(width 0.1397)
		(layer "In5.Cu")
		(net "PCIE_COMP_TO_SCC_0_DN")
	)
	(segment
		(start 166.331646 -21.086064)
		(end 166.773098 -21.66493)
		(width 0.1397)
		(layer "In5.Cu")
		(net "PCIE_COMP_TO_SCC_0_DN")
	)
	(segment
		(start 166.304468 -20.42922)
		(end 166.256462 -20.553426)
		(width 0.1397)
		(layer "In5.Cu")
		(net "PCIE_COMP_TO_SCC_0_DN")
	)
	(segment
		(start 179.999894 -5.200142)
		(end 179.999894 -4.831842)
		(width 0.1397)
		(layer "In5.Cu")
		(net "PCIE_COMP_TO_SCC_0_DN")
	)
	(segment
		(start 178.215544 -5.607812)
		(end 178.215544 -5.607558)
		(width 0.1397)
		(layer "In5.Cu")
		(net "PCIE_COMP_TO_SCC_0_DN")
	)
	(segment
		(start 166.308786 -20.418044)
		(end 166.304468 -20.42922)
		(width 0.1397)
		(layer "In5.Cu")
		(net "PCIE_COMP_TO_SCC_0_DN")
	)
	(segment
		(start 179.300886 -4.665472)
		(end 178.924712 -4.745482)
		(width 0.1397)
		(layer "In5.Cu")
		(net "PCIE_COMP_TO_SCC_0_DN")
	)
	(segment
		(start 166.389812 -20.206716)
		(end 166.329868 -20.362164)
		(width 0.1397)
		(layer "In5.Cu")
		(net "PCIE_COMP_TO_SCC_0_DN")
	)
	(segment
		(start 166.312342 -20.408646)
		(end 166.308786 -20.418044)
		(width 0.1397)
		(layer "In5.Cu")
		(net "PCIE_COMP_TO_SCC_0_DN")
	)
	(arc
		(start 179.999894 -4.831842)
		(mid 179.951165 -4.714201)
		(end 179.833524 -4.665472)
		(width 0.1397)
		(layer "In5.Cu")
		(net "PCIE_COMP_TO_SCC_0_DN")
	)
	(arc
		(start 167.355774 -23.09622)
		(mid 167.156545 -23.577203)
		(end 166.675562 -23.776432)
		(width 0.1397)
		(layer "In5.Cu")
		(net "PCIE_COMP_TO_SCC_0_DN")
	)
	(arc
		(start 166.404798 -23.776432)
		(mid 166.207232 -23.858266)
		(end 166.125398 -24.055832)
		(width 0.1397)
		(layer "In5.Cu")
		(net "PCIE_COMP_TO_SCC_0_DN")
	)
	(segment
		(start 166.044372 -27.983434)
		(end 166.044372 -28.155646)
		(width 0.14605)
		(layer "F.Cu")
		(net "PCIE_CLK_R_P")
	)
	(segment
		(start 162.418268 -23.935944)
		(end 162.77082 -24.288496)
		(width 0.14605)
		(layer "F.Cu")
		(net "PCIE_CLK_R_P")
	)
	(segment
		(start 162.405568 -23.427944)
		(end 162.405568 -22.907244)
		(width 0.14605)
		(layer "F.Cu")
		(net "PCIE_CLK_R_P")
	)
	(segment
		(start 162.77082 -24.288496)
		(end 162.77082 -24.548846)
		(width 0.14605)
		(layer "F.Cu")
		(net "PCIE_CLK_R_P")
	)
	(segment
		(start 162.77082 -24.548846)
		(end 165.93058 -27.708606)
		(width 0.14605)
		(layer "F.Cu")
		(net "PCIE_CLK_R_P")
	)
	(segment
		(start 162.418268 -23.440644)
		(end 162.405568 -23.427944)
		(width 0.14605)
		(layer "F.Cu")
		(net "PCIE_CLK_R_P")
	)
	(segment
		(start 162.418268 -23.935944)
		(end 162.418268 -23.440644)
		(width 0.14605)
		(layer "F.Cu")
		(net "PCIE_CLK_R_P")
	)
	(arc
		(start 165.93058 -27.708606)
		(mid 166.014832 -27.834698)
		(end 166.044372 -27.983434)
		(width 0.14605)
		(layer "F.Cu")
		(net "PCIE_CLK_R_P")
	)
	(arc
		(start 166.044372 -28.155646)
		(mid 165.972804 -28.328426)
		(end 165.800024 -28.399994)
		(width 0.14605)
		(layer "F.Cu")
		(net "PCIE_CLK_R_P")
	)
	(segment
		(start 163.434268 -23.935944)
		(end 163.08197 -24.288242)
		(width 0.14605)
		(layer "F.Cu")
		(net "PCIE_CLK_R_N")
	)
	(segment
		(start 163.434268 -23.430992)
		(end 163.446968 -23.418292)
		(width 0.14605)
		(layer "F.Cu")
		(net "PCIE_CLK_R_N")
	)
	(segment
		(start 163.08197 -24.419814)
		(end 166.150544 -27.488388)
		(width 0.14605)
		(layer "F.Cu")
		(net "PCIE_CLK_R_N")
	)
	(segment
		(start 163.446968 -23.418292)
		(end 163.446968 -22.907244)
		(width 0.14605)
		(layer "F.Cu")
		(net "PCIE_CLK_R_N")
	)
	(segment
		(start 166.355522 -27.983688)
		(end 166.355522 -28.155646)
		(width 0.14605)
		(layer "F.Cu")
		(net "PCIE_CLK_R_N")
	)
	(segment
		(start 163.08197 -24.288242)
		(end 163.08197 -24.419814)
		(width 0.14605)
		(layer "F.Cu")
		(net "PCIE_CLK_R_N")
	)
	(segment
		(start 163.434268 -23.935944)
		(end 163.434268 -23.430992)
		(width 0.14605)
		(layer "F.Cu")
		(net "PCIE_CLK_R_N")
	)
	(arc
		(start 166.150544 -27.488388)
		(mid 166.302326 -27.715635)
		(end 166.355522 -27.983688)
		(width 0.14605)
		(layer "F.Cu")
		(net "PCIE_CLK_R_N")
	)
	(arc
		(start 166.355522 -28.155646)
		(mid 166.42709 -28.328426)
		(end 166.59987 -28.399994)
		(width 0.14605)
		(layer "F.Cu")
		(net "PCIE_CLK_R_N")
	)
	(segment
		(start 66.8655 -106.7562)
		(end 66.8655 -107.546394)
		(width 0.254)
		(layer "F.Cu")
		(net "P3V3_VREG")
	)
	(segment
		(start 64.628014 -94.444058)
		(end 64.628014 -93.781372)
		(width 0.254)
		(layer "F.Cu")
		(net "P3V3_VREG")
	)
	(segment
		(start 64.475106 -98.050858)
		(end 64.475106 -96.362774)
		(width 0.254)
		(layer "F.Cu")
		(net "P3V3_VREG")
	)
	(segment
		(start 64.628014 -93.781372)
		(end 65.530984 -92.878402)
		(width 0.254)
		(layer "F.Cu")
		(net "P3V3_VREG")
	)
	(segment
		(start 64.69888 -95.57258)
		(end 64.628014 -95.501714)
		(width 0.254)
		(layer "F.Cu")
		(net "P3V3_VREG")
	)
	(segment
		(start 64.69888 -96.139)
		(end 64.69888 -95.57258)
		(width 0.254)
		(layer "F.Cu")
		(net "P3V3_VREG")
	)
	(segment
		(start 64.628014 -95.501714)
		(end 64.628014 -94.444058)
		(width 0.254)
		(layer "F.Cu")
		(net "P3V3_VREG")
	)
	(segment
		(start 64.475106 -96.362774)
		(end 64.69888 -96.139)
		(width 0.254)
		(layer "F.Cu")
		(net "P3V3_VREG")
	)
	(via
		(at 65.530984 -92.878402)
		(size 0.508)
		(drill 0.254)
		(layers "F.Cu" "B.Cu")
		(net "P3V3_VREG")
	)
	(via
		(at 66.8655 -107.546394)
		(size 0.508)
		(drill 0.254)
		(layers "F.Cu" "B.Cu")
		(net "P3V3_VREG")
	)
	(via
		(at 67.5767 -97.801938)
		(size 0.6096)
		(drill 0.3048)
		(layers "F.Cu" "B.Cu")
		(net "P3V3_VREG")
	)
	(segment
		(start 66.23812 -93.585538)
		(end 67.119246 -93.585538)
		(width 0.254)
		(layer "B.Cu")
		(net "P3V3_VREG")
	)
	(segment
		(start 66.8655 -107.546394)
		(end 67.431666 -107.546394)
		(width 0.254)
		(layer "B.Cu")
		(net "P3V3_VREG")
	)
	(segment
		(start 67.5767 -94.042992)
		(end 67.5767 -97.801938)
		(width 0.254)
		(layer "B.Cu")
		(net "P3V3_VREG")
	)
	(segment
		(start 68.453 -106.52506)
		(end 68.453 -98.8822)
		(width 0.254)
		(layer "B.Cu")
		(net "P3V3_VREG")
	)
	(segment
		(start 68.453 -98.8822)
		(end 67.5767 -98.0059)
		(width 0.254)
		(layer "B.Cu")
		(net "P3V3_VREG")
	)
	(segment
		(start 65.530984 -92.878402)
		(end 66.23812 -93.585538)
		(width 0.254)
		(layer "B.Cu")
		(net "P3V3_VREG")
	)
	(segment
		(start 67.431666 -107.546394)
		(end 68.453 -106.52506)
		(width 0.254)
		(layer "B.Cu")
		(net "P3V3_VREG")
	)
	(segment
		(start 67.5767 -98.0059)
		(end 67.5767 -97.801938)
		(width 0.254)
		(layer "B.Cu")
		(net "P3V3_VREG")
	)
	(segment
		(start 67.119246 -93.585538)
		(end 67.5767 -94.042992)
		(width 0.254)
		(layer "B.Cu")
		(net "P3V3_VREG")
	)
	(segment
		(start 67.884548 -96.0628)
		(end 67.592194 -96.355154)
		(width 0.254)
		(layer "F.Cu")
		(net "P3V3_TRIP")
	)
	(segment
		(start 66.421 -97.028)
		(end 66.919348 -97.028)
		(width 0.254)
		(layer "F.Cu")
		(net "P3V3_TRIP")
	)
	(segment
		(start 65.974976 -97.474024)
		(end 66.421 -97.028)
		(width 0.254)
		(layer "F.Cu")
		(net "P3V3_TRIP")
	)
	(segment
		(start 68.736972 -96.0628)
		(end 67.884548 -96.0628)
		(width 0.254)
		(layer "F.Cu")
		(net "P3V3_TRIP")
	)
	(segment
		(start 65.974976 -98.050858)
		(end 65.974976 -97.474024)
		(width 0.254)
		(layer "F.Cu")
		(net "P3V3_TRIP")
	)
	(segment
		(start 66.919348 -97.028)
		(end 67.592194 -96.355154)
		(width 0.254)
		(layer "F.Cu")
		(net "P3V3_TRIP")
	)
	(via
		(at 67.592194 -96.355154)
		(size 0.6604)
		(drill 0.3302)
		(layers "F.Cu" "B.Cu")
		(net "P3V3_TRIP")
	)
	(segment
		(start 64.897 -105.6005)
		(end 64.897 -105.283)
		(width 0.254)
		(layer "F.Cu")
		(net "P3V3_ROVP")
	)
	(segment
		(start 64.897 -105.283)
		(end 64.475106 -104.861106)
		(width 0.254)
		(layer "F.Cu")
		(net "P3V3_ROVP")
	)
	(segment
		(start 64.475106 -104.861106)
		(end 64.475106 -102.949502)
		(width 0.254)
		(layer "F.Cu")
		(net "P3V3_ROVP")
	)
	(segment
		(start 67.852036 -97.0788)
		(end 66.879978 -98.050858)
		(width 0.254)
		(layer "F.Cu")
		(net "P3V3_RF")
	)
	(segment
		(start 65.517014 -94.444058)
		(end 65.517014 -93.908372)
		(width 0.254)
		(layer "F.Cu")
		(net "P3V3_RF")
	)
	(segment
		(start 65.517014 -93.908372)
		(end 66.546984 -92.878402)
		(width 0.254)
		(layer "F.Cu")
		(net "P3V3_RF")
	)
	(segment
		(start 66.879978 -98.050858)
		(end 66.475102 -98.050858)
		(width 0.254)
		(layer "F.Cu")
		(net "P3V3_RF")
	)
	(segment
		(start 68.736972 -98.010218)
		(end 68.736972 -97.0788)
		(width 0.254)
		(layer "F.Cu")
		(net "P3V3_RF")
	)
	(segment
		(start 68.736972 -97.0788)
		(end 67.852036 -97.0788)
		(width 0.254)
		(layer "F.Cu")
		(net "P3V3_RF")
	)
	(via
		(at 66.546984 -92.878402)
		(size 0.508)
		(drill 0.254)
		(layers "F.Cu" "B.Cu")
		(net "P3V3_RF")
	)
	(via
		(at 68.514468 -96.723454)
		(size 0.6096)
		(drill 0.3048)
		(layers "F.Cu" "B.Cu")
		(net "P3V3_RF")
	)
	(via
		(at 68.736972 -98.010218)
		(size 0.508)
		(drill 0.254)
		(layers "F.Cu" "B.Cu")
		(net "P3V3_RF")
	)
	(segment
		(start 66.546984 -92.878402)
		(end 67.202558 -92.878402)
		(width 0.254)
		(layer "B.Cu")
		(net "P3V3_RF")
	)
	(segment
		(start 67.202558 -92.878402)
		(end 68.1863 -93.862144)
		(width 0.254)
		(layer "B.Cu")
		(net "P3V3_RF")
	)
	(segment
		(start 68.1863 -93.862144)
		(end 68.1863 -96.395286)
		(width 0.254)
		(layer "B.Cu")
		(net "P3V3_RF")
	)
	(segment
		(start 68.736972 -98.010218)
		(end 68.736972 -96.945958)
		(width 0.254)
		(layer "B.Cu")
		(net "P3V3_RF")
	)
	(segment
		(start 68.1863 -96.395286)
		(end 68.514468 -96.723454)
		(width 0.254)
		(layer "B.Cu")
		(net "P3V3_RF")
	)
	(segment
		(start 68.736972 -96.945958)
		(end 68.514468 -96.723454)
		(width 0.254)
		(layer "B.Cu")
		(net "P3V3_RF")
	)
	(segment
		(start 66.497962 -96.393)
		(end 65.475104 -97.415858)
		(width 0.254)
		(layer "F.Cu")
		(net "P3V3_MODE")
	)
	(segment
		(start 68.574158 -94.84995)
		(end 69.778626 -94.84995)
		(width 0.254)
		(layer "F.Cu")
		(net "P3V3_MODE")
	)
	(segment
		(start 67.3735 -95.0468)
		(end 67.3735 -95.65005)
		(width 0.254)
		(layer "F.Cu")
		(net "P3V3_MODE")
	)
	(segment
		(start 66.63055 -96.393)
		(end 66.497962 -96.393)
		(width 0.254)
		(layer "F.Cu")
		(net "P3V3_MODE")
	)
	(segment
		(start 65.475104 -97.415858)
		(end 65.475104 -98.050858)
		(width 0.254)
		(layer "F.Cu")
		(net "P3V3_MODE")
	)
	(segment
		(start 67.3735 -95.65005)
		(end 66.63055 -96.393)
		(width 0.254)
		(layer "F.Cu")
		(net "P3V3_MODE")
	)
	(segment
		(start 67.57035 -94.84995)
		(end 67.3735 -95.0468)
		(width 0.254)
		(layer "F.Cu")
		(net "P3V3_MODE")
	)
	(segment
		(start 68.574158 -94.84995)
		(end 67.57035 -94.84995)
		(width 0.254)
		(layer "F.Cu")
		(net "P3V3_MODE")
	)
	(via
		(at 68.574158 -94.84995)
		(size 0.6604)
		(drill 0.3302)
		(layers "F.Cu" "B.Cu")
		(net "P3V3_MODE")
	)
	(segment
		(start 60.15228 -106.01833)
		(end 60.15228 -108.25988)
		(width 0.254)
		(layer "F.Cu")
		(net "P3V3_LL")
	)
	(segment
		(start 64.572896 -108.331)
		(end 65.024 -108.331)
		(width 0.254)
		(layer "F.Cu")
		(net "P3V3_LL")
	)
	(segment
		(start 60.15228 -108.25988)
		(end 60.54598 -108.65358)
		(width 0.254)
		(layer "F.Cu")
		(net "P3V3_LL")
	)
	(segment
		(start 64.250316 -108.65358)
		(end 64.572896 -108.331)
		(width 0.254)
		(layer "F.Cu")
		(net "P3V3_LL")
	)
	(segment
		(start 60.54598 -108.65358)
		(end 64.250316 -108.65358)
		(width 0.254)
		(layer "F.Cu")
		(net "P3V3_LL")
	)
	(via
		(at 57.423304 -103.62692)
		(size 0.6096)
		(drill 0.3048)
		(layers "F.Cu" "B.Cu")
		(net "P3V3_LL")
	)
	(via
		(at 60.344304 -106.52252)
		(size 0.6096)
		(drill 0.3048)
		(layers "F.Cu" "B.Cu")
		(net "P3V3_LL")
	)
	(via
		(at 58.4962 -103.5558)
		(size 0.6604)
		(drill 0.3302)
		(layers "F.Cu" "B.Cu")
		(net "P3V3_LL")
	)
	(via
		(at 57.499504 -106.49712)
		(size 0.6096)
		(drill 0.3048)
		(layers "F.Cu" "B.Cu")
		(net "P3V3_LL")
	)
	(via
		(at 59.7662 -102.9716)
		(size 0.6604)
		(drill 0.3302)
		(layers "F.Cu" "B.Cu")
		(net "P3V3_LL")
	)
	(via
		(at 62.6618 -106.3244)
		(size 0.7112)
		(drill 0.4064)
		(layers "F.Cu" "B.Cu")
		(net "P3V3_LL")
	)
	(via
		(at 60.268104 -103.65232)
		(size 0.6096)
		(drill 0.3048)
		(layers "F.Cu" "B.Cu")
		(net "P3V3_LL")
	)
	(via
		(at 63.6016 -103.5812)
		(size 0.6096)
		(drill 0.3048)
		(layers "F.Cu" "B.Cu")
		(net "P3V3_LL")
	)
	(segment
		(start 158.69158 -115.62842)
		(end 157.52318 -115.62842)
		(width 0.254)
		(layer "F.Cu")
		(net "P1V5_E_VREG")
	)
	(segment
		(start 157.52318 -115.62842)
		(end 156.802074 -116.349526)
		(width 0.254)
		(layer "F.Cu")
		(net "P1V5_E_VREG")
	)
	(segment
		(start 158.69158 -115.62842)
		(end 159.51708 -115.62842)
		(width 0.254)
		(layer "F.Cu")
		(net "P1V5_E_VREG")
	)
	(segment
		(start 159.51708 -115.62842)
		(end 159.85998 -115.97132)
		(width 0.254)
		(layer "F.Cu")
		(net "P1V5_E_VREG")
	)
	(segment
		(start 156.802074 -116.349526)
		(end 155.966922 -116.349526)
		(width 0.254)
		(layer "F.Cu")
		(net "P1V5_E_VREG")
	)
	(segment
		(start 156.838396 -117.849396)
		(end 157.861 -118.872)
		(width 0.254)
		(layer "F.Cu")
		(net "P1V5_E_TRIP")
	)
	(segment
		(start 155.966922 -117.849396)
		(end 156.838396 -117.849396)
		(width 0.254)
		(layer "F.Cu")
		(net "P1V5_E_TRIP")
	)
	(segment
		(start 157.861 -118.872)
		(end 157.861 -120.0785)
		(width 0.254)
		(layer "F.Cu")
		(net "P1V5_E_TRIP")
	)
	(via
		(at 157.861 -118.872)
		(size 0.6604)
		(drill 0.3302)
		(layers "F.Cu" "B.Cu")
		(net "P1V5_E_TRIP")
	)
	(segment
		(start 148.624544 -116.9162)
		(end 149.191218 -116.349526)
		(width 0.254)
		(layer "F.Cu")
		(net "P1V5_E_ROVP")
	)
	(segment
		(start 149.191218 -116.349526)
		(end 151.068278 -116.349526)
		(width 0.254)
		(layer "F.Cu")
		(net "P1V5_E_ROVP")
	)
	(segment
		(start 148.4503 -116.9162)
		(end 148.624544 -116.9162)
		(width 0.254)
		(layer "F.Cu")
		(net "P1V5_E_ROVP")
	)
	(segment
		(start 156.718 -120.0785)
		(end 156.718 -119.0498)
		(width 0.254)
		(layer "F.Cu")
		(net "P1V5_E_RF")
	)
	(segment
		(start 156.449522 -118.349522)
		(end 155.966922 -118.349522)
		(width 0.254)
		(layer "F.Cu")
		(net "P1V5_E_RF")
	)
	(segment
		(start 156.718 -119.0498)
		(end 156.718 -118.618)
		(width 0.254)
		(layer "F.Cu")
		(net "P1V5_E_RF")
	)
	(segment
		(start 156.718 -118.618)
		(end 156.449522 -118.349522)
		(width 0.254)
		(layer "F.Cu")
		(net "P1V5_E_RF")
	)
	(segment
		(start 160.953704 -116.86032)
		(end 159.85998 -116.86032)
		(width 0.254)
		(layer "F.Cu")
		(net "P1V5_E_RF")
	)
	(via
		(at 156.718 -119.0498)
		(size 0.508)
		(drill 0.254)
		(layers "F.Cu" "B.Cu")
		(net "P1V5_E_RF")
	)
	(via
		(at 157.812232 -119.0498)
		(size 0.6096)
		(drill 0.3048)
		(layers "F.Cu" "B.Cu")
		(net "P1V5_E_RF")
	)
	(via
		(at 160.953704 -116.86032)
		(size 0.508)
		(drill 0.254)
		(layers "F.Cu" "B.Cu")
		(net "P1V5_E_RF")
	)
	(segment
		(start 160.953704 -118.306596)
		(end 160.2105 -119.0498)
		(width 0.254)
		(layer "B.Cu")
		(net "P1V5_E_RF")
	)
	(segment
		(start 160.953704 -116.86032)
		(end 160.953704 -118.306596)
		(width 0.254)
		(layer "B.Cu")
		(net "P1V5_E_RF")
	)
	(segment
		(start 156.718 -119.0498)
		(end 157.812232 -119.0498)
		(width 0.254)
		(layer "B.Cu")
		(net "P1V5_E_RF")
	)
	(segment
		(start 160.2105 -119.0498)
		(end 157.812232 -119.0498)
		(width 0.254)
		(layer "B.Cu")
		(net "P1V5_E_RF")
	)
	(via
		(at 146.65706 -115.10518)
		(size 0.6096)
		(drill 0.3048)
		(layers "F.Cu" "B.Cu")
		(net "P1V5_E_RC")
	)
	(segment
		(start 147.02536 -114.173)
		(end 146.65706 -114.5413)
		(width 0.508)
		(layer "B.Cu")
		(net "P1V5_E_RC")
	)
	(segment
		(start 146.65706 -115.10518)
		(end 146.65706 -115.90528)
		(width 0.508)
		(layer "B.Cu")
		(net "P1V5_E_RC")
	)
	(segment
		(start 147.33778 -116.586)
		(end 147.701 -116.586)
		(width 0.508)
		(layer "B.Cu")
		(net "P1V5_E_RC")
	)
	(segment
		(start 147.7645 -114.173)
		(end 147.02536 -114.173)
		(width 0.508)
		(layer "B.Cu")
		(net "P1V5_E_RC")
	)
	(segment
		(start 146.65706 -114.5413)
		(end 146.65706 -115.10518)
		(width 0.508)
		(layer "B.Cu")
		(net "P1V5_E_RC")
	)
	(segment
		(start 146.65706 -115.90528)
		(end 147.33778 -116.586)
		(width 0.508)
		(layer "B.Cu")
		(net "P1V5_E_RC")
	)
	(segment
		(start 136.906 -115.062)
		(end 136.906 -118.872)
		(width 0.381)
		(layer "F.Cu")
		(net "P1V5_E_OUT")
	)
	(segment
		(start 136.906 -118.872)
		(end 140.0937 -122.0597)
		(width 0.381)
		(layer "F.Cu")
		(net "P1V5_E_OUT")
	)
	(segment
		(start 144.8054 -115.95481)
		(end 144.54378 -116.21643)
		(width 0.254)
		(layer "F.Cu")
		(net "P1V5_E_OUT")
	)
	(segment
		(start 144.8054 -112.4204)
		(end 144.8054 -115.95481)
		(width 0.254)
		(layer "F.Cu")
		(net "P1V5_E_OUT")
	)
	(segment
		(start 142.4178 -124.3838)
		(end 140.0937 -122.0597)
		(width 0.381)
		(layer "F.Cu")
		(net "P1V5_E_OUT")
	)
	(segment
		(start 144.54378 -116.21643)
		(end 144.54378 -116.89842)
		(width 0.254)
		(layer "F.Cu")
		(net "P1V5_E_OUT")
	)
	(segment
		(start 144.533874 -112.148874)
		(end 144.8054 -112.4204)
		(width 0.254)
		(layer "F.Cu")
		(net "P1V5_E_OUT")
	)
	(segment
		(start 144.8562 -124.3838)
		(end 142.4178 -124.3838)
		(width 0.381)
		(layer "F.Cu")
		(net "P1V5_E_OUT")
	)
	(segment
		(start 142.370302 -112.148874)
		(end 144.533874 -112.148874)
		(width 0.254)
		(layer "F.Cu")
		(net "P1V5_E_OUT")
	)
	(via
		(at 138.6586 -111.2012)
		(size 0.7112)
		(drill 0.4064)
		(layers "F.Cu" "B.Cu")
		(net "P1V5_E_OUT")
	)
	(via
		(at 140.0937 -122.0597)
		(size 0.6604)
		(drill 0.3302)
		(layers "F.Cu" "B.Cu")
		(net "P1V5_E_OUT")
	)
	(via
		(at 139.2936 -107.5944)
		(size 0.6604)
		(drill 0.3302)
		(layers "F.Cu" "B.Cu")
		(net "P1V5_E_OUT")
	)
	(via
		(at 143.810228 -107.5182)
		(size 0.6604)
		(drill 0.3302)
		(layers "F.Cu" "B.Cu")
		(net "P1V5_E_OUT")
	)
	(via
		(at 137.1092 -111.2266)
		(size 0.7112)
		(drill 0.4064)
		(layers "F.Cu" "B.Cu")
		(net "P1V5_E_OUT")
	)
	(via
		(at 140.0556 -111.2012)
		(size 0.7112)
		(drill 0.4064)
		(layers "F.Cu" "B.Cu")
		(net "P1V5_E_OUT")
	)
	(segment
		(start 159.08528 -118.98122)
		(end 157.512258 -117.408198)
		(width 0.254)
		(layer "F.Cu")
		(net "P1V5_E_MODE")
	)
	(segment
		(start 157.512258 -117.408198)
		(end 156.994352 -117.408198)
		(width 0.254)
		(layer "F.Cu")
		(net "P1V5_E_MODE")
	)
	(segment
		(start 156.935678 -117.349524)
		(end 155.966922 -117.349524)
		(width 0.254)
		(layer "F.Cu")
		(net "P1V5_E_MODE")
	)
	(segment
		(start 156.994352 -117.408198)
		(end 156.935678 -117.349524)
		(width 0.254)
		(layer "F.Cu")
		(net "P1V5_E_MODE")
	)
	(segment
		(start 159.860742 -121.369074)
		(end 159.860742 -120.59539)
		(width 0.254)
		(layer "F.Cu")
		(net "P1V5_E_MODE")
	)
	(segment
		(start 159.440372 -120.17502)
		(end 159.08528 -119.819928)
		(width 0.254)
		(layer "F.Cu")
		(net "P1V5_E_MODE")
	)
	(segment
		(start 159.08528 -119.819928)
		(end 159.08528 -118.98122)
		(width 0.254)
		(layer "F.Cu")
		(net "P1V5_E_MODE")
	)
	(segment
		(start 159.860742 -120.59539)
		(end 159.440372 -120.17502)
		(width 0.254)
		(layer "F.Cu")
		(net "P1V5_E_MODE")
	)
	(via
		(at 159.440372 -120.17502)
		(size 0.6604)
		(drill 0.3302)
		(layers "F.Cu" "B.Cu")
		(net "P1V5_E_MODE")
	)
	(segment
		(start 148.7932 -115.8494)
		(end 151.068278 -115.8494)
		(width 0.254)
		(layer "F.Cu")
		(net "P1V5_E_LL")
	)
	(segment
		(start 145.3642 -115.968272)
		(end 145.68678 -116.290852)
		(width 0.254)
		(layer "F.Cu")
		(net "P1V5_E_LL")
	)
	(segment
		(start 147.929346 -112.148874)
		(end 145.635726 -112.148874)
		(width 0.254)
		(layer "F.Cu")
		(net "P1V5_E_LL")
	)
	(segment
		(start 145.3642 -112.4204)
		(end 145.3642 -115.968272)
		(width 0.254)
		(layer "F.Cu")
		(net "P1V5_E_LL")
	)
	(segment
		(start 145.68678 -116.290852)
		(end 145.68678 -116.89842)
		(width 0.254)
		(layer "F.Cu")
		(net "P1V5_E_LL")
	)
	(segment
		(start 145.635726 -112.148874)
		(end 145.3642 -112.4204)
		(width 0.254)
		(layer "F.Cu")
		(net "P1V5_E_LL")
	)
	(segment
		(start 148.69668 -115.94592)
		(end 148.7932 -115.8494)
		(width 0.254)
		(layer "F.Cu")
		(net "P1V5_E_LL")
	)
	(via
		(at 148.69668 -115.94592)
		(size 0.508)
		(drill 0.254)
		(layers "F.Cu" "B.Cu")
		(net "P1V5_E_LL")
	)
	(via
		(at 151.257 -111.6076)
		(size 0.6604)
		(drill 0.3302)
		(layers "F.Cu" "B.Cu")
		(net "P1V5_E_LL")
	)
	(segment
		(start 148.69668 -115.94592)
		(end 148.6535 -115.90274)
		(width 0.508)
		(layer "B.Cu")
		(net "P1V5_E_LL")
	)
	(segment
		(start 148.6535 -115.90274)
		(end 148.6535 -114.173)
		(width 0.508)
		(layer "B.Cu")
		(net "P1V5_E_LL")
	)
	(segment
		(start 11.4173 -67.5894)
		(end 11.4173 -66.5226)
		(width 0.508)
		(layer "F.Cu")
		(net "P12V_MAIN")
	)
	(segment
		(start 11.4173 -64.5287)
		(end 11.4173 -66.5226)
		(width 0.508)
		(layer "F.Cu")
		(net "P12V_MAIN")
	)
	(segment
		(start 10.23366 -60.912756)
		(end 10.23366 -63.34506)
		(width 0.508)
		(layer "F.Cu")
		(net "P12V_MAIN")
	)
	(segment
		(start 16.2814 -45.339)
		(end 16.256 -45.3136)
		(width 0.508)
		(layer "F.Cu")
		(net "P12V_MAIN")
	)
	(segment
		(start 10.23366 -63.34506)
		(end 11.4173 -64.5287)
		(width 0.508)
		(layer "F.Cu")
		(net "P12V_MAIN")
	)
	(segment
		(start 22.8092 -45.212)
		(end 22.8092 -46.5709)
		(width 0.508)
		(layer "F.Cu")
		(net "P12V_MAIN")
	)
	(segment
		(start 16.2814 -46.8249)
		(end 16.2814 -45.339)
		(width 0.508)
		(layer "F.Cu")
		(net "P12V_MAIN")
	)
	(segment
		(start 18.4912 -46.5201)
		(end 18.4912 -45.2628)
		(width 0.508)
		(layer "F.Cu")
		(net "P12V_MAIN")
	)
	(via
		(at 27.602688 -33.749234)
		(size 0.8636)
		(drill 0.508)
		(layers "F.Cu" "B.Cu")
		(net "P12V_MAIN")
	)
	(via
		(at 22.8092 -45.212)
		(size 0.508)
		(drill 0.254)
		(layers "F.Cu" "B.Cu")
		(net "P12V_MAIN")
	)
	(via
		(at 26.078688 -35.171634)
		(size 0.8636)
		(drill 0.508)
		(layers "F.Cu" "B.Cu")
		(net "P12V_MAIN")
	)
	(via
		(at 28.4734 -31.623)
		(size 0.6604)
		(drill 0.3302)
		(layers "F.Cu" "B.Cu")
		(net "P12V_MAIN")
	)
	(via
		(at 21.5392 -37.3634)
		(size 0.6604)
		(drill 0.3302)
		(layers "F.Cu" "B.Cu")
		(net "P12V_MAIN")
	)
	(via
		(at 18.4912 -45.2628)
		(size 0.508)
		(drill 0.254)
		(layers "F.Cu" "B.Cu")
		(net "P12V_MAIN")
	)
	(via
		(at 18.0848 -34.8488)
		(size 0.508)
		(drill 0.254)
		(layers "F.Cu" "B.Cu")
		(net "P12V_MAIN")
	)
	(via
		(at 21.506688 -35.171634)
		(size 0.8636)
		(drill 0.508)
		(layers "F.Cu" "B.Cu")
		(net "P12V_MAIN")
	)
	(via
		(at 16.256 -45.3136)
		(size 0.508)
		(drill 0.254)
		(layers "F.Cu" "B.Cu")
		(net "P12V_MAIN")
	)
	(via
		(at 27.7114 -37.3634)
		(size 0.6604)
		(drill 0.3302)
		(layers "F.Cu" "B.Cu")
		(net "P12V_MAIN")
	)
	(via
		(at 23.622 -37.338)
		(size 0.6604)
		(drill 0.3302)
		(layers "F.Cu" "B.Cu")
		(net "P12V_MAIN")
	)
	(via
		(at 27.602688 -35.171634)
		(size 0.8636)
		(drill 0.508)
		(layers "F.Cu" "B.Cu")
		(net "P12V_MAIN")
	)
	(via
		(at 23.030688 -35.171634)
		(size 0.8636)
		(drill 0.508)
		(layers "F.Cu" "B.Cu")
		(net "P12V_MAIN")
	)
	(via
		(at 23.030688 -33.749234)
		(size 0.8636)
		(drill 0.508)
		(layers "F.Cu" "B.Cu")
		(net "P12V_MAIN")
	)
	(via
		(at 29.531056 -34.560256)
		(size 0.6604)
		(drill 0.3302)
		(layers "F.Cu" "B.Cu")
		(net "P12V_MAIN")
	)
	(via
		(at 10.23366 -60.912756)
		(size 0.508)
		(drill 0.254)
		(layers "F.Cu" "B.Cu")
		(net "P12V_MAIN")
	)
	(via
		(at 26.078688 -33.749234)
		(size 0.8636)
		(drill 0.508)
		(layers "F.Cu" "B.Cu")
		(net "P12V_MAIN")
	)
	(via
		(at 25.6286 -37.338)
		(size 0.6604)
		(drill 0.3302)
		(layers "F.Cu" "B.Cu")
		(net "P12V_MAIN")
	)
	(via
		(at 30.4038 -37.3888)
		(size 0.6604)
		(drill 0.3302)
		(layers "F.Cu" "B.Cu")
		(net "P12V_MAIN")
	)
	(via
		(at 21.506688 -33.749234)
		(size 0.8636)
		(drill 0.508)
		(layers "F.Cu" "B.Cu")
		(net "P12V_MAIN")
	)
	(via
		(at 24.554688 -33.749234)
		(size 0.8636)
		(drill 0.508)
		(layers "F.Cu" "B.Cu")
		(net "P12V_MAIN")
	)
	(via
		(at 30.4038 -31.6484)
		(size 0.6604)
		(drill 0.3302)
		(layers "F.Cu" "B.Cu")
		(net "P12V_MAIN")
	)
	(via
		(at 24.554688 -35.171634)
		(size 0.8636)
		(drill 0.508)
		(layers "F.Cu" "B.Cu")
		(net "P12V_MAIN")
	)
	(segment
		(start 16.256 -46.101)
		(end 16.256 -45.3136)
		(width 0.508)
		(layer "In5.Cu")
		(net "P12V_MAIN")
	)
	(segment
		(start 14.8844 -59.2836)
		(end 16.8656 -57.3024)
		(width 0.508)
		(layer "In5.Cu")
		(net "P12V_MAIN")
	)
	(segment
		(start 16.8656 -46.7106)
		(end 16.256 -46.101)
		(width 0.508)
		(layer "In5.Cu")
		(net "P12V_MAIN")
	)
	(segment
		(start 22.8092 -46.1518)
		(end 22.8092 -45.212)
		(width 0.508)
		(layer "In5.Cu")
		(net "P12V_MAIN")
	)
	(segment
		(start 18.4912 -46.0756)
		(end 18.85061 -46.43501)
		(width 0.508)
		(layer "In5.Cu")
		(net "P12V_MAIN")
	)
	(segment
		(start 16.256 -45.3136)
		(end 16.256 -44.7294)
		(width 0.508)
		(layer "In5.Cu")
		(net "P12V_MAIN")
	)
	(segment
		(start 22.8092 -45.212)
		(end 22.8092 -37.5539)
		(width 0.508)
		(layer "In5.Cu")
		(net "P12V_MAIN")
	)
	(segment
		(start 22.8092 -37.5539)
		(end 21.506688 -36.251388)
		(width 0.508)
		(layer "In5.Cu")
		(net "P12V_MAIN")
	)
	(segment
		(start 21.506688 -36.251388)
		(end 21.506688 -35.171634)
		(width 0.508)
		(layer "In5.Cu")
		(net "P12V_MAIN")
	)
	(segment
		(start 22.52599 -46.43501)
		(end 22.8092 -46.1518)
		(width 0.508)
		(layer "In5.Cu")
		(net "P12V_MAIN")
	)
	(segment
		(start 16.8656 -57.3024)
		(end 16.8656 -46.7106)
		(width 0.508)
		(layer "In5.Cu")
		(net "P12V_MAIN")
	)
	(segment
		(start 16.256 -44.7294)
		(end 16.7132 -44.2722)
		(width 0.508)
		(layer "In5.Cu")
		(net "P12V_MAIN")
	)
	(segment
		(start 18.4912 -44.6278)
		(end 18.4912 -45.2628)
		(width 0.508)
		(layer "In5.Cu")
		(net "P12V_MAIN")
	)
	(segment
		(start 11.862816 -59.2836)
		(end 14.8844 -59.2836)
		(width 0.508)
		(layer "In5.Cu")
		(net "P12V_MAIN")
	)
	(segment
		(start 18.1356 -44.2722)
		(end 18.4912 -44.6278)
		(width 0.508)
		(layer "In5.Cu")
		(net "P12V_MAIN")
	)
	(segment
		(start 10.23366 -60.912756)
		(end 11.862816 -59.2836)
		(width 0.508)
		(layer "In5.Cu")
		(net "P12V_MAIN")
	)
	(segment
		(start 18.85061 -46.43501)
		(end 22.52599 -46.43501)
		(width 0.508)
		(layer "In5.Cu")
		(net "P12V_MAIN")
	)
	(segment
		(start 16.7132 -44.2722)
		(end 18.1356 -44.2722)
		(width 0.508)
		(layer "In5.Cu")
		(net "P12V_MAIN")
	)
	(segment
		(start 18.4912 -45.2628)
		(end 18.4912 -46.0756)
		(width 0.508)
		(layer "In5.Cu")
		(net "P12V_MAIN")
	)
	(segment
		(start 74.22515 -73.219818)
		(end 74.22515 -72.19061)
		(width 0.127)
		(layer "F.Cu")
		(net "I2C_IOC_4_SDA")
	)
	(segment
		(start 72.952356 -72.24776)
		(end 72.952356 -73.194418)
		(width 0.127)
		(layer "F.Cu")
		(net "I2C_IOC_4_SDA")
	)
	(segment
		(start 185.000138 -40.39997)
		(end 184.999884 -40.39997)
		(width 0.127)
		(layer "F.Cu")
		(net "I2C_IOC_4_SDA")
	)
	(segment
		(start 73.613518 -71.948294)
		(end 73.251822 -71.948294)
		(width 0.127)
		(layer "F.Cu")
		(net "I2C_IOC_4_SDA")
	)
	(segment
		(start 185.399934 -40.799766)
		(end 185.000138 -40.39997)
		(width 0.127)
		(layer "F.Cu")
		(net "I2C_IOC_4_SDA")
	)
	(segment
		(start 74.22515 -72.19061)
		(end 73.982834 -71.948294)
		(width 0.127)
		(layer "F.Cu")
		(net "I2C_IOC_4_SDA")
	)
	(segment
		(start 73.982834 -71.948294)
		(end 73.613518 -71.948294)
		(width 0.127)
		(layer "F.Cu")
		(net "I2C_IOC_4_SDA")
	)
	(segment
		(start 73.251822 -71.948294)
		(end 72.952356 -72.24776)
		(width 0.127)
		(layer "F.Cu")
		(net "I2C_IOC_4_SDA")
	)
	(via
		(at 73.613518 -71.948294)
		(size 0.6604)
		(drill 0.3302)
		(layers "F.Cu" "B.Cu")
		(net "I2C_IOC_4_SDA")
	)
	(via
		(at 185.399934 -40.799766)
		(size 0.508)
		(drill 0.254)
		(layers "F.Cu" "B.Cu")
		(net "I2C_IOC_4_SDA")
	)
	(via
		(at 74.22515 -73.219818)
		(size 0.508)
		(drill 0.254)
		(layers "F.Cu" "B.Cu")
		(net "I2C_IOC_4_SDA")
	)
	(segment
		(start 186.487308 -40.72001)
		(end 186.407552 -40.799766)
		(width 0.127)
		(layer "B.Cu")
		(net "I2C_IOC_4_SDA")
	)
	(segment
		(start 186.407552 -40.799766)
		(end 185.399934 -40.799766)
		(width 0.127)
		(layer "B.Cu")
		(net "I2C_IOC_4_SDA")
	)
	(segment
		(start 180.619146 -20.901406)
		(end 181.600348 -21.882608)
		(width 0.127)
		(layer "In2.Cu")
		(net "I2C_IOC_4_SDA")
	)
	(segment
		(start 197.7263 -32.478218)
		(end 195.069968 -35.13455)
		(width 0.127)
		(layer "In2.Cu")
		(net "I2C_IOC_4_SDA")
	)
	(segment
		(start 195.069968 -35.13455)
		(end 192.937384 -35.13455)
		(width 0.127)
		(layer "In2.Cu")
		(net "I2C_IOC_4_SDA")
	)
	(segment
		(start 181.600348 -22.839934)
		(end 182.762144 -24.00173)
		(width 0.127)
		(layer "In2.Cu")
		(net "I2C_IOC_4_SDA")
	)
	(segment
		(start 184.980834 -39.026084)
		(end 184.980834 -40.380666)
		(width 0.127)
		(layer "In2.Cu")
		(net "I2C_IOC_4_SDA")
	)
	(segment
		(start 81.82991 -68.67652)
		(end 85.414866 -65.091564)
		(width 0.127)
		(layer "In2.Cu")
		(net "I2C_IOC_4_SDA")
	)
	(segment
		(start 74.22515 -73.219818)
		(end 75.445366 -73.219818)
		(width 0.127)
		(layer "In2.Cu")
		(net "I2C_IOC_4_SDA")
	)
	(segment
		(start 75.445366 -73.219818)
		(end 76.637134 -72.02805)
		(width 0.127)
		(layer "In2.Cu")
		(net "I2C_IOC_4_SDA")
	)
	(segment
		(start 89.294716 -60.155582)
		(end 89.294716 -58.504836)
		(width 0.127)
		(layer "In2.Cu")
		(net "I2C_IOC_4_SDA")
	)
	(segment
		(start 92.785692 -55.01386)
		(end 94.396306 -55.01386)
		(width 0.127)
		(layer "In2.Cu")
		(net "I2C_IOC_4_SDA")
	)
	(segment
		(start 185.228738 -38.77818)
		(end 184.980834 -39.026084)
		(width 0.127)
		(layer "In2.Cu")
		(net "I2C_IOC_4_SDA")
	)
	(segment
		(start 197.7263 -26.98242)
		(end 197.7263 -32.478218)
		(width 0.127)
		(layer "In2.Cu")
		(net "I2C_IOC_4_SDA")
	)
	(segment
		(start 191.633348 -24.209502)
		(end 194.953382 -24.209502)
		(width 0.127)
		(layer "In2.Cu")
		(net "I2C_IOC_4_SDA")
	)
	(segment
		(start 77.226414 -72.02805)
		(end 80.577944 -68.67652)
		(width 0.127)
		(layer "In2.Cu")
		(net "I2C_IOC_4_SDA")
	)
	(segment
		(start 76.637134 -72.02805)
		(end 77.226414 -72.02805)
		(width 0.127)
		(layer "In2.Cu")
		(net "I2C_IOC_4_SDA")
	)
	(segment
		(start 181.600348 -21.882608)
		(end 181.600348 -22.839934)
		(width 0.127)
		(layer "In2.Cu")
		(net "I2C_IOC_4_SDA")
	)
	(segment
		(start 110.152688 -42.544746)
		(end 123.363736 -42.544746)
		(width 0.127)
		(layer "In2.Cu")
		(net "I2C_IOC_4_SDA")
	)
	(segment
		(start 89.294716 -58.504836)
		(end 92.785692 -55.01386)
		(width 0.127)
		(layer "In2.Cu")
		(net "I2C_IOC_4_SDA")
	)
	(segment
		(start 187.580778 -24.00173)
		(end 187.872116 -23.710392)
		(width 0.127)
		(layer "In2.Cu")
		(net "I2C_IOC_4_SDA")
	)
	(segment
		(start 100.134166 -49.276)
		(end 103.421434 -49.276)
		(width 0.127)
		(layer "In2.Cu")
		(net "I2C_IOC_4_SDA")
	)
	(segment
		(start 188.6204 -37.5793)
		(end 187.42152 -38.77818)
		(width 0.127)
		(layer "In2.Cu")
		(net "I2C_IOC_4_SDA")
	)
	(segment
		(start 187.42152 -38.77818)
		(end 185.228738 -38.77818)
		(width 0.127)
		(layer "In2.Cu")
		(net "I2C_IOC_4_SDA")
	)
	(segment
		(start 94.396306 -55.01386)
		(end 100.134166 -49.276)
		(width 0.127)
		(layer "In2.Cu")
		(net "I2C_IOC_4_SDA")
	)
	(segment
		(start 182.762144 -24.00173)
		(end 187.580778 -24.00173)
		(width 0.127)
		(layer "In2.Cu")
		(net "I2C_IOC_4_SDA")
	)
	(segment
		(start 191.134238 -23.710392)
		(end 191.633348 -24.209502)
		(width 0.127)
		(layer "In2.Cu")
		(net "I2C_IOC_4_SDA")
	)
	(segment
		(start 123.363736 -42.544746)
		(end 140.020802 -25.88768)
		(width 0.127)
		(layer "In2.Cu")
		(net "I2C_IOC_4_SDA")
	)
	(segment
		(start 85.414866 -65.091564)
		(end 85.414866 -64.035432)
		(width 0.127)
		(layer "In2.Cu")
		(net "I2C_IOC_4_SDA")
	)
	(segment
		(start 192.937384 -35.13455)
		(end 190.492634 -37.5793)
		(width 0.127)
		(layer "In2.Cu")
		(net "I2C_IOC_4_SDA")
	)
	(segment
		(start 103.421434 -49.276)
		(end 110.152688 -42.544746)
		(width 0.127)
		(layer "In2.Cu")
		(net "I2C_IOC_4_SDA")
	)
	(segment
		(start 80.577944 -68.67652)
		(end 81.82991 -68.67652)
		(width 0.127)
		(layer "In2.Cu")
		(net "I2C_IOC_4_SDA")
	)
	(segment
		(start 190.492634 -37.5793)
		(end 188.6204 -37.5793)
		(width 0.127)
		(layer "In2.Cu")
		(net "I2C_IOC_4_SDA")
	)
	(segment
		(start 194.953382 -24.209502)
		(end 197.7263 -26.98242)
		(width 0.127)
		(layer "In2.Cu")
		(net "I2C_IOC_4_SDA")
	)
	(segment
		(start 152.196292 -25.88768)
		(end 157.182566 -20.901406)
		(width 0.127)
		(layer "In2.Cu")
		(net "I2C_IOC_4_SDA")
	)
	(segment
		(start 85.414866 -64.035432)
		(end 89.294716 -60.155582)
		(width 0.127)
		(layer "In2.Cu")
		(net "I2C_IOC_4_SDA")
	)
	(segment
		(start 157.182566 -20.901406)
		(end 180.619146 -20.901406)
		(width 0.127)
		(layer "In2.Cu")
		(net "I2C_IOC_4_SDA")
	)
	(segment
		(start 187.872116 -23.710392)
		(end 191.134238 -23.710392)
		(width 0.127)
		(layer "In2.Cu")
		(net "I2C_IOC_4_SDA")
	)
	(segment
		(start 140.020802 -25.88768)
		(end 152.196292 -25.88768)
		(width 0.127)
		(layer "In2.Cu")
		(net "I2C_IOC_4_SDA")
	)
	(segment
		(start 184.980834 -40.380666)
		(end 185.399934 -40.799766)
		(width 0.127)
		(layer "In2.Cu")
		(net "I2C_IOC_4_SDA")
	)
	(segment
		(start 186.74207 -36.742878)
		(end 186.25693 -36.742878)
		(width 0.127)
		(layer "F.Cu")
		(net "I2C_IOC_4_SCL")
	)
	(segment
		(start 189.56782 -35.13582)
		(end 188.43244 -36.2712)
		(width 0.127)
		(layer "F.Cu")
		(net "I2C_IOC_4_SCL")
	)
	(segment
		(start 190.6397 -34.4043)
		(end 189.992 -35.052)
		(width 0.127)
		(layer "F.Cu")
		(net "I2C_IOC_4_SCL")
	)
	(segment
		(start 186.25693 -36.742878)
		(end 185.799984 -37.199824)
		(width 0.127)
		(layer "F.Cu")
		(net "I2C_IOC_4_SCL")
	)
	(segment
		(start 188.423296 -36.2712)
		(end 188.165486 -36.52901)
		(width 0.127)
		(layer "F.Cu")
		(net "I2C_IOC_4_SCL")
	)
	(segment
		(start 190.6397 -34.3408)
		(end 190.6397 -34.4043)
		(width 0.127)
		(layer "F.Cu")
		(net "I2C_IOC_4_SCL")
	)
	(segment
		(start 76.57084 -72.85355)
		(end 76.10729 -73.3171)
		(width 0.127)
		(layer "F.Cu")
		(net "I2C_IOC_4_SCL")
	)
	(segment
		(start 189.992 -35.13582)
		(end 189.56782 -35.13582)
		(width 0.127)
		(layer "F.Cu")
		(net "I2C_IOC_4_SCL")
	)
	(segment
		(start 186.955938 -36.52901)
		(end 186.74207 -36.742878)
		(width 0.127)
		(layer "F.Cu")
		(net "I2C_IOC_4_SCL")
	)
	(segment
		(start 76.57084 -71.404988)
		(end 76.57084 -72.85355)
		(width 0.127)
		(layer "F.Cu")
		(net "I2C_IOC_4_SCL")
	)
	(segment
		(start 188.43244 -36.2712)
		(end 188.423296 -36.2712)
		(width 0.127)
		(layer "F.Cu")
		(net "I2C_IOC_4_SCL")
	)
	(segment
		(start 188.165486 -36.52901)
		(end 186.955938 -36.52901)
		(width 0.127)
		(layer "F.Cu")
		(net "I2C_IOC_4_SCL")
	)
	(segment
		(start 189.992 -35.052)
		(end 189.992 -35.13582)
		(width 0.127)
		(layer "F.Cu")
		(net "I2C_IOC_4_SCL")
	)
	(via
		(at 189.992 -35.13582)
		(size 0.6604)
		(drill 0.3302)
		(layers "F.Cu" "B.Cu")
		(net "I2C_IOC_4_SCL")
	)
	(via
		(at 190.6397 -34.3408)
		(size 0.508)
		(drill 0.254)
		(layers "F.Cu" "B.Cu")
		(net "I2C_IOC_4_SCL")
	)
	(via
		(at 76.10729 -73.3171)
		(size 0.508)
		(drill 0.254)
		(layers "F.Cu" "B.Cu")
		(net "I2C_IOC_4_SCL")
	)
	(segment
		(start 191.410082 -34.641282)
		(end 192.29451 -34.641282)
		(width 0.127)
		(layer "B.Cu")
		(net "I2C_IOC_4_SCL")
	)
	(segment
		(start 190.6397 -34.3408)
		(end 191.1096 -34.3408)
		(width 0.127)
		(layer "B.Cu")
		(net "I2C_IOC_4_SCL")
	)
	(segment
		(start 191.1096 -34.3408)
		(end 191.410082 -34.641282)
		(width 0.127)
		(layer "B.Cu")
		(net "I2C_IOC_4_SCL")
	)
	(segment
		(start 194.701668 -24.717502)
		(end 191.422782 -24.717502)
		(width 0.127)
		(layer "In2.Cu")
		(net "I2C_IOC_4_SCL")
	)
	(segment
		(start 80.78851 -69.18452)
		(end 77.441044 -72.531986)
		(width 0.127)
		(layer "In2.Cu")
		(net "I2C_IOC_4_SCL")
	)
	(segment
		(start 100.3046 -49.911)
		(end 94.69374 -55.52186)
		(width 0.127)
		(layer "In2.Cu")
		(net "I2C_IOC_4_SCL")
	)
	(segment
		(start 89.802716 -60.366148)
		(end 85.922866 -64.245998)
		(width 0.127)
		(layer "In2.Cu")
		(net "I2C_IOC_4_SCL")
	)
	(segment
		(start 181.034944 -22.03577)
		(end 180.40858 -21.409406)
		(width 0.127)
		(layer "In2.Cu")
		(net "I2C_IOC_4_SCL")
	)
	(segment
		(start 123.574302 -43.052746)
		(end 111.041688 -43.052746)
		(width 0.127)
		(layer "In2.Cu")
		(net "I2C_IOC_4_SCL")
	)
	(segment
		(start 76.544932 -73.3171)
		(end 76.10729 -73.3171)
		(width 0.127)
		(layer "In2.Cu")
		(net "I2C_IOC_4_SCL")
	)
	(segment
		(start 152.406858 -26.39568)
		(end 140.231368 -26.39568)
		(width 0.127)
		(layer "In2.Cu")
		(net "I2C_IOC_4_SCL")
	)
	(segment
		(start 191.422782 -24.717502)
		(end 190.923672 -24.218392)
		(width 0.127)
		(layer "In2.Cu")
		(net "I2C_IOC_4_SCL")
	)
	(segment
		(start 85.922866 -64.245998)
		(end 85.922866 -65.30213)
		(width 0.127)
		(layer "In2.Cu")
		(net "I2C_IOC_4_SCL")
	)
	(segment
		(start 111.041688 -43.052746)
		(end 104.183434 -49.911)
		(width 0.127)
		(layer "In2.Cu")
		(net "I2C_IOC_4_SCL")
	)
	(segment
		(start 188.082682 -24.218392)
		(end 187.791344 -24.50973)
		(width 0.127)
		(layer "In2.Cu")
		(net "I2C_IOC_4_SCL")
	)
	(segment
		(start 195.8721 -29.1084)
		(end 195.8721 -25.887934)
		(width 0.127)
		(layer "In2.Cu")
		(net "I2C_IOC_4_SCL")
	)
	(segment
		(start 77.441044 -72.531986)
		(end 77.330046 -72.531986)
		(width 0.127)
		(layer "In2.Cu")
		(net "I2C_IOC_4_SCL")
	)
	(segment
		(start 140.231368 -26.39568)
		(end 123.574302 -43.052746)
		(width 0.127)
		(layer "In2.Cu")
		(net "I2C_IOC_4_SCL")
	)
	(segment
		(start 157.393132 -21.409406)
		(end 152.406858 -26.39568)
		(width 0.127)
		(layer "In2.Cu")
		(net "I2C_IOC_4_SCL")
	)
	(segment
		(start 94.69374 -55.52186)
		(end 92.996258 -55.52186)
		(width 0.127)
		(layer "In2.Cu")
		(net "I2C_IOC_4_SCL")
	)
	(segment
		(start 180.40858 -21.409406)
		(end 157.393132 -21.409406)
		(width 0.127)
		(layer "In2.Cu")
		(net "I2C_IOC_4_SCL")
	)
	(segment
		(start 190.923672 -24.218392)
		(end 188.082682 -24.218392)
		(width 0.127)
		(layer "In2.Cu")
		(net "I2C_IOC_4_SCL")
	)
	(segment
		(start 181.034944 -22.993096)
		(end 181.034944 -22.03577)
		(width 0.127)
		(layer "In2.Cu")
		(net "I2C_IOC_4_SCL")
	)
	(segment
		(start 187.791344 -24.50973)
		(end 182.551578 -24.50973)
		(width 0.127)
		(layer "In2.Cu")
		(net "I2C_IOC_4_SCL")
	)
	(segment
		(start 195.8721 -25.887934)
		(end 194.701668 -24.717502)
		(width 0.127)
		(layer "In2.Cu")
		(net "I2C_IOC_4_SCL")
	)
	(segment
		(start 85.922866 -65.30213)
		(end 82.040476 -69.18452)
		(width 0.127)
		(layer "In2.Cu")
		(net "I2C_IOC_4_SCL")
	)
	(segment
		(start 77.330046 -72.531986)
		(end 76.544932 -73.3171)
		(width 0.127)
		(layer "In2.Cu")
		(net "I2C_IOC_4_SCL")
	)
	(segment
		(start 92.996258 -55.52186)
		(end 89.802716 -58.715402)
		(width 0.127)
		(layer "In2.Cu")
		(net "I2C_IOC_4_SCL")
	)
	(segment
		(start 89.802716 -58.715402)
		(end 89.802716 -60.366148)
		(width 0.127)
		(layer "In2.Cu")
		(net "I2C_IOC_4_SCL")
	)
	(segment
		(start 182.551578 -24.50973)
		(end 181.034944 -22.993096)
		(width 0.127)
		(layer "In2.Cu")
		(net "I2C_IOC_4_SCL")
	)
	(segment
		(start 190.6397 -34.3408)
		(end 195.8721 -29.1084)
		(width 0.127)
		(layer "In2.Cu")
		(net "I2C_IOC_4_SCL")
	)
	(segment
		(start 104.183434 -49.911)
		(end 100.3046 -49.911)
		(width 0.127)
		(layer "In2.Cu")
		(net "I2C_IOC_4_SCL")
	)
	(segment
		(start 82.040476 -69.18452)
		(end 80.78851 -69.18452)
		(width 0.127)
		(layer "In2.Cu")
		(net "I2C_IOC_4_SCL")
	)
	(segment
		(start 185.799984 -38.800024)
		(end 185.958988 -38.800024)
		(width 0.127)
		(layer "F.Cu")
		(net "I2C_IOC_3_SDA")
	)
	(segment
		(start 187.623704 -38.457124)
		(end 188.743082 -37.337746)
		(width 0.127)
		(layer "F.Cu")
		(net "I2C_IOC_3_SDA")
	)
	(segment
		(start 189.483746 -37.337746)
		(end 190.068962 -36.75253)
		(width 0.127)
		(layer "F.Cu")
		(net "I2C_IOC_3_SDA")
	)
	(segment
		(start 190.068962 -36.75253)
		(end 190.97117 -36.75253)
		(width 0.127)
		(layer "F.Cu")
		(net "I2C_IOC_3_SDA")
	)
	(segment
		(start 191.243204 -36.480496)
		(end 191.1858 -36.5379)
		(width 0.127)
		(layer "F.Cu")
		(net "I2C_IOC_3_SDA")
	)
	(segment
		(start 186.301888 -38.457124)
		(end 187.623704 -38.457124)
		(width 0.127)
		(layer "F.Cu")
		(net "I2C_IOC_3_SDA")
	)
	(segment
		(start 192.384934 -36.480496)
		(end 191.243204 -36.480496)
		(width 0.127)
		(layer "F.Cu")
		(net "I2C_IOC_3_SDA")
	)
	(segment
		(start 185.958988 -38.800024)
		(end 186.301888 -38.457124)
		(width 0.127)
		(layer "F.Cu")
		(net "I2C_IOC_3_SDA")
	)
	(segment
		(start 190.97117 -36.75253)
		(end 191.1858 -36.5379)
		(width 0.127)
		(layer "F.Cu")
		(net "I2C_IOC_3_SDA")
	)
	(segment
		(start 188.743082 -37.337746)
		(end 189.483746 -37.337746)
		(width 0.127)
		(layer "F.Cu")
		(net "I2C_IOC_3_SDA")
	)
	(via
		(at 191.1858 -36.5379)
		(size 0.6604)
		(drill 0.3302)
		(layers "F.Cu" "B.Cu")
		(net "I2C_IOC_3_SDA")
	)
	(segment
		(start 184.999884 -41.199816)
		(end 185.399934 -41.599866)
		(width 0.127)
		(layer "F.Cu")
		(net "I2C_IOC_3_SCL")
	)
	(via
		(at 185.399934 -41.599866)
		(size 0.508)
		(drill 0.254)
		(layers "F.Cu" "B.Cu")
		(net "I2C_IOC_3_SCL")
	)
	(via
		(at 189.992 -42.418)
		(size 0.6096)
		(drill 0.3048)
		(layers "F.Cu" "B.Cu")
		(net "I2C_IOC_3_SCL")
	)
	(segment
		(start 189.173866 -41.599866)
		(end 189.992 -42.418)
		(width 0.127)
		(layer "B.Cu")
		(net "I2C_IOC_3_SCL")
	)
	(segment
		(start 190.627 -43.053)
		(end 189.992 -42.418)
		(width 0.127)
		(layer "B.Cu")
		(net "I2C_IOC_3_SCL")
	)
	(segment
		(start 191.4525 -43.053)
		(end 190.627 -43.053)
		(width 0.127)
		(layer "B.Cu")
		(net "I2C_IOC_3_SCL")
	)
	(segment
		(start 185.399934 -41.599866)
		(end 189.173866 -41.599866)
		(width 0.127)
		(layer "B.Cu")
		(net "I2C_IOC_3_SCL")
	)
	(segment
		(start 184.999884 -36.399978)
		(end 185.399934 -35.999928)
		(width 0.127)
		(layer "F.Cu")
		(net "I2C_IOC_2_SDA")
	)
	(via
		(at 190.5 -35.814)
		(size 0.6096)
		(drill 0.3048)
		(layers "F.Cu" "B.Cu")
		(net "I2C_IOC_2_SDA")
	)
	(via
		(at 185.399934 -35.999928)
		(size 0.508)
		(drill 0.254)
		(layers "F.Cu" "B.Cu")
		(net "I2C_IOC_2_SDA")
	)
	(segment
		(start 191.164718 -35.669982)
		(end 192.29451 -35.669982)
		(width 0.127)
		(layer "B.Cu")
		(net "I2C_IOC_2_SDA")
	)
	(segment
		(start 190.5 -35.814)
		(end 191.0207 -35.814)
		(width 0.127)
		(layer "B.Cu")
		(net "I2C_IOC_2_SDA")
	)
	(segment
		(start 185.819034 -35.999928)
		(end 185.970418 -36.151312)
		(width 0.127)
		(layer "B.Cu")
		(net "I2C_IOC_2_SDA")
	)
	(segment
		(start 189.9793 -35.814)
		(end 190.5 -35.814)
		(width 0.127)
		(layer "B.Cu")
		(net "I2C_IOC_2_SDA")
	)
	(segment
		(start 189.641988 -36.151312)
		(end 189.9793 -35.814)
		(width 0.127)
		(layer "B.Cu")
		(net "I2C_IOC_2_SDA")
	)
	(segment
		(start 191.0207 -35.814)
		(end 191.164718 -35.669982)
		(width 0.127)
		(layer "B.Cu")
		(net "I2C_IOC_2_SDA")
	)
	(segment
		(start 185.399934 -35.999928)
		(end 185.819034 -35.999928)
		(width 0.127)
		(layer "B.Cu")
		(net "I2C_IOC_2_SDA")
	)
	(segment
		(start 185.970418 -36.151312)
		(end 189.641988 -36.151312)
		(width 0.127)
		(layer "B.Cu")
		(net "I2C_IOC_2_SDA")
	)
	(segment
		(start 184.999884 -37.999924)
		(end 185.399934 -37.599874)
		(width 0.127)
		(layer "F.Cu")
		(net "I2C_IOC_2_SCL")
	)
	(via
		(at 190.373 -36.8427)
		(size 0.6096)
		(drill 0.3048)
		(layers "F.Cu" "B.Cu")
		(net "I2C_IOC_2_SCL")
	)
	(via
		(at 185.399934 -37.599874)
		(size 0.508)
		(drill 0.254)
		(layers "F.Cu" "B.Cu")
		(net "I2C_IOC_2_SCL")
	)
	(segment
		(start 189.8523 -36.8427)
		(end 188.663326 -38.031674)
		(width 0.127)
		(layer "B.Cu")
		(net "I2C_IOC_2_SCL")
	)
	(segment
		(start 185.831734 -38.031674)
		(end 185.399934 -37.599874)
		(width 0.127)
		(layer "B.Cu")
		(net "I2C_IOC_2_SCL")
	)
	(segment
		(start 190.373 -36.8427)
		(end 189.8523 -36.8427)
		(width 0.127)
		(layer "B.Cu")
		(net "I2C_IOC_2_SCL")
	)
	(segment
		(start 188.663326 -38.031674)
		(end 185.831734 -38.031674)
		(width 0.127)
		(layer "B.Cu")
		(net "I2C_IOC_2_SCL")
	)
	(segment
		(start 191.508634 -36.8427)
		(end 190.373 -36.8427)
		(width 0.127)
		(layer "B.Cu")
		(net "I2C_IOC_2_SCL")
	)
	(segment
		(start 191.9097 -35.9029)
		(end 190.8937 -35.9029)
		(width 0.127)
		(layer "F.Cu")
		(net "I2C_IOC_1_SDA")
	)
	(segment
		(start 186.59983 -37.999924)
		(end 187.574936 -37.999924)
		(width 0.127)
		(layer "F.Cu")
		(net "I2C_IOC_1_SDA")
	)
	(segment
		(start 189.751208 -36.24453)
		(end 189.319154 -36.676584)
		(width 0.127)
		(layer "F.Cu")
		(net "I2C_IOC_1_SDA")
	)
	(segment
		(start 188.785246 -36.789614)
		(end 189.206124 -36.789614)
		(width 0.127)
		(layer "F.Cu")
		(net "I2C_IOC_1_SDA")
	)
	(segment
		(start 192.3796 -35.433)
		(end 191.9097 -35.9029)
		(width 0.127)
		(layer "F.Cu")
		(net "I2C_IOC_1_SDA")
	)
	(segment
		(start 189.206124 -36.789614)
		(end 189.319154 -36.676584)
		(width 0.127)
		(layer "F.Cu")
		(net "I2C_IOC_1_SDA")
	)
	(segment
		(start 187.574936 -37.999924)
		(end 188.785246 -36.789614)
		(width 0.127)
		(layer "F.Cu")
		(net "I2C_IOC_1_SDA")
	)
	(segment
		(start 190.8937 -35.9029)
		(end 190.55207 -36.24453)
		(width 0.127)
		(layer "F.Cu")
		(net "I2C_IOC_1_SDA")
	)
	(segment
		(start 190.55207 -36.24453)
		(end 189.751208 -36.24453)
		(width 0.127)
		(layer "F.Cu")
		(net "I2C_IOC_1_SDA")
	)
	(via
		(at 189.319154 -36.676584)
		(size 0.6604)
		(drill 0.3302)
		(layers "F.Cu" "B.Cu")
		(net "I2C_IOC_1_SDA")
	)
	(segment
		(start 190.41872 -43.0657)
		(end 189.83198 -43.0657)
		(width 0.127)
		(layer "F.Cu")
		(net "I2C_IOC_1_SCL")
	)
	(segment
		(start 190.41872 -43.0657)
		(end 191.4017 -43.0657)
		(width 0.127)
		(layer "F.Cu")
		(net "I2C_IOC_1_SCL")
	)
	(segment
		(start 186.901328 -41.199816)
		(end 186.59983 -41.199816)
		(width 0.127)
		(layer "F.Cu")
		(net "I2C_IOC_1_SCL")
	)
	(segment
		(start 189.419484 -42.653204)
		(end 188.354716 -42.653204)
		(width 0.127)
		(layer "F.Cu")
		(net "I2C_IOC_1_SCL")
	)
	(segment
		(start 188.354716 -42.653204)
		(end 186.901328 -41.199816)
		(width 0.127)
		(layer "F.Cu")
		(net "I2C_IOC_1_SCL")
	)
	(segment
		(start 189.83198 -43.0657)
		(end 189.419484 -42.653204)
		(width 0.127)
		(layer "F.Cu")
		(net "I2C_IOC_1_SCL")
	)
	(via
		(at 190.41872 -43.0657)
		(size 0.6604)
		(drill 0.3302)
		(layers "F.Cu" "B.Cu")
		(net "I2C_IOC_1_SCL")
	)
	(segment
		(start 186.466734 -40.047926)
		(end 186.11469 -40.39997)
		(width 0.127)
		(layer "F.Cu")
		(net "I2C_IOC_0_SDA")
	)
	(segment
		(start 189.6745 -40.0558)
		(end 189.666626 -40.047926)
		(width 0.127)
		(layer "F.Cu")
		(net "I2C_IOC_0_SDA")
	)
	(segment
		(start 189.666626 -40.047926)
		(end 186.466734 -40.047926)
		(width 0.127)
		(layer "F.Cu")
		(net "I2C_IOC_0_SDA")
	)
	(segment
		(start 186.11469 -40.39997)
		(end 185.799984 -40.39997)
		(width 0.127)
		(layer "F.Cu")
		(net "I2C_IOC_0_SDA")
	)
	(via
		(at 189.6745 -40.0558)
		(size 0.508)
		(drill 0.254)
		(layers "F.Cu" "B.Cu")
		(net "I2C_IOC_0_SDA")
	)
	(via
		(at 190.381382 -40.8432)
		(size 0.6096)
		(drill 0.3048)
		(layers "F.Cu" "B.Cu")
		(net "I2C_IOC_0_SDA")
	)
	(segment
		(start 190.381382 -40.8432)
		(end 189.8777 -40.8432)
		(width 0.127)
		(layer "B.Cu")
		(net "I2C_IOC_0_SDA")
	)
	(segment
		(start 189.6745 -40.64)
		(end 189.6745 -40.0558)
		(width 0.127)
		(layer "B.Cu")
		(net "I2C_IOC_0_SDA")
	)
	(segment
		(start 191.5795 -40.8432)
		(end 190.381382 -40.8432)
		(width 0.127)
		(layer "B.Cu")
		(net "I2C_IOC_0_SDA")
	)
	(segment
		(start 189.8777 -40.8432)
		(end 189.6745 -40.64)
		(width 0.127)
		(layer "B.Cu")
		(net "I2C_IOC_0_SDA")
	)
	(segment
		(start 191.8208 -35.2171)
		(end 192.6463 -34.3916)
		(width 0.127)
		(layer "F.Cu")
		(net "I2C_IOC_0_SCL")
	)
	(segment
		(start 186.190382 -37.609526)
		(end 187.453524 -37.609526)
		(width 0.127)
		(layer "F.Cu")
		(net "I2C_IOC_0_SCL")
	)
	(segment
		(start 187.453524 -37.609526)
		(end 189.335156 -35.727894)
		(width 0.127)
		(layer "F.Cu")
		(net "I2C_IOC_0_SCL")
	)
	(segment
		(start 190.306706 -35.727894)
		(end 190.8175 -35.2171)
		(width 0.127)
		(layer "F.Cu")
		(net "I2C_IOC_0_SCL")
	)
	(segment
		(start 190.8175 -35.2171)
		(end 191.2747 -35.2171)
		(width 0.127)
		(layer "F.Cu")
		(net "I2C_IOC_0_SCL")
	)
	(segment
		(start 191.2747 -35.2171)
		(end 191.8208 -35.2171)
		(width 0.127)
		(layer "F.Cu")
		(net "I2C_IOC_0_SCL")
	)
	(segment
		(start 185.799984 -37.999924)
		(end 186.190382 -37.609526)
		(width 0.127)
		(layer "F.Cu")
		(net "I2C_IOC_0_SCL")
	)
	(segment
		(start 189.335156 -35.727894)
		(end 190.306706 -35.727894)
		(width 0.127)
		(layer "F.Cu")
		(net "I2C_IOC_0_SCL")
	)
	(via
		(at 191.2747 -35.2171)
		(size 0.6604)
		(drill 0.3302)
		(layers "F.Cu" "B.Cu")
		(net "I2C_IOC_0_SCL")
	)
	(segment
		(start 25.38476 -86.8426)
		(end 25.38476 -87.4268)
		(width 0.127)
		(layer "F.Cu")
		(net "I2C_BMC_RMT_SDA1_LS")
	)
	(segment
		(start 27.051 -85.60054)
		(end 27.051 -84.8106)
		(width 0.127)
		(layer "F.Cu")
		(net "I2C_BMC_RMT_SDA1_LS")
	)
	(segment
		(start 26.449274 -86.529926)
		(end 25.697434 -86.529926)
		(width 0.127)
		(layer "F.Cu")
		(net "I2C_BMC_RMT_SDA1_LS")
	)
	(segment
		(start 26.85034 -86.12886)
		(end 26.449274 -86.529926)
		(width 0.127)
		(layer "F.Cu")
		(net "I2C_BMC_RMT_SDA1_LS")
	)
	(segment
		(start 26.85034 -85.91804)
		(end 26.85034 -86.12886)
		(width 0.127)
		(layer "F.Cu")
		(net "I2C_BMC_RMT_SDA1_LS")
	)
	(segment
		(start 26.79192 -85.85962)
		(end 27.051 -85.60054)
		(width 0.127)
		(layer "F.Cu")
		(net "I2C_BMC_RMT_SDA1_LS")
	)
	(segment
		(start 128.500124 -78.500224)
		(end 128.999996 -79.000096)
		(width 0.127)
		(layer "F.Cu")
		(net "I2C_BMC_RMT_SDA1_LS")
	)
	(segment
		(start 26.79192 -85.85962)
		(end 26.85034 -85.91804)
		(width 0.127)
		(layer "F.Cu")
		(net "I2C_BMC_RMT_SDA1_LS")
	)
	(segment
		(start 25.697434 -86.529926)
		(end 25.38476 -86.8426)
		(width 0.127)
		(layer "F.Cu")
		(net "I2C_BMC_RMT_SDA1_LS")
	)
	(via
		(at 137.019284 -86.956138)
		(size 0.508)
		(drill 0.254)
		(layers "F.Cu" "B.Cu")
		(net "I2C_BMC_RMT_SDA1_LS")
	)
	(via
		(at 26.79192 -85.85962)
		(size 0.6604)
		(drill 0.3302)
		(layers "F.Cu" "B.Cu")
		(net "I2C_BMC_RMT_SDA1_LS")
	)
	(via
		(at 27.051 -84.8106)
		(size 0.508)
		(drill 0.254)
		(layers "F.Cu" "B.Cu")
		(net "I2C_BMC_RMT_SDA1_LS")
	)
	(via
		(at 128.999996 -79.000096)
		(size 0.4572)
		(drill 0.2032)
		(layers "F.Cu" "B.Cu")
		(net "I2C_BMC_RMT_SDA1_LS")
	)
	(segment
		(start 131.877054 -81.672938)
		(end 131.877054 -80.883252)
		(width 0.127)
		(layer "B.Cu")
		(net "I2C_BMC_RMT_SDA1_LS")
	)
	(segment
		(start 131.877054 -80.883252)
		(end 131.210304 -80.216502)
		(width 0.127)
		(layer "B.Cu")
		(net "I2C_BMC_RMT_SDA1_LS")
	)
	(segment
		(start 138.302238 -85.988144)
		(end 138.302238 -84.562188)
		(width 0.127)
		(layer "B.Cu")
		(net "I2C_BMC_RMT_SDA1_LS")
	)
	(segment
		(start 137.603738 -84.25561)
		(end 137.603738 -83.878674)
		(width 0.127)
		(layer "B.Cu")
		(net "I2C_BMC_RMT_SDA1_LS")
	)
	(segment
		(start 136.427464 -82.7024)
		(end 132.906516 -82.7024)
		(width 0.127)
		(layer "B.Cu")
		(net "I2C_BMC_RMT_SDA1_LS")
	)
	(segment
		(start 132.906516 -82.7024)
		(end 131.877054 -81.672938)
		(width 0.127)
		(layer "B.Cu")
		(net "I2C_BMC_RMT_SDA1_LS")
	)
	(segment
		(start 137.603738 -83.878674)
		(end 136.427464 -82.7024)
		(width 0.127)
		(layer "B.Cu")
		(net "I2C_BMC_RMT_SDA1_LS")
	)
	(segment
		(start 138.302238 -84.562188)
		(end 137.99566 -84.25561)
		(width 0.127)
		(layer "B.Cu")
		(net "I2C_BMC_RMT_SDA1_LS")
	)
	(segment
		(start 137.334244 -86.956138)
		(end 138.302238 -85.988144)
		(width 0.127)
		(layer "B.Cu")
		(net "I2C_BMC_RMT_SDA1_LS")
	)
	(segment
		(start 129.84861 -79.3115)
		(end 129.3114 -79.3115)
		(width 0.127)
		(layer "B.Cu")
		(net "I2C_BMC_RMT_SDA1_LS")
	)
	(segment
		(start 129.3114 -79.3115)
		(end 128.999996 -79.000096)
		(width 0.127)
		(layer "B.Cu")
		(net "I2C_BMC_RMT_SDA1_LS")
	)
	(segment
		(start 137.019284 -86.956138)
		(end 137.334244 -86.956138)
		(width 0.127)
		(layer "B.Cu")
		(net "I2C_BMC_RMT_SDA1_LS")
	)
	(segment
		(start 130.753612 -80.216502)
		(end 129.84861 -79.3115)
		(width 0.127)
		(layer "B.Cu")
		(net "I2C_BMC_RMT_SDA1_LS")
	)
	(segment
		(start 131.210304 -80.216502)
		(end 130.753612 -80.216502)
		(width 0.127)
		(layer "B.Cu")
		(net "I2C_BMC_RMT_SDA1_LS")
	)
	(segment
		(start 137.99566 -84.25561)
		(end 137.603738 -84.25561)
		(width 0.127)
		(layer "B.Cu")
		(net "I2C_BMC_RMT_SDA1_LS")
	)
	(segment
		(start 64.501776 -86.527132)
		(end 66.170556 -86.527132)
		(width 0.127)
		(layer "In5.Cu")
		(net "I2C_BMC_RMT_SDA1_LS")
	)
	(segment
		(start 66.170556 -86.527132)
		(end 74.172572 -94.529148)
		(width 0.127)
		(layer "In5.Cu")
		(net "I2C_BMC_RMT_SDA1_LS")
	)
	(segment
		(start 126.921768 -86.487)
		(end 134.457694 -86.487)
		(width 0.127)
		(layer "In5.Cu")
		(net "I2C_BMC_RMT_SDA1_LS")
	)
	(segment
		(start 136.533382 -87.44204)
		(end 137.019284 -86.956138)
		(width 0.127)
		(layer "In5.Cu")
		(net "I2C_BMC_RMT_SDA1_LS")
	)
	(segment
		(start 134.457694 -86.487)
		(end 135.412734 -87.44204)
		(width 0.127)
		(layer "In5.Cu")
		(net "I2C_BMC_RMT_SDA1_LS")
	)
	(segment
		(start 51.169316 -93.713554)
		(end 51.169316 -82.889344)
		(width 0.127)
		(layer "In5.Cu")
		(net "I2C_BMC_RMT_SDA1_LS")
	)
	(segment
		(start 79.323692 -97.04324)
		(end 98.802952 -97.04324)
		(width 0.127)
		(layer "In5.Cu")
		(net "I2C_BMC_RMT_SDA1_LS")
	)
	(segment
		(start 74.172572 -94.529148)
		(end 76.8096 -94.529148)
		(width 0.127)
		(layer "In5.Cu")
		(net "I2C_BMC_RMT_SDA1_LS")
	)
	(segment
		(start 52.21986 -81.8388)
		(end 59.813444 -81.8388)
		(width 0.127)
		(layer "In5.Cu")
		(net "I2C_BMC_RMT_SDA1_LS")
	)
	(segment
		(start 59.813444 -81.8388)
		(end 64.501776 -86.527132)
		(width 0.127)
		(layer "In5.Cu")
		(net "I2C_BMC_RMT_SDA1_LS")
	)
	(segment
		(start 35.419538 -98.766884)
		(end 46.115986 -98.766884)
		(width 0.127)
		(layer "In5.Cu")
		(net "I2C_BMC_RMT_SDA1_LS")
	)
	(segment
		(start 117.40261 -94.499938)
		(end 118.62435 -93.278198)
		(width 0.127)
		(layer "In5.Cu")
		(net "I2C_BMC_RMT_SDA1_LS")
	)
	(segment
		(start 27.051 -90.398346)
		(end 35.419538 -98.766884)
		(width 0.127)
		(layer "In5.Cu")
		(net "I2C_BMC_RMT_SDA1_LS")
	)
	(segment
		(start 76.8096 -94.529148)
		(end 79.323692 -97.04324)
		(width 0.127)
		(layer "In5.Cu")
		(net "I2C_BMC_RMT_SDA1_LS")
	)
	(segment
		(start 101.346254 -94.499938)
		(end 117.40261 -94.499938)
		(width 0.127)
		(layer "In5.Cu")
		(net "I2C_BMC_RMT_SDA1_LS")
	)
	(segment
		(start 51.169316 -82.889344)
		(end 52.21986 -81.8388)
		(width 0.127)
		(layer "In5.Cu")
		(net "I2C_BMC_RMT_SDA1_LS")
	)
	(segment
		(start 119.956072 -92.812108)
		(end 120.59666 -92.812108)
		(width 0.127)
		(layer "In5.Cu")
		(net "I2C_BMC_RMT_SDA1_LS")
	)
	(segment
		(start 135.412734 -87.44204)
		(end 136.533382 -87.44204)
		(width 0.127)
		(layer "In5.Cu")
		(net "I2C_BMC_RMT_SDA1_LS")
	)
	(segment
		(start 46.115986 -98.766884)
		(end 51.169316 -93.713554)
		(width 0.127)
		(layer "In5.Cu")
		(net "I2C_BMC_RMT_SDA1_LS")
	)
	(segment
		(start 118.62435 -93.278198)
		(end 119.489982 -93.278198)
		(width 0.127)
		(layer "In5.Cu")
		(net "I2C_BMC_RMT_SDA1_LS")
	)
	(segment
		(start 119.489982 -93.278198)
		(end 119.956072 -92.812108)
		(width 0.127)
		(layer "In5.Cu")
		(net "I2C_BMC_RMT_SDA1_LS")
	)
	(segment
		(start 120.59666 -92.812108)
		(end 126.921768 -86.487)
		(width 0.127)
		(layer "In5.Cu")
		(net "I2C_BMC_RMT_SDA1_LS")
	)
	(segment
		(start 98.802952 -97.04324)
		(end 101.346254 -94.499938)
		(width 0.127)
		(layer "In5.Cu")
		(net "I2C_BMC_RMT_SDA1_LS")
	)
	(segment
		(start 27.051 -84.8106)
		(end 27.051 -90.398346)
		(width 0.127)
		(layer "In5.Cu")
		(net "I2C_BMC_RMT_SDA1_LS")
	)
	(segment
		(start 26.00833 -93.178122)
		(end 25.745948 -92.91574)
		(width 0.127)
		(layer "F.Cu")
		(net "I2C_BMC_RMT_SDA1")
	)
	(segment
		(start 25.745948 -92.91574)
		(end 25.745948 -92.028772)
		(width 0.127)
		(layer "F.Cu")
		(net "I2C_BMC_RMT_SDA1")
	)
	(segment
		(start 25.745948 -92.028772)
		(end 25.38476 -91.667584)
		(width 0.127)
		(layer "F.Cu")
		(net "I2C_BMC_RMT_SDA1")
	)
	(segment
		(start 25.38476 -91.667584)
		(end 25.38476 -90.678)
		(width 0.127)
		(layer "F.Cu")
		(net "I2C_BMC_RMT_SDA1")
	)
	(segment
		(start 26.229564 -92.956888)
		(end 26.00833 -93.178122)
		(width 0.127)
		(layer "F.Cu")
		(net "I2C_BMC_RMT_SDA1")
	)
	(segment
		(start 26.229564 -92.198952)
		(end 26.229564 -92.956888)
		(width 0.127)
		(layer "F.Cu")
		(net "I2C_BMC_RMT_SDA1")
	)
	(via
		(at 29.021532 -89.406984)
		(size 0.6096)
		(drill 0.3048)
		(layers "F.Cu" "B.Cu")
		(net "I2C_BMC_RMT_SDA1")
	)
	(via
		(at 59.2836 -85.4964)
		(size 0.508)
		(drill 0.254)
		(layers "F.Cu" "B.Cu")
		(net "I2C_BMC_RMT_SDA1")
	)
	(via
		(at 26.229564 -92.198952)
		(size 0.508)
		(drill 0.254)
		(layers "F.Cu" "B.Cu")
		(net "I2C_BMC_RMT_SDA1")
	)
	(segment
		(start 59.2836 -85.4964)
		(end 58.801 -85.979)
		(width 0.127)
		(layer "B.Cu")
		(net "I2C_BMC_RMT_SDA1")
	)
	(segment
		(start 33.914334 -85.979)
		(end 33.015682 -86.877652)
		(width 0.127)
		(layer "B.Cu")
		(net "I2C_BMC_RMT_SDA1")
	)
	(segment
		(start 33.015682 -86.877652)
		(end 31.550864 -86.877652)
		(width 0.127)
		(layer "B.Cu")
		(net "I2C_BMC_RMT_SDA1")
	)
	(segment
		(start 58.801 -85.979)
		(end 33.914334 -85.979)
		(width 0.127)
		(layer "B.Cu")
		(net "I2C_BMC_RMT_SDA1")
	)
	(segment
		(start 31.550864 -86.877652)
		(end 29.021532 -89.406984)
		(width 0.127)
		(layer "B.Cu")
		(net "I2C_BMC_RMT_SDA1")
	)
	(segment
		(start 26.229564 -92.198952)
		(end 29.021532 -89.406984)
		(width 0.127)
		(layer "B.Cu")
		(net "I2C_BMC_RMT_SDA1")
	)
	(segment
		(start 121.968514 -35.80892)
		(end 90.345514 -35.80892)
		(width 0.127)
		(layer "In2.Cu")
		(net "I2C_BMC_RMT_SDA1")
	)
	(segment
		(start 137.74039 -20.037044)
		(end 121.968514 -35.80892)
		(width 0.127)
		(layer "In2.Cu")
		(net "I2C_BMC_RMT_SDA1")
	)
	(segment
		(start 76.38796 -69.99224)
		(end 74.533252 -69.99224)
		(width 0.127)
		(layer "In2.Cu")
		(net "I2C_BMC_RMT_SDA1")
	)
	(segment
		(start 80.761332 -65.618868)
		(end 76.38796 -69.99224)
		(width 0.127)
		(layer "In2.Cu")
		(net "I2C_BMC_RMT_SDA1")
	)
	(segment
		(start 164.706046 -9.14781)
		(end 159.873442 -9.14781)
		(width 0.127)
		(layer "In2.Cu")
		(net "I2C_BMC_RMT_SDA1")
	)
	(segment
		(start 86.9061 -50.11801)
		(end 84.113878 -52.910232)
		(width 0.127)
		(layer "In2.Cu")
		(net "I2C_BMC_RMT_SDA1")
	)
	(segment
		(start 84.113878 -61.74359)
		(end 80.761332 -65.096136)
		(width 0.127)
		(layer "In2.Cu")
		(net "I2C_BMC_RMT_SDA1")
	)
	(segment
		(start 178.71821 -14.5796)
		(end 172.30725 -8.16864)
		(width 0.127)
		(layer "In2.Cu")
		(net "I2C_BMC_RMT_SDA1")
	)
	(segment
		(start 67.945 -83.494626)
		(end 66.209926 -85.2297)
		(width 0.127)
		(layer "In2.Cu")
		(net "I2C_BMC_RMT_SDA1")
	)
	(segment
		(start 66.209926 -85.2297)
		(end 59.5503 -85.2297)
		(width 0.127)
		(layer "In2.Cu")
		(net "I2C_BMC_RMT_SDA1")
	)
	(segment
		(start 172.30725 -8.16864)
		(end 165.685216 -8.16864)
		(width 0.127)
		(layer "In2.Cu")
		(net "I2C_BMC_RMT_SDA1")
	)
	(segment
		(start 74.533252 -69.99224)
		(end 67.945 -76.580492)
		(width 0.127)
		(layer "In2.Cu")
		(net "I2C_BMC_RMT_SDA1")
	)
	(segment
		(start 90.345514 -35.80892)
		(end 86.9061 -39.248334)
		(width 0.127)
		(layer "In2.Cu")
		(net "I2C_BMC_RMT_SDA1")
	)
	(segment
		(start 181.166262 -13.860526)
		(end 180.447188 -14.5796)
		(width 0.127)
		(layer "In2.Cu")
		(net "I2C_BMC_RMT_SDA1")
	)
	(segment
		(start 180.447188 -14.5796)
		(end 178.71821 -14.5796)
		(width 0.127)
		(layer "In2.Cu")
		(net "I2C_BMC_RMT_SDA1")
	)
	(segment
		(start 148.984208 -20.037044)
		(end 137.74039 -20.037044)
		(width 0.127)
		(layer "In2.Cu")
		(net "I2C_BMC_RMT_SDA1")
	)
	(segment
		(start 67.945 -76.580492)
		(end 67.945 -83.494626)
		(width 0.127)
		(layer "In2.Cu")
		(net "I2C_BMC_RMT_SDA1")
	)
	(segment
		(start 181.166262 -8.233918)
		(end 181.166262 -13.860526)
		(width 0.127)
		(layer "In2.Cu")
		(net "I2C_BMC_RMT_SDA1")
	)
	(segment
		(start 165.685216 -8.16864)
		(end 164.706046 -9.14781)
		(width 0.127)
		(layer "In2.Cu")
		(net "I2C_BMC_RMT_SDA1")
	)
	(segment
		(start 80.761332 -65.096136)
		(end 80.761332 -65.618868)
		(width 0.127)
		(layer "In2.Cu")
		(net "I2C_BMC_RMT_SDA1")
	)
	(segment
		(start 86.9061 -39.248334)
		(end 86.9061 -50.11801)
		(width 0.127)
		(layer "In2.Cu")
		(net "I2C_BMC_RMT_SDA1")
	)
	(segment
		(start 59.5503 -85.2297)
		(end 59.2836 -85.4964)
		(width 0.127)
		(layer "In2.Cu")
		(net "I2C_BMC_RMT_SDA1")
	)
	(segment
		(start 159.873442 -9.14781)
		(end 148.984208 -20.037044)
		(width 0.127)
		(layer "In2.Cu")
		(net "I2C_BMC_RMT_SDA1")
	)
	(segment
		(start 84.113878 -52.910232)
		(end 84.113878 -61.74359)
		(width 0.127)
		(layer "In2.Cu")
		(net "I2C_BMC_RMT_SDA1")
	)
	(segment
		(start 181.799992 -7.600188)
		(end 181.166262 -8.233918)
		(width 0.127)
		(layer "In2.Cu")
		(net "I2C_BMC_RMT_SDA1")
	)
	(segment
		(start 24.73452 -86.395052)
		(end 25.46858 -85.660992)
		(width 0.127)
		(layer "F.Cu")
		(net "I2C_BMC_RMT_SCL1_LS")
	)
	(segment
		(start 132.363464 -81.320386)
		(end 131.687824 -80.644746)
		(width 0.127)
		(layer "F.Cu")
		(net "I2C_BMC_RMT_SCL1_LS")
	)
	(segment
		(start 136.849358 -83.401154)
		(end 136.829292 -83.401154)
		(width 0.127)
		(layer "F.Cu")
		(net "I2C_BMC_RMT_SCL1_LS")
	)
	(segment
		(start 138.31951 -84.860892)
		(end 138.72845 -84.451952)
		(width 0.127)
		(layer "F.Cu")
		(net "I2C_BMC_RMT_SCL1_LS")
	)
	(segment
		(start 139.01801 -84.261452)
		(end 139.006834 -84.250276)
		(width 0.127)
		(layer "F.Cu")
		(net "I2C_BMC_RMT_SCL1_LS")
	)
	(segment
		(start 131.687824 -80.644746)
		(end 131.687824 -79.405988)
		(width 0.127)
		(layer "F.Cu")
		(net "I2C_BMC_RMT_SCL1_LS")
	)
	(segment
		(start 24.73452 -87.4268)
		(end 24.73452 -86.395052)
		(width 0.127)
		(layer "F.Cu")
		(net "I2C_BMC_RMT_SCL1_LS")
	)
	(segment
		(start 138.175238 -84.067904)
		(end 137.669778 -83.562444)
		(width 0.127)
		(layer "F.Cu")
		(net "I2C_BMC_RMT_SCL1_LS")
	)
	(segment
		(start 136.829292 -83.401154)
		(end 136.027668 -82.59953)
		(width 0.127)
		(layer "F.Cu")
		(net "I2C_BMC_RMT_SCL1_LS")
	)
	(segment
		(start 138.87831 -84.250276)
		(end 138.695938 -84.067904)
		(width 0.127)
		(layer "F.Cu")
		(net "I2C_BMC_RMT_SCL1_LS")
	)
	(segment
		(start 129.993898 -78.994)
		(end 129.500122 -78.500224)
		(width 0.127)
		(layer "F.Cu")
		(net "I2C_BMC_RMT_SCL1_LS")
	)
	(segment
		(start 137.590276 -83.541616)
		(end 136.98982 -83.541616)
		(width 0.127)
		(layer "F.Cu")
		(net "I2C_BMC_RMT_SCL1_LS")
	)
	(segment
		(start 26.0096 -85.119972)
		(end 25.46858 -85.660992)
		(width 0.127)
		(layer "F.Cu")
		(net "I2C_BMC_RMT_SCL1_LS")
	)
	(segment
		(start 138.086084 -86.956138)
		(end 138.31951 -86.722712)
		(width 0.127)
		(layer "F.Cu")
		(net "I2C_BMC_RMT_SCL1_LS")
	)
	(segment
		(start 136.98982 -83.541616)
		(end 136.849358 -83.401154)
		(width 0.127)
		(layer "F.Cu")
		(net "I2C_BMC_RMT_SCL1_LS")
	)
	(segment
		(start 133.574028 -82.59953)
		(end 132.363464 -81.388966)
		(width 0.127)
		(layer "F.Cu")
		(net "I2C_BMC_RMT_SCL1_LS")
	)
	(segment
		(start 26.0096 -84.8106)
		(end 26.0096 -85.119972)
		(width 0.127)
		(layer "F.Cu")
		(net "I2C_BMC_RMT_SCL1_LS")
	)
	(segment
		(start 131.275836 -78.994)
		(end 129.993898 -78.994)
		(width 0.127)
		(layer "F.Cu")
		(net "I2C_BMC_RMT_SCL1_LS")
	)
	(segment
		(start 131.687824 -79.405988)
		(end 131.275836 -78.994)
		(width 0.127)
		(layer "F.Cu")
		(net "I2C_BMC_RMT_SCL1_LS")
	)
	(segment
		(start 138.82751 -84.451952)
		(end 139.01801 -84.261452)
		(width 0.127)
		(layer "F.Cu")
		(net "I2C_BMC_RMT_SCL1_LS")
	)
	(segment
		(start 137.611104 -83.562444)
		(end 137.590276 -83.541616)
		(width 0.127)
		(layer "F.Cu")
		(net "I2C_BMC_RMT_SCL1_LS")
	)
	(segment
		(start 132.363464 -81.388966)
		(end 132.363464 -81.320386)
		(width 0.127)
		(layer "F.Cu")
		(net "I2C_BMC_RMT_SCL1_LS")
	)
	(segment
		(start 138.72845 -84.451952)
		(end 138.82751 -84.451952)
		(width 0.127)
		(layer "F.Cu")
		(net "I2C_BMC_RMT_SCL1_LS")
	)
	(segment
		(start 138.695938 -84.067904)
		(end 138.175238 -84.067904)
		(width 0.127)
		(layer "F.Cu")
		(net "I2C_BMC_RMT_SCL1_LS")
	)
	(segment
		(start 137.669778 -83.562444)
		(end 137.611104 -83.562444)
		(width 0.127)
		(layer "F.Cu")
		(net "I2C_BMC_RMT_SCL1_LS")
	)
	(segment
		(start 138.31951 -86.722712)
		(end 138.31951 -84.860892)
		(width 0.127)
		(layer "F.Cu")
		(net "I2C_BMC_RMT_SCL1_LS")
	)
	(segment
		(start 136.027668 -82.59953)
		(end 133.574028 -82.59953)
		(width 0.127)
		(layer "F.Cu")
		(net "I2C_BMC_RMT_SCL1_LS")
	)
	(segment
		(start 139.006834 -84.250276)
		(end 138.87831 -84.250276)
		(width 0.127)
		(layer "F.Cu")
		(net "I2C_BMC_RMT_SCL1_LS")
	)
	(via
		(at 25.46858 -85.660992)
		(size 0.6604)
		(drill 0.3302)
		(layers "F.Cu" "B.Cu")
		(net "I2C_BMC_RMT_SCL1_LS")
	)
	(via
		(at 138.086084 -86.956138)
		(size 0.508)
		(drill 0.254)
		(layers "F.Cu" "B.Cu")
		(net "I2C_BMC_RMT_SCL1_LS")
	)
	(via
		(at 26.0096 -84.8106)
		(size 0.508)
		(drill 0.254)
		(layers "F.Cu" "B.Cu")
		(net "I2C_BMC_RMT_SCL1_LS")
	)
	(segment
		(start 79.174086 -97.6122)
		(end 76.73213 -95.170244)
		(width 0.127)
		(layer "In5.Cu")
		(net "I2C_BMC_RMT_SCL1_LS")
	)
	(segment
		(start 74.020426 -95.170244)
		(end 66.013838 -87.163656)
		(width 0.127)
		(layer "In5.Cu")
		(net "I2C_BMC_RMT_SCL1_LS")
	)
	(segment
		(start 120.9167 -93.539818)
		(end 120.641618 -93.8149)
		(width 0.127)
		(layer "In5.Cu")
		(net "I2C_BMC_RMT_SCL1_LS")
	)
	(segment
		(start 26.0096 -90.695526)
		(end 26.0096 -84.8106)
		(width 0.127)
		(layer "In5.Cu")
		(net "I2C_BMC_RMT_SCL1_LS")
	)
	(segment
		(start 52.006246 -83.114642)
		(end 52.006246 -94.368874)
		(width 0.127)
		(layer "In5.Cu")
		(net "I2C_BMC_RMT_SCL1_LS")
	)
	(segment
		(start 52.774088 -82.3468)
		(end 52.006246 -83.114642)
		(width 0.127)
		(layer "In5.Cu")
		(net "I2C_BMC_RMT_SCL1_LS")
	)
	(segment
		(start 66.013838 -87.163656)
		(end 64.419734 -87.163656)
		(width 0.127)
		(layer "In5.Cu")
		(net "I2C_BMC_RMT_SCL1_LS")
	)
	(segment
		(start 137.73785 -86.956138)
		(end 136.743948 -87.95004)
		(width 0.127)
		(layer "In5.Cu")
		(net "I2C_BMC_RMT_SCL1_LS")
	)
	(segment
		(start 127.386334 -86.995)
		(end 120.9167 -93.464634)
		(width 0.127)
		(layer "In5.Cu")
		(net "I2C_BMC_RMT_SCL1_LS")
	)
	(segment
		(start 135.202168 -87.95004)
		(end 134.247128 -86.995)
		(width 0.127)
		(layer "In5.Cu")
		(net "I2C_BMC_RMT_SCL1_LS")
	)
	(segment
		(start 119.648986 -93.8149)
		(end 118.455948 -95.007938)
		(width 0.127)
		(layer "In5.Cu")
		(net "I2C_BMC_RMT_SCL1_LS")
	)
	(segment
		(start 120.641618 -93.8149)
		(end 119.648986 -93.8149)
		(width 0.127)
		(layer "In5.Cu")
		(net "I2C_BMC_RMT_SCL1_LS")
	)
	(segment
		(start 98.952558 -97.6122)
		(end 79.174086 -97.6122)
		(width 0.127)
		(layer "In5.Cu")
		(net "I2C_BMC_RMT_SCL1_LS")
	)
	(segment
		(start 76.73213 -95.170244)
		(end 74.020426 -95.170244)
		(width 0.127)
		(layer "In5.Cu")
		(net "I2C_BMC_RMT_SCL1_LS")
	)
	(segment
		(start 120.9167 -93.464634)
		(end 120.9167 -93.539818)
		(width 0.127)
		(layer "In5.Cu")
		(net "I2C_BMC_RMT_SCL1_LS")
	)
	(segment
		(start 101.55682 -95.007938)
		(end 98.952558 -97.6122)
		(width 0.127)
		(layer "In5.Cu")
		(net "I2C_BMC_RMT_SCL1_LS")
	)
	(segment
		(start 59.602878 -82.3468)
		(end 52.774088 -82.3468)
		(width 0.127)
		(layer "In5.Cu")
		(net "I2C_BMC_RMT_SCL1_LS")
	)
	(segment
		(start 52.006246 -94.368874)
		(end 46.487842 -99.887278)
		(width 0.127)
		(layer "In5.Cu")
		(net "I2C_BMC_RMT_SCL1_LS")
	)
	(segment
		(start 46.487842 -99.887278)
		(end 35.201352 -99.887278)
		(width 0.127)
		(layer "In5.Cu")
		(net "I2C_BMC_RMT_SCL1_LS")
	)
	(segment
		(start 134.247128 -86.995)
		(end 127.386334 -86.995)
		(width 0.127)
		(layer "In5.Cu")
		(net "I2C_BMC_RMT_SCL1_LS")
	)
	(segment
		(start 136.743948 -87.95004)
		(end 135.202168 -87.95004)
		(width 0.127)
		(layer "In5.Cu")
		(net "I2C_BMC_RMT_SCL1_LS")
	)
	(segment
		(start 138.086084 -86.956138)
		(end 137.73785 -86.956138)
		(width 0.127)
		(layer "In5.Cu")
		(net "I2C_BMC_RMT_SCL1_LS")
	)
	(segment
		(start 64.419734 -87.163656)
		(end 59.602878 -82.3468)
		(width 0.127)
		(layer "In5.Cu")
		(net "I2C_BMC_RMT_SCL1_LS")
	)
	(segment
		(start 35.201352 -99.887278)
		(end 26.0096 -90.695526)
		(width 0.127)
		(layer "In5.Cu")
		(net "I2C_BMC_RMT_SCL1_LS")
	)
	(segment
		(start 118.455948 -95.007938)
		(end 101.55682 -95.007938)
		(width 0.127)
		(layer "In5.Cu")
		(net "I2C_BMC_RMT_SCL1_LS")
	)
	(segment
		(start 25.213564 -92.931488)
		(end 24.96693 -93.178122)
		(width 0.127)
		(layer "F.Cu")
		(net "I2C_BMC_RMT_SCL1")
	)
	(segment
		(start 24.96693 -93.178122)
		(end 24.73452 -92.945712)
		(width 0.127)
		(layer "F.Cu")
		(net "I2C_BMC_RMT_SCL1")
	)
	(segment
		(start 25.213564 -92.198952)
		(end 25.213564 -92.931488)
		(width 0.127)
		(layer "F.Cu")
		(net "I2C_BMC_RMT_SCL1")
	)
	(segment
		(start 24.73452 -92.945712)
		(end 24.73452 -90.678)
		(width 0.127)
		(layer "F.Cu")
		(net "I2C_BMC_RMT_SCL1")
	)
	(via
		(at 32.799782 -86.356952)
		(size 0.6096)
		(drill 0.3048)
		(layers "F.Cu" "B.Cu")
		(net "I2C_BMC_RMT_SCL1")
	)
	(via
		(at 25.213564 -92.198952)
		(size 0.508)
		(drill 0.254)
		(layers "F.Cu" "B.Cu")
		(net "I2C_BMC_RMT_SCL1")
	)
	(via
		(at 58.42 -85.471)
		(size 0.508)
		(drill 0.254)
		(layers "F.Cu" "B.Cu")
		(net "I2C_BMC_RMT_SCL1")
	)
	(segment
		(start 25.519634 -91.892882)
		(end 25.213564 -92.198952)
		(width 0.127)
		(layer "B.Cu")
		(net "I2C_BMC_RMT_SCL1")
	)
	(segment
		(start 32.799782 -86.356952)
		(end 31.05531 -86.356952)
		(width 0.127)
		(layer "B.Cu")
		(net "I2C_BMC_RMT_SCL1")
	)
	(segment
		(start 31.05531 -86.356952)
		(end 25.519634 -91.892628)
		(width 0.127)
		(layer "B.Cu")
		(net "I2C_BMC_RMT_SCL1")
	)
	(segment
		(start 32.799782 -86.356952)
		(end 33.685734 -85.471)
		(width 0.127)
		(layer "B.Cu")
		(net "I2C_BMC_RMT_SCL1")
	)
	(segment
		(start 33.685734 -85.471)
		(end 58.42 -85.471)
		(width 0.127)
		(layer "B.Cu")
		(net "I2C_BMC_RMT_SCL1")
	)
	(segment
		(start 25.519634 -91.892628)
		(end 25.519634 -91.892882)
		(width 0.127)
		(layer "B.Cu")
		(net "I2C_BMC_RMT_SCL1")
	)
	(segment
		(start 165.47465 -7.66064)
		(end 164.49548 -8.63981)
		(width 0.127)
		(layer "In2.Cu")
		(net "I2C_BMC_RMT_SCL1")
	)
	(segment
		(start 181.799992 -6.20014)
		(end 180.658262 -7.34187)
		(width 0.127)
		(layer "In2.Cu")
		(net "I2C_BMC_RMT_SCL1")
	)
	(segment
		(start 180.658262 -13.64996)
		(end 180.236622 -14.0716)
		(width 0.127)
		(layer "In2.Cu")
		(net "I2C_BMC_RMT_SCL1")
	)
	(segment
		(start 180.236622 -14.0716)
		(end 179.02555 -14.0716)
		(width 0.127)
		(layer "In2.Cu")
		(net "I2C_BMC_RMT_SCL1")
	)
	(segment
		(start 83.605878 -52.699666)
		(end 83.605878 -61.533024)
		(width 0.127)
		(layer "In2.Cu")
		(net "I2C_BMC_RMT_SCL1")
	)
	(segment
		(start 148.401786 -19.529044)
		(end 137.529824 -19.529044)
		(width 0.127)
		(layer "In2.Cu")
		(net "I2C_BMC_RMT_SCL1")
	)
	(segment
		(start 74.254868 -69.48424)
		(end 66.914268 -76.824586)
		(width 0.127)
		(layer "In2.Cu")
		(net "I2C_BMC_RMT_SCL1")
	)
	(segment
		(start 121.757948 -35.30092)
		(end 90.134948 -35.30092)
		(width 0.127)
		(layer "In2.Cu")
		(net "I2C_BMC_RMT_SCL1")
	)
	(segment
		(start 180.658262 -7.34187)
		(end 180.658262 -13.64996)
		(width 0.127)
		(layer "In2.Cu")
		(net "I2C_BMC_RMT_SCL1")
	)
	(segment
		(start 76.177394 -69.48424)
		(end 74.254868 -69.48424)
		(width 0.127)
		(layer "In2.Cu")
		(net "I2C_BMC_RMT_SCL1")
	)
	(segment
		(start 137.529824 -19.529044)
		(end 121.757948 -35.30092)
		(width 0.127)
		(layer "In2.Cu")
		(net "I2C_BMC_RMT_SCL1")
	)
	(segment
		(start 66.914268 -83.759548)
		(end 65.952116 -84.7217)
		(width 0.127)
		(layer "In2.Cu")
		(net "I2C_BMC_RMT_SCL1")
	)
	(segment
		(start 79.922878 -65.216024)
		(end 79.922878 -65.738756)
		(width 0.127)
		(layer "In2.Cu")
		(net "I2C_BMC_RMT_SCL1")
	)
	(segment
		(start 86.3981 -39.037768)
		(end 86.3981 -49.907444)
		(width 0.127)
		(layer "In2.Cu")
		(net "I2C_BMC_RMT_SCL1")
	)
	(segment
		(start 59.1693 -84.7217)
		(end 58.42 -85.471)
		(width 0.127)
		(layer "In2.Cu")
		(net "I2C_BMC_RMT_SCL1")
	)
	(segment
		(start 159.29102 -8.63981)
		(end 148.401786 -19.529044)
		(width 0.127)
		(layer "In2.Cu")
		(net "I2C_BMC_RMT_SCL1")
	)
	(segment
		(start 66.914268 -76.824586)
		(end 66.914268 -83.759548)
		(width 0.127)
		(layer "In2.Cu")
		(net "I2C_BMC_RMT_SCL1")
	)
	(segment
		(start 164.49548 -8.63981)
		(end 159.29102 -8.63981)
		(width 0.127)
		(layer "In2.Cu")
		(net "I2C_BMC_RMT_SCL1")
	)
	(segment
		(start 179.02555 -14.0716)
		(end 172.61459 -7.66064)
		(width 0.127)
		(layer "In2.Cu")
		(net "I2C_BMC_RMT_SCL1")
	)
	(segment
		(start 90.134948 -35.30092)
		(end 86.3981 -39.037768)
		(width 0.127)
		(layer "In2.Cu")
		(net "I2C_BMC_RMT_SCL1")
	)
	(segment
		(start 83.605878 -61.533024)
		(end 79.922878 -65.216024)
		(width 0.127)
		(layer "In2.Cu")
		(net "I2C_BMC_RMT_SCL1")
	)
	(segment
		(start 172.61459 -7.66064)
		(end 165.47465 -7.66064)
		(width 0.127)
		(layer "In2.Cu")
		(net "I2C_BMC_RMT_SCL1")
	)
	(segment
		(start 79.922878 -65.738756)
		(end 76.177394 -69.48424)
		(width 0.127)
		(layer "In2.Cu")
		(net "I2C_BMC_RMT_SCL1")
	)
	(segment
		(start 65.952116 -84.7217)
		(end 59.1693 -84.7217)
		(width 0.127)
		(layer "In2.Cu")
		(net "I2C_BMC_RMT_SCL1")
	)
	(segment
		(start 86.3981 -49.907444)
		(end 83.605878 -52.699666)
		(width 0.127)
		(layer "In2.Cu")
		(net "I2C_BMC_RMT_SCL1")
	)
	(segment
		(start 21.34235 -86.331298)
		(end 21.34235 -85.91423)
		(width 0.127)
		(layer "F.Cu")
		(net "I2C_BMC_LOC_SDA0_LS")
	)
	(segment
		(start 127.500126 -77.500226)
		(end 127.999998 -78.000098)
		(width 0.127)
		(layer "F.Cu")
		(net "I2C_BMC_LOC_SDA0_LS")
	)
	(segment
		(start 21.34235 -85.91423)
		(end 21.34235 -84.954872)
		(width 0.127)
		(layer "F.Cu")
		(net "I2C_BMC_LOC_SDA0_LS")
	)
	(segment
		(start 20.02663 -87.479378)
		(end 20.02663 -86.895178)
		(width 0.127)
		(layer "F.Cu")
		(net "I2C_BMC_LOC_SDA0_LS")
	)
	(segment
		(start 20.02663 -86.895178)
		(end 20.339304 -86.582504)
		(width 0.127)
		(layer "F.Cu")
		(net "I2C_BMC_LOC_SDA0_LS")
	)
	(segment
		(start 20.339304 -86.582504)
		(end 21.091144 -86.582504)
		(width 0.127)
		(layer "F.Cu")
		(net "I2C_BMC_LOC_SDA0_LS")
	)
	(segment
		(start 21.091144 -86.582504)
		(end 21.34235 -86.331298)
		(width 0.127)
		(layer "F.Cu")
		(net "I2C_BMC_LOC_SDA0_LS")
	)
	(via
		(at 127.999998 -78.000098)
		(size 0.4572)
		(drill 0.2032)
		(layers "F.Cu" "B.Cu")
		(net "I2C_BMC_LOC_SDA0_LS")
	)
	(via
		(at 139.173458 -86.918546)
		(size 0.508)
		(drill 0.254)
		(layers "F.Cu" "B.Cu")
		(net "I2C_BMC_LOC_SDA0_LS")
	)
	(via
		(at 21.34235 -84.954872)
		(size 0.508)
		(drill 0.254)
		(layers "F.Cu" "B.Cu")
		(net "I2C_BMC_LOC_SDA0_LS")
	)
	(via
		(at 21.34235 -85.91423)
		(size 0.6604)
		(drill 0.3302)
		(layers "F.Cu" "B.Cu")
		(net "I2C_BMC_LOC_SDA0_LS")
	)
	(segment
		(start 136.766554 -82.1944)
		(end 138.819382 -84.247228)
		(width 0.127)
		(layer "B.Cu")
		(net "I2C_BMC_LOC_SDA0_LS")
	)
	(segment
		(start 138.819382 -84.247228)
		(end 139.168632 -84.247228)
		(width 0.127)
		(layer "B.Cu")
		(net "I2C_BMC_LOC_SDA0_LS")
	)
	(segment
		(start 129.149856 -78.514702)
		(end 129.692654 -79.0575)
		(width 0.127)
		(layer "B.Cu")
		(net "I2C_BMC_LOC_SDA0_LS")
	)
	(segment
		(start 129.95402 -79.0575)
		(end 130.859022 -79.962502)
		(width 0.127)
		(layer "B.Cu")
		(net "I2C_BMC_LOC_SDA0_LS")
	)
	(segment
		(start 139.7508 -86.341204)
		(end 139.7508 -85.971634)
		(width 0.127)
		(layer "B.Cu")
		(net "I2C_BMC_LOC_SDA0_LS")
	)
	(segment
		(start 127.999998 -78.000098)
		(end 128.514602 -78.514702)
		(width 0.127)
		(layer "B.Cu")
		(net "I2C_BMC_LOC_SDA0_LS")
	)
	(segment
		(start 128.514602 -78.514702)
		(end 129.149856 -78.514702)
		(width 0.127)
		(layer "B.Cu")
		(net "I2C_BMC_LOC_SDA0_LS")
	)
	(segment
		(start 130.859022 -79.962502)
		(end 131.490212 -79.962502)
		(width 0.127)
		(layer "B.Cu")
		(net "I2C_BMC_LOC_SDA0_LS")
	)
	(segment
		(start 139.173458 -86.918546)
		(end 139.7508 -86.341204)
		(width 0.127)
		(layer "B.Cu")
		(net "I2C_BMC_LOC_SDA0_LS")
	)
	(segment
		(start 131.490212 -79.962502)
		(end 132.2324 -80.70469)
		(width 0.127)
		(layer "B.Cu")
		(net "I2C_BMC_LOC_SDA0_LS")
	)
	(segment
		(start 139.880848 -85.841586)
		(end 139.880848 -84.959444)
		(width 0.127)
		(layer "B.Cu")
		(net "I2C_BMC_LOC_SDA0_LS")
	)
	(segment
		(start 132.757926 -82.1944)
		(end 136.766554 -82.1944)
		(width 0.127)
		(layer "B.Cu")
		(net "I2C_BMC_LOC_SDA0_LS")
	)
	(segment
		(start 132.2324 -81.668874)
		(end 132.757926 -82.1944)
		(width 0.127)
		(layer "B.Cu")
		(net "I2C_BMC_LOC_SDA0_LS")
	)
	(segment
		(start 139.880848 -84.959444)
		(end 139.168632 -84.247228)
		(width 0.127)
		(layer "B.Cu")
		(net "I2C_BMC_LOC_SDA0_LS")
	)
	(segment
		(start 129.692654 -79.0575)
		(end 129.95402 -79.0575)
		(width 0.127)
		(layer "B.Cu")
		(net "I2C_BMC_LOC_SDA0_LS")
	)
	(segment
		(start 132.2324 -80.70469)
		(end 132.2324 -81.668874)
		(width 0.127)
		(layer "B.Cu")
		(net "I2C_BMC_LOC_SDA0_LS")
	)
	(segment
		(start 139.7508 -85.971634)
		(end 139.880848 -85.841586)
		(width 0.127)
		(layer "B.Cu")
		(net "I2C_BMC_LOC_SDA0_LS")
	)
	(segment
		(start 21.28393 -95.745554)
		(end 21.849334 -95.18015)
		(width 0.127)
		(layer "In5.Cu")
		(net "I2C_BMC_LOC_SDA0_LS")
	)
	(segment
		(start 129.2606 -91.7702)
		(end 128.394968 -91.7702)
		(width 0.127)
		(layer "In5.Cu")
		(net "I2C_BMC_LOC_SDA0_LS")
	)
	(segment
		(start 128.0668 -92.098368)
		(end 128.0668 -92.4814)
		(width 0.127)
		(layer "In5.Cu")
		(net "I2C_BMC_LOC_SDA0_LS")
	)
	(segment
		(start 128.394968 -91.7702)
		(end 128.0668 -92.098368)
		(width 0.127)
		(layer "In5.Cu")
		(net "I2C_BMC_LOC_SDA0_LS")
	)
	(segment
		(start 137.6934 -88.100916)
		(end 137.6934 -88.704166)
		(width 0.127)
		(layer "In5.Cu")
		(net "I2C_BMC_LOC_SDA0_LS")
	)
	(segment
		(start 21.849334 -95.18015)
		(end 21.849334 -87.045546)
		(width 0.127)
		(layer "In5.Cu")
		(net "I2C_BMC_LOC_SDA0_LS")
	)
	(segment
		(start 128.0668 -92.4814)
		(end 127.0889 -93.4593)
		(width 0.127)
		(layer "In5.Cu")
		(net "I2C_BMC_LOC_SDA0_LS")
	)
	(segment
		(start 95.252794 -104.904794)
		(end 77.67955 -104.904794)
		(width 0.127)
		(layer "In5.Cu")
		(net "I2C_BMC_LOC_SDA0_LS")
	)
	(segment
		(start 102.60965 -97.547938)
		(end 95.252794 -104.904794)
		(width 0.127)
		(layer "In5.Cu")
		(net "I2C_BMC_LOC_SDA0_LS")
	)
	(segment
		(start 21.34235 -86.538562)
		(end 21.34235 -84.954872)
		(width 0.127)
		(layer "In5.Cu")
		(net "I2C_BMC_LOC_SDA0_LS")
	)
	(segment
		(start 137.6934 -88.704166)
		(end 136.838182 -89.559384)
		(width 0.127)
		(layer "In5.Cu")
		(net "I2C_BMC_LOC_SDA0_LS")
	)
	(segment
		(start 138.639804 -87.4522)
		(end 138.342116 -87.4522)
		(width 0.127)
		(layer "In5.Cu")
		(net "I2C_BMC_LOC_SDA0_LS")
	)
	(segment
		(start 139.173458 -86.918546)
		(end 138.639804 -87.4522)
		(width 0.127)
		(layer "In5.Cu")
		(net "I2C_BMC_LOC_SDA0_LS")
	)
	(segment
		(start 131.471416 -89.559384)
		(end 129.2606 -91.7702)
		(width 0.127)
		(layer "In5.Cu")
		(net "I2C_BMC_LOC_SDA0_LS")
	)
	(segment
		(start 21.28393 -100.12807)
		(end 21.28393 -95.745554)
		(width 0.127)
		(layer "In5.Cu")
		(net "I2C_BMC_LOC_SDA0_LS")
	)
	(segment
		(start 77.67955 -104.904794)
		(end 66.023744 -116.5606)
		(width 0.127)
		(layer "In5.Cu")
		(net "I2C_BMC_LOC_SDA0_LS")
	)
	(segment
		(start 66.023744 -116.5606)
		(end 37.71646 -116.5606)
		(width 0.127)
		(layer "In5.Cu")
		(net "I2C_BMC_LOC_SDA0_LS")
	)
	(segment
		(start 127.0889 -93.4593)
		(end 127.0889 -93.63075)
		(width 0.127)
		(layer "In5.Cu")
		(net "I2C_BMC_LOC_SDA0_LS")
	)
	(segment
		(start 136.838182 -89.559384)
		(end 131.471416 -89.559384)
		(width 0.127)
		(layer "In5.Cu")
		(net "I2C_BMC_LOC_SDA0_LS")
	)
	(segment
		(start 138.342116 -87.4522)
		(end 137.6934 -88.100916)
		(width 0.127)
		(layer "In5.Cu")
		(net "I2C_BMC_LOC_SDA0_LS")
	)
	(segment
		(start 37.71646 -116.5606)
		(end 21.28393 -100.12807)
		(width 0.127)
		(layer "In5.Cu")
		(net "I2C_BMC_LOC_SDA0_LS")
	)
	(segment
		(start 127.0889 -93.63075)
		(end 123.171712 -97.547938)
		(width 0.127)
		(layer "In5.Cu")
		(net "I2C_BMC_LOC_SDA0_LS")
	)
	(segment
		(start 21.849334 -87.045546)
		(end 21.34235 -86.538562)
		(width 0.127)
		(layer "In5.Cu")
		(net "I2C_BMC_LOC_SDA0_LS")
	)
	(segment
		(start 123.171712 -97.547938)
		(end 102.60965 -97.547938)
		(width 0.127)
		(layer "In5.Cu")
		(net "I2C_BMC_LOC_SDA0_LS")
	)
	(segment
		(start 20.871434 -92.25153)
		(end 20.871434 -93.009466)
		(width 0.127)
		(layer "F.Cu")
		(net "I2C_BMC_LOC_SDA0")
	)
	(segment
		(start 20.6502 -93.2307)
		(end 20.387818 -92.968318)
		(width 0.127)
		(layer "F.Cu")
		(net "I2C_BMC_LOC_SDA0")
	)
	(segment
		(start 20.871434 -93.009466)
		(end 20.6502 -93.2307)
		(width 0.127)
		(layer "F.Cu")
		(net "I2C_BMC_LOC_SDA0")
	)
	(segment
		(start 20.02663 -91.720162)
		(end 20.02663 -90.730578)
		(width 0.127)
		(layer "F.Cu")
		(net "I2C_BMC_LOC_SDA0")
	)
	(segment
		(start 20.387818 -92.968318)
		(end 20.387818 -92.08135)
		(width 0.127)
		(layer "F.Cu")
		(net "I2C_BMC_LOC_SDA0")
	)
	(segment
		(start 20.387818 -92.08135)
		(end 20.02663 -91.720162)
		(width 0.127)
		(layer "F.Cu")
		(net "I2C_BMC_LOC_SDA0")
	)
	(via
		(at 30.862524 -88.72093)
		(size 0.6096)
		(drill 0.3048)
		(layers "F.Cu" "B.Cu")
		(net "I2C_BMC_LOC_SDA0")
	)
	(via
		(at 20.871434 -92.25153)
		(size 0.508)
		(drill 0.254)
		(layers "F.Cu" "B.Cu")
		(net "I2C_BMC_LOC_SDA0")
	)
	(via
		(at 60.320682 -86.356952)
		(size 0.508)
		(drill 0.254)
		(layers "F.Cu" "B.Cu")
		(net "I2C_BMC_LOC_SDA0")
	)
	(segment
		(start 33.044638 -87.567262)
		(end 32.016192 -87.567262)
		(width 0.127)
		(layer "B.Cu")
		(net "I2C_BMC_LOC_SDA0")
	)
	(segment
		(start 59.813444 -86.86419)
		(end 33.74771 -86.86419)
		(width 0.127)
		(layer "B.Cu")
		(net "I2C_BMC_LOC_SDA0")
	)
	(segment
		(start 20.871434 -92.25153)
		(end 21.35632 -92.736416)
		(width 0.127)
		(layer "B.Cu")
		(net "I2C_BMC_LOC_SDA0")
	)
	(segment
		(start 26.847038 -92.736416)
		(end 30.862524 -88.72093)
		(width 0.127)
		(layer "B.Cu")
		(net "I2C_BMC_LOC_SDA0")
	)
	(segment
		(start 60.320682 -86.356952)
		(end 59.813444 -86.86419)
		(width 0.127)
		(layer "B.Cu")
		(net "I2C_BMC_LOC_SDA0")
	)
	(segment
		(start 33.74771 -86.86419)
		(end 33.044638 -87.567262)
		(width 0.127)
		(layer "B.Cu")
		(net "I2C_BMC_LOC_SDA0")
	)
	(segment
		(start 21.35632 -92.736416)
		(end 26.847038 -92.736416)
		(width 0.127)
		(layer "B.Cu")
		(net "I2C_BMC_LOC_SDA0")
	)
	(segment
		(start 32.016192 -87.567262)
		(end 30.862524 -88.72093)
		(width 0.127)
		(layer "B.Cu")
		(net "I2C_BMC_LOC_SDA0")
	)
	(segment
		(start 139.59967 -24.87168)
		(end 122.942604 -41.528746)
		(width 0.127)
		(layer "In2.Cu")
		(net "I2C_BMC_LOC_SDA0")
	)
	(segment
		(start 84.398866 -64.521334)
		(end 81.330292 -67.589908)
		(width 0.127)
		(layer "In2.Cu")
		(net "I2C_BMC_LOC_SDA0")
	)
	(segment
		(start 72.8599 -77.601572)
		(end 72.075802 -78.38567)
		(width 0.127)
		(layer "In2.Cu")
		(net "I2C_BMC_LOC_SDA0")
	)
	(segment
		(start 81.330292 -67.589908)
		(end 80.227424 -67.589908)
		(width 0.127)
		(layer "In2.Cu")
		(net "I2C_BMC_LOC_SDA0")
	)
	(segment
		(start 194.45224 -16.58493)
		(end 189.89294 -21.14423)
		(width 0.127)
		(layer "In2.Cu")
		(net "I2C_BMC_LOC_SDA0")
	)
	(segment
		(start 60.844938 -85.832696)
		(end 60.320682 -86.356952)
		(width 0.127)
		(layer "In2.Cu")
		(net "I2C_BMC_LOC_SDA0")
	)
	(segment
		(start 93.78696 -53.99786)
		(end 92.36456 -53.99786)
		(width 0.127)
		(layer "In2.Cu")
		(net "I2C_BMC_LOC_SDA0")
	)
	(segment
		(start 189.89294 -21.14423)
		(end 184.672224 -21.14423)
		(width 0.127)
		(layer "In2.Cu")
		(net "I2C_BMC_LOC_SDA0")
	)
	(segment
		(start 72.075802 -84.849716)
		(end 71.092822 -85.832696)
		(width 0.127)
		(layer "In2.Cu")
		(net "I2C_BMC_LOC_SDA0")
	)
	(segment
		(start 88.17356 -58.18886)
		(end 88.17356 -59.839606)
		(width 0.127)
		(layer "In2.Cu")
		(net "I2C_BMC_LOC_SDA0")
	)
	(segment
		(start 72.075802 -78.38567)
		(end 72.075802 -84.849716)
		(width 0.127)
		(layer "In2.Cu")
		(net "I2C_BMC_LOC_SDA0")
	)
	(segment
		(start 156.761434 -19.885406)
		(end 151.77516 -24.87168)
		(width 0.127)
		(layer "In2.Cu")
		(net "I2C_BMC_LOC_SDA0")
	)
	(segment
		(start 184.672224 -21.14423)
		(end 183.4134 -19.885406)
		(width 0.127)
		(layer "In2.Cu")
		(net "I2C_BMC_LOC_SDA0")
	)
	(segment
		(start 99.77882 -48.006)
		(end 93.78696 -53.99786)
		(width 0.127)
		(layer "In2.Cu")
		(net "I2C_BMC_LOC_SDA0")
	)
	(segment
		(start 183.4134 -19.885406)
		(end 156.761434 -19.885406)
		(width 0.127)
		(layer "In2.Cu")
		(net "I2C_BMC_LOC_SDA0")
	)
	(segment
		(start 109.271054 -41.528746)
		(end 102.7938 -48.006)
		(width 0.127)
		(layer "In2.Cu")
		(net "I2C_BMC_LOC_SDA0")
	)
	(segment
		(start 92.36456 -53.99786)
		(end 88.17356 -58.18886)
		(width 0.127)
		(layer "In2.Cu")
		(net "I2C_BMC_LOC_SDA0")
	)
	(segment
		(start 194.45224 -9.45261)
		(end 194.45224 -16.58493)
		(width 0.127)
		(layer "In2.Cu")
		(net "I2C_BMC_LOC_SDA0")
	)
	(segment
		(start 75.014074 -71.00824)
		(end 72.8599 -73.162414)
		(width 0.127)
		(layer "In2.Cu")
		(net "I2C_BMC_LOC_SDA0")
	)
	(segment
		(start 192.599818 -7.600188)
		(end 194.45224 -9.45261)
		(width 0.127)
		(layer "In2.Cu")
		(net "I2C_BMC_LOC_SDA0")
	)
	(segment
		(start 84.398866 -63.6143)
		(end 84.398866 -64.521334)
		(width 0.127)
		(layer "In2.Cu")
		(net "I2C_BMC_LOC_SDA0")
	)
	(segment
		(start 102.7938 -48.006)
		(end 99.77882 -48.006)
		(width 0.127)
		(layer "In2.Cu")
		(net "I2C_BMC_LOC_SDA0")
	)
	(segment
		(start 71.092822 -85.832696)
		(end 60.844938 -85.832696)
		(width 0.127)
		(layer "In2.Cu")
		(net "I2C_BMC_LOC_SDA0")
	)
	(segment
		(start 72.8599 -73.162414)
		(end 72.8599 -77.601572)
		(width 0.127)
		(layer "In2.Cu")
		(net "I2C_BMC_LOC_SDA0")
	)
	(segment
		(start 80.227424 -67.589908)
		(end 76.809092 -71.00824)
		(width 0.127)
		(layer "In2.Cu")
		(net "I2C_BMC_LOC_SDA0")
	)
	(segment
		(start 88.17356 -59.839606)
		(end 84.398866 -63.6143)
		(width 0.127)
		(layer "In2.Cu")
		(net "I2C_BMC_LOC_SDA0")
	)
	(segment
		(start 76.809092 -71.00824)
		(end 75.014074 -71.00824)
		(width 0.127)
		(layer "In2.Cu")
		(net "I2C_BMC_LOC_SDA0")
	)
	(segment
		(start 122.942604 -41.528746)
		(end 109.271054 -41.528746)
		(width 0.127)
		(layer "In2.Cu")
		(net "I2C_BMC_LOC_SDA0")
	)
	(segment
		(start 151.77516 -24.87168)
		(end 139.59967 -24.87168)
		(width 0.127)
		(layer "In2.Cu")
		(net "I2C_BMC_LOC_SDA0")
	)
	(segment
		(start 133.790436 -82.09153)
		(end 131.9784 -80.279494)
		(width 0.127)
		(layer "F.Cu")
		(net "I2C_BMC_LOC_SCL0_LS")
	)
	(segment
		(start 138.906504 -83.559904)
		(end 138.385804 -83.559904)
		(width 0.127)
		(layer "F.Cu")
		(net "I2C_BMC_LOC_SCL0_LS")
	)
	(segment
		(start 20.4724 -84.98332)
		(end 20.01647 -85.43925)
		(width 0.127)
		(layer "F.Cu")
		(net "I2C_BMC_LOC_SCL0_LS")
	)
	(segment
		(start 20.01647 -85.81517)
		(end 19.37639 -86.45525)
		(width 0.127)
		(layer "F.Cu")
		(net "I2C_BMC_LOC_SCL0_LS")
	)
	(segment
		(start 140.88999 -84.68614)
		(end 140.465302 -84.261452)
		(width 0.127)
		(layer "F.Cu")
		(net "I2C_BMC_LOC_SCL0_LS")
	)
	(segment
		(start 137.166858 -83.000088)
		(end 136.2583 -82.09153)
		(width 0.127)
		(layer "F.Cu")
		(net "I2C_BMC_LOC_SCL0_LS")
	)
	(segment
		(start 138.385804 -83.559904)
		(end 137.825988 -83.000088)
		(width 0.127)
		(layer "F.Cu")
		(net "I2C_BMC_LOC_SCL0_LS")
	)
	(segment
		(start 131.9784 -79.30134)
		(end 131.177284 -78.500224)
		(width 0.127)
		(layer "F.Cu")
		(net "I2C_BMC_LOC_SCL0_LS")
	)
	(segment
		(start 136.2583 -82.09153)
		(end 133.790436 -82.09153)
		(width 0.127)
		(layer "F.Cu")
		(net "I2C_BMC_LOC_SCL0_LS")
	)
	(segment
		(start 131.9784 -80.279494)
		(end 131.9784 -79.30134)
		(width 0.127)
		(layer "F.Cu")
		(net "I2C_BMC_LOC_SCL0_LS")
	)
	(segment
		(start 140.054076 -83.996276)
		(end 139.800076 -83.742276)
		(width 0.127)
		(layer "F.Cu")
		(net "I2C_BMC_LOC_SCL0_LS")
	)
	(segment
		(start 140.054076 -84.261452)
		(end 140.054076 -83.996276)
		(width 0.127)
		(layer "F.Cu")
		(net "I2C_BMC_LOC_SCL0_LS")
	)
	(segment
		(start 140.465302 -84.261452)
		(end 140.054076 -84.261452)
		(width 0.127)
		(layer "F.Cu")
		(net "I2C_BMC_LOC_SCL0_LS")
	)
	(segment
		(start 137.825988 -83.000088)
		(end 137.166858 -83.000088)
		(width 0.127)
		(layer "F.Cu")
		(net "I2C_BMC_LOC_SCL0_LS")
	)
	(segment
		(start 19.37639 -86.45525)
		(end 19.37639 -87.479378)
		(width 0.127)
		(layer "F.Cu")
		(net "I2C_BMC_LOC_SCL0_LS")
	)
	(segment
		(start 139.088876 -83.742276)
		(end 138.906504 -83.559904)
		(width 0.127)
		(layer "F.Cu")
		(net "I2C_BMC_LOC_SCL0_LS")
	)
	(segment
		(start 20.01647 -85.43925)
		(end 20.01647 -85.81517)
		(width 0.127)
		(layer "F.Cu")
		(net "I2C_BMC_LOC_SCL0_LS")
	)
	(segment
		(start 131.177284 -78.500224)
		(end 130.50012 -78.500224)
		(width 0.127)
		(layer "F.Cu")
		(net "I2C_BMC_LOC_SCL0_LS")
	)
	(segment
		(start 139.800076 -83.742276)
		(end 139.088876 -83.742276)
		(width 0.127)
		(layer "F.Cu")
		(net "I2C_BMC_LOC_SCL0_LS")
	)
	(via
		(at 140.88999 -84.68614)
		(size 0.508)
		(drill 0.254)
		(layers "F.Cu" "B.Cu")
		(net "I2C_BMC_LOC_SCL0_LS")
	)
	(via
		(at 20.4724 -84.98332)
		(size 0.508)
		(drill 0.254)
		(layers "F.Cu" "B.Cu")
		(net "I2C_BMC_LOC_SCL0_LS")
	)
	(via
		(at 20.01647 -85.81517)
		(size 0.6604)
		(drill 0.3302)
		(layers "F.Cu" "B.Cu")
		(net "I2C_BMC_LOC_SCL0_LS")
	)
	(segment
		(start 137.024872 -90.09126)
		(end 138.2014 -88.914732)
		(width 0.127)
		(layer "In5.Cu")
		(net "I2C_BMC_LOC_SCL0_LS")
	)
	(segment
		(start 20.77593 -95.534988)
		(end 20.77593 -100.338636)
		(width 0.127)
		(layer "In5.Cu")
		(net "I2C_BMC_LOC_SCL0_LS")
	)
	(segment
		(start 102.820216 -98.055938)
		(end 123.382278 -98.055938)
		(width 0.127)
		(layer "In5.Cu")
		(net "I2C_BMC_LOC_SCL0_LS")
	)
	(segment
		(start 138.85037 -87.9602)
		(end 139.714224 -87.096346)
		(width 0.127)
		(layer "In5.Cu")
		(net "I2C_BMC_LOC_SCL0_LS")
	)
	(segment
		(start 128.731772 -92.762832)
		(end 128.769618 -92.724986)
		(width 0.127)
		(layer "In5.Cu")
		(net "I2C_BMC_LOC_SCL0_LS")
	)
	(segment
		(start 127.386842 -94.869)
		(end 128.1938 -94.062042)
		(width 0.127)
		(layer "In5.Cu")
		(net "I2C_BMC_LOC_SCL0_LS")
	)
	(segment
		(start 123.382278 -98.055938)
		(end 126.569216 -94.869)
		(width 0.127)
		(layer "In5.Cu")
		(net "I2C_BMC_LOC_SCL0_LS")
	)
	(segment
		(start 129.785618 -92.724986)
		(end 132.419344 -90.09126)
		(width 0.127)
		(layer "In5.Cu")
		(net "I2C_BMC_LOC_SCL0_LS")
	)
	(segment
		(start 126.569216 -94.869)
		(end 127.386842 -94.869)
		(width 0.127)
		(layer "In5.Cu")
		(net "I2C_BMC_LOC_SCL0_LS")
	)
	(segment
		(start 139.714224 -85.861906)
		(end 140.88999 -84.68614)
		(width 0.127)
		(layer "In5.Cu")
		(net "I2C_BMC_LOC_SCL0_LS")
	)
	(segment
		(start 20.5867 -85.09762)
		(end 20.5867 -86.501478)
		(width 0.127)
		(layer "In5.Cu")
		(net "I2C_BMC_LOC_SCL0_LS")
	)
	(segment
		(start 20.4724 -84.98332)
		(end 20.5867 -85.09762)
		(width 0.127)
		(layer "In5.Cu")
		(net "I2C_BMC_LOC_SCL0_LS")
	)
	(segment
		(start 66.697098 -117.0686)
		(end 78.183994 -105.581704)
		(width 0.127)
		(layer "In5.Cu")
		(net "I2C_BMC_LOC_SCL0_LS")
	)
	(segment
		(start 138.552682 -87.9602)
		(end 138.85037 -87.9602)
		(width 0.127)
		(layer "In5.Cu")
		(net "I2C_BMC_LOC_SCL0_LS")
	)
	(segment
		(start 128.521968 -92.762832)
		(end 128.731772 -92.762832)
		(width 0.127)
		(layer "In5.Cu")
		(net "I2C_BMC_LOC_SCL0_LS")
	)
	(segment
		(start 20.5867 -86.501478)
		(end 21.341334 -87.256112)
		(width 0.127)
		(layer "In5.Cu")
		(net "I2C_BMC_LOC_SCL0_LS")
	)
	(segment
		(start 21.341334 -94.969584)
		(end 20.77593 -95.534988)
		(width 0.127)
		(layer "In5.Cu")
		(net "I2C_BMC_LOC_SCL0_LS")
	)
	(segment
		(start 128.1938 -93.091)
		(end 128.521968 -92.762832)
		(width 0.127)
		(layer "In5.Cu")
		(net "I2C_BMC_LOC_SCL0_LS")
	)
	(segment
		(start 128.1938 -94.062042)
		(end 128.1938 -93.091)
		(width 0.127)
		(layer "In5.Cu")
		(net "I2C_BMC_LOC_SCL0_LS")
	)
	(segment
		(start 21.341334 -87.256112)
		(end 21.341334 -94.969584)
		(width 0.127)
		(layer "In5.Cu")
		(net "I2C_BMC_LOC_SCL0_LS")
	)
	(segment
		(start 95.29445 -105.581704)
		(end 102.820216 -98.055938)
		(width 0.127)
		(layer "In5.Cu")
		(net "I2C_BMC_LOC_SCL0_LS")
	)
	(segment
		(start 37.505894 -117.0686)
		(end 66.697098 -117.0686)
		(width 0.127)
		(layer "In5.Cu")
		(net "I2C_BMC_LOC_SCL0_LS")
	)
	(segment
		(start 20.77593 -100.338636)
		(end 37.505894 -117.0686)
		(width 0.127)
		(layer "In5.Cu")
		(net "I2C_BMC_LOC_SCL0_LS")
	)
	(segment
		(start 139.714224 -87.096346)
		(end 139.714224 -85.861906)
		(width 0.127)
		(layer "In5.Cu")
		(net "I2C_BMC_LOC_SCL0_LS")
	)
	(segment
		(start 132.419344 -90.09126)
		(end 137.024872 -90.09126)
		(width 0.127)
		(layer "In5.Cu")
		(net "I2C_BMC_LOC_SCL0_LS")
	)
	(segment
		(start 138.2014 -88.914732)
		(end 138.2014 -88.311482)
		(width 0.127)
		(layer "In5.Cu")
		(net "I2C_BMC_LOC_SCL0_LS")
	)
	(segment
		(start 138.2014 -88.311482)
		(end 138.552682 -87.9602)
		(width 0.127)
		(layer "In5.Cu")
		(net "I2C_BMC_LOC_SCL0_LS")
	)
	(segment
		(start 78.183994 -105.581704)
		(end 95.29445 -105.581704)
		(width 0.127)
		(layer "In5.Cu")
		(net "I2C_BMC_LOC_SCL0_LS")
	)
	(segment
		(start 128.769618 -92.724986)
		(end 129.785618 -92.724986)
		(width 0.127)
		(layer "In5.Cu")
		(net "I2C_BMC_LOC_SCL0_LS")
	)
	(segment
		(start 19.37639 -92.99829)
		(end 19.37639 -90.730578)
		(width 0.127)
		(layer "F.Cu")
		(net "I2C_BMC_LOC_SCL0")
	)
	(segment
		(start 19.855434 -92.25153)
		(end 19.855434 -92.984066)
		(width 0.127)
		(layer "F.Cu")
		(net "I2C_BMC_LOC_SCL0")
	)
	(segment
		(start 19.6088 -93.2307)
		(end 19.37639 -92.99829)
		(width 0.127)
		(layer "F.Cu")
		(net "I2C_BMC_LOC_SCL0")
	)
	(segment
		(start 19.855434 -92.984066)
		(end 19.6088 -93.2307)
		(width 0.127)
		(layer "F.Cu")
		(net "I2C_BMC_LOC_SCL0")
	)
	(via
		(at 19.855434 -92.25153)
		(size 0.508)
		(drill 0.254)
		(layers "F.Cu" "B.Cu")
		(net "I2C_BMC_LOC_SCL0")
	)
	(via
		(at 60.371228 -87.37219)
		(size 0.6096)
		(drill 0.3048)
		(layers "F.Cu" "B.Cu")
		(net "I2C_BMC_LOC_SCL0")
	)
	(via
		(at 61.355224 -86.388194)
		(size 0.508)
		(drill 0.254)
		(layers "F.Cu" "B.Cu")
		(net "I2C_BMC_LOC_SCL0")
	)
	(segment
		(start 33.958276 -87.37219)
		(end 27.858466 -93.472)
		(width 0.127)
		(layer "B.Cu")
		(net "I2C_BMC_LOC_SCL0")
	)
	(segment
		(start 27.858466 -93.472)
		(end 21.075904 -93.472)
		(width 0.127)
		(layer "B.Cu")
		(net "I2C_BMC_LOC_SCL0")
	)
	(segment
		(start 60.371228 -87.37219)
		(end 33.958276 -87.37219)
		(width 0.127)
		(layer "B.Cu")
		(net "I2C_BMC_LOC_SCL0")
	)
	(segment
		(start 21.075904 -93.472)
		(end 19.855434 -92.25153)
		(width 0.127)
		(layer "B.Cu")
		(net "I2C_BMC_LOC_SCL0")
	)
	(segment
		(start 61.355224 -86.388194)
		(end 60.371228 -87.37219)
		(width 0.127)
		(layer "B.Cu")
		(net "I2C_BMC_LOC_SCL0")
	)
	(segment
		(start 184.461658 -21.65223)
		(end 183.202834 -20.393406)
		(width 0.127)
		(layer "In2.Cu")
		(net "I2C_BMC_LOC_SCL0")
	)
	(segment
		(start 77.019658 -71.51624)
		(end 75.22464 -71.51624)
		(width 0.127)
		(layer "In2.Cu")
		(net "I2C_BMC_LOC_SCL0")
	)
	(segment
		(start 75.22464 -71.51624)
		(end 73.3679 -73.37298)
		(width 0.127)
		(layer "In2.Cu")
		(net "I2C_BMC_LOC_SCL0")
	)
	(segment
		(start 84.906866 -63.824866)
		(end 84.906866 -64.7319)
		(width 0.127)
		(layer "In2.Cu")
		(net "I2C_BMC_LOC_SCL0")
	)
	(segment
		(start 88.786716 -59.945016)
		(end 84.906866 -63.824866)
		(width 0.127)
		(layer "In2.Cu")
		(net "I2C_BMC_LOC_SCL0")
	)
	(segment
		(start 156.972 -20.393406)
		(end 151.985726 -25.37968)
		(width 0.127)
		(layer "In2.Cu")
		(net "I2C_BMC_LOC_SCL0")
	)
	(segment
		(start 73.3679 -77.812138)
		(end 72.583802 -78.596236)
		(width 0.127)
		(layer "In2.Cu")
		(net "I2C_BMC_LOC_SCL0")
	)
	(segment
		(start 109.48162 -42.036746)
		(end 102.877366 -48.641)
		(width 0.127)
		(layer "In2.Cu")
		(net "I2C_BMC_LOC_SCL0")
	)
	(segment
		(start 194.96024 -16.795496)
		(end 190.103506 -21.65223)
		(width 0.127)
		(layer "In2.Cu")
		(net "I2C_BMC_LOC_SCL0")
	)
	(segment
		(start 84.906866 -64.7319)
		(end 81.470246 -68.16852)
		(width 0.127)
		(layer "In2.Cu")
		(net "I2C_BMC_LOC_SCL0")
	)
	(segment
		(start 100.0506 -48.641)
		(end 94.18574 -54.50586)
		(width 0.127)
		(layer "In2.Cu")
		(net "I2C_BMC_LOC_SCL0")
	)
	(segment
		(start 81.470246 -68.16852)
		(end 80.367378 -68.16852)
		(width 0.127)
		(layer "In2.Cu")
		(net "I2C_BMC_LOC_SCL0")
	)
	(segment
		(start 73.3679 -73.37298)
		(end 73.3679 -77.812138)
		(width 0.127)
		(layer "In2.Cu")
		(net "I2C_BMC_LOC_SCL0")
	)
	(segment
		(start 123.15317 -42.036746)
		(end 109.48162 -42.036746)
		(width 0.127)
		(layer "In2.Cu")
		(net "I2C_BMC_LOC_SCL0")
	)
	(segment
		(start 194.96024 -8.560562)
		(end 194.96024 -16.795496)
		(width 0.127)
		(layer "In2.Cu")
		(net "I2C_BMC_LOC_SCL0")
	)
	(segment
		(start 92.575126 -54.50586)
		(end 88.786716 -58.29427)
		(width 0.127)
		(layer "In2.Cu")
		(net "I2C_BMC_LOC_SCL0")
	)
	(segment
		(start 71.25589 -86.388194)
		(end 61.355224 -86.388194)
		(width 0.127)
		(layer "In2.Cu")
		(net "I2C_BMC_LOC_SCL0")
	)
	(segment
		(start 102.877366 -48.641)
		(end 100.0506 -48.641)
		(width 0.127)
		(layer "In2.Cu")
		(net "I2C_BMC_LOC_SCL0")
	)
	(segment
		(start 72.583802 -85.060282)
		(end 71.25589 -86.388194)
		(width 0.127)
		(layer "In2.Cu")
		(net "I2C_BMC_LOC_SCL0")
	)
	(segment
		(start 151.985726 -25.37968)
		(end 139.810236 -25.37968)
		(width 0.127)
		(layer "In2.Cu")
		(net "I2C_BMC_LOC_SCL0")
	)
	(segment
		(start 183.202834 -20.393406)
		(end 156.972 -20.393406)
		(width 0.127)
		(layer "In2.Cu")
		(net "I2C_BMC_LOC_SCL0")
	)
	(segment
		(start 139.810236 -25.37968)
		(end 123.15317 -42.036746)
		(width 0.127)
		(layer "In2.Cu")
		(net "I2C_BMC_LOC_SCL0")
	)
	(segment
		(start 72.583802 -78.596236)
		(end 72.583802 -85.060282)
		(width 0.127)
		(layer "In2.Cu")
		(net "I2C_BMC_LOC_SCL0")
	)
	(segment
		(start 80.367378 -68.16852)
		(end 77.019658 -71.51624)
		(width 0.127)
		(layer "In2.Cu")
		(net "I2C_BMC_LOC_SCL0")
	)
	(segment
		(start 190.103506 -21.65223)
		(end 184.461658 -21.65223)
		(width 0.127)
		(layer "In2.Cu")
		(net "I2C_BMC_LOC_SCL0")
	)
	(segment
		(start 192.599818 -6.20014)
		(end 194.96024 -8.560562)
		(width 0.127)
		(layer "In2.Cu")
		(net "I2C_BMC_LOC_SCL0")
	)
	(segment
		(start 94.18574 -54.50586)
		(end 92.575126 -54.50586)
		(width 0.127)
		(layer "In2.Cu")
		(net "I2C_BMC_LOC_SCL0")
	)
	(segment
		(start 88.786716 -58.29427)
		(end 88.786716 -59.945016)
		(width 0.127)
		(layer "In2.Cu")
		(net "I2C_BMC_LOC_SCL0")
	)
	(segment
		(start 88.543638 -53.23586)
		(end 87.602314 -53.23586)
		(width 0.127)
		(layer "F.Cu")
		(net "EXP_REF_CLK_R_N")
	)
	(segment
		(start 87.339932 -53.23586)
		(end 87.085424 -52.981352)
		(width 0.127)
		(layer "F.Cu")
		(net "EXP_REF_CLK_R_N")
	)
	(segment
		(start 86.005162 -52.981352)
		(end 85.268054 -53.71846)
		(width 0.127)
		(layer "F.Cu")
		(net "EXP_REF_CLK_R_N")
	)
	(segment
		(start 87.602314 -53.23586)
		(end 87.339932 -53.23586)
		(width 0.127)
		(layer "F.Cu")
		(net "EXP_REF_CLK_R_N")
	)
	(segment
		(start 87.085424 -52.981352)
		(end 86.005162 -52.981352)
		(width 0.127)
		(layer "F.Cu")
		(net "EXP_REF_CLK_R_N")
	)
	(segment
		(start 85.268054 -53.71846)
		(end 85.268054 -54.753002)
		(width 0.127)
		(layer "F.Cu")
		(net "EXP_REF_CLK_R_N")
	)
	(segment
		(start 117.288056 -25.413462)
		(end 81.381092 -25.413462)
		(width 0.127)
		(layer "F.Cu")
		(net "DRIVE_7_ACT")
	)
	(segment
		(start 81.381092 -25.413462)
		(end 80.246728 -26.547826)
		(width 0.127)
		(layer "F.Cu")
		(net "DRIVE_7_ACT")
	)
	(segment
		(start 121.340626 -21.360892)
		(end 117.288056 -25.413462)
		(width 0.127)
		(layer "F.Cu")
		(net "DRIVE_7_ACT")
	)
	(segment
		(start 107.499912 -78.500224)
		(end 107.00004 -78.000352)
		(width 0.127)
		(layer "F.Cu")
		(net "DRIVE_7_ACT")
	)
	(segment
		(start 80.246728 -26.547826)
		(end 79.952088 -26.842466)
		(width 0.127)
		(layer "F.Cu")
		(net "DRIVE_7_ACT")
	)
	(segment
		(start 79.952088 -26.842466)
		(end 79.952088 -27.506168)
		(width 0.127)
		(layer "F.Cu")
		(net "DRIVE_7_ACT")
	)
	(segment
		(start 122.00001 -8.800084)
		(end 121.340626 -9.459468)
		(width 0.127)
		(layer "F.Cu")
		(net "DRIVE_7_ACT")
	)
	(segment
		(start 121.340626 -9.459468)
		(end 121.340626 -21.360892)
		(width 0.127)
		(layer "F.Cu")
		(net "DRIVE_7_ACT")
	)
	(via
		(at 80.246728 -26.547826)
		(size 0.6604)
		(drill 0.3302)
		(layers "F.Cu" "B.Cu")
		(net "DRIVE_7_ACT")
	)
	(via
		(at 107.00004 -78.000352)
		(size 0.4572)
		(drill 0.2032)
		(layers "F.Cu" "B.Cu")
		(net "DRIVE_7_ACT")
	)
	(via
		(at 79.952088 -27.506168)
		(size 0.508)
		(drill 0.254)
		(layers "F.Cu" "B.Cu")
		(net "DRIVE_7_ACT")
	)
	(segment
		(start 86.094316 -66.6115)
		(end 91.821 -72.338184)
		(width 0.127)
		(layer "In5.Cu")
		(net "DRIVE_7_ACT")
	)
	(segment
		(start 85.2932 -63.44412)
		(end 85.2932 -65.866518)
		(width 0.127)
		(layer "In5.Cu")
		(net "DRIVE_7_ACT")
	)
	(segment
		(start 97.536 -77.724)
		(end 98.205798 -78.393798)
		(width 0.127)
		(layer "In5.Cu")
		(net "DRIVE_7_ACT")
	)
	(segment
		(start 91.821 -72.338184)
		(end 91.821 -73.567798)
		(width 0.127)
		(layer "In5.Cu")
		(net "DRIVE_7_ACT")
	)
	(segment
		(start 95.977202 -77.724)
		(end 97.536 -77.724)
		(width 0.127)
		(layer "In5.Cu")
		(net "DRIVE_7_ACT")
	)
	(segment
		(start 86.038182 -66.6115)
		(end 86.094316 -66.6115)
		(width 0.127)
		(layer "In5.Cu")
		(net "DRIVE_7_ACT")
	)
	(segment
		(start 79.952088 -30.407356)
		(end 80.46212 -30.917388)
		(width 0.127)
		(layer "In5.Cu")
		(net "DRIVE_7_ACT")
	)
	(segment
		(start 80.46212 -30.917388)
		(end 80.46212 -39.081456)
		(width 0.127)
		(layer "In5.Cu")
		(net "DRIVE_7_ACT")
	)
	(segment
		(start 81.356454 -59.507374)
		(end 85.2932 -63.44412)
		(width 0.127)
		(layer "In5.Cu")
		(net "DRIVE_7_ACT")
	)
	(segment
		(start 91.821 -73.567798)
		(end 95.977202 -77.724)
		(width 0.127)
		(layer "In5.Cu")
		(net "DRIVE_7_ACT")
	)
	(segment
		(start 85.2932 -65.866518)
		(end 86.038182 -66.6115)
		(width 0.127)
		(layer "In5.Cu")
		(net "DRIVE_7_ACT")
	)
	(segment
		(start 98.205798 -78.393798)
		(end 106.606594 -78.393798)
		(width 0.127)
		(layer "In5.Cu")
		(net "DRIVE_7_ACT")
	)
	(segment
		(start 79.952088 -27.506168)
		(end 79.952088 -30.407356)
		(width 0.127)
		(layer "In5.Cu")
		(net "DRIVE_7_ACT")
	)
	(segment
		(start 81.356454 -39.97579)
		(end 81.356454 -59.507374)
		(width 0.127)
		(layer "In5.Cu")
		(net "DRIVE_7_ACT")
	)
	(segment
		(start 80.46212 -39.081456)
		(end 81.356454 -39.97579)
		(width 0.127)
		(layer "In5.Cu")
		(net "DRIVE_7_ACT")
	)
	(segment
		(start 106.606594 -78.393798)
		(end 107.00004 -78.000352)
		(width 0.127)
		(layer "In5.Cu")
		(net "DRIVE_7_ACT")
	)
	(segment
		(start 79.068422 -26.953718)
		(end 79.068422 -27.934158)
		(width 0.127)
		(layer "F.Cu")
		(net "DRIVE_6_ACT")
	)
	(segment
		(start 79.068422 -27.934158)
		(end 79.068422 -28.762452)
		(width 0.127)
		(layer "F.Cu")
		(net "DRIVE_6_ACT")
	)
	(segment
		(start 79.068422 -28.762452)
		(end 78.920594 -28.91028)
		(width 0.127)
		(layer "F.Cu")
		(net "DRIVE_6_ACT")
	)
	(segment
		(start 117.07749 -24.905462)
		(end 81.116678 -24.905462)
		(width 0.127)
		(layer "F.Cu")
		(net "DRIVE_6_ACT")
	)
	(segment
		(start 122.00001 -7.400036)
		(end 120.832626 -8.56742)
		(width 0.127)
		(layer "F.Cu")
		(net "DRIVE_6_ACT")
	)
	(segment
		(start 81.116678 -24.905462)
		(end 79.068422 -26.953718)
		(width 0.127)
		(layer "F.Cu")
		(net "DRIVE_6_ACT")
	)
	(segment
		(start 105.499916 -80.50022)
		(end 105.000044 -80.000348)
		(width 0.127)
		(layer "F.Cu")
		(net "DRIVE_6_ACT")
	)
	(segment
		(start 120.832626 -8.56742)
		(end 120.832626 -21.150326)
		(width 0.127)
		(layer "F.Cu")
		(net "DRIVE_6_ACT")
	)
	(segment
		(start 120.832626 -21.150326)
		(end 117.07749 -24.905462)
		(width 0.127)
		(layer "F.Cu")
		(net "DRIVE_6_ACT")
	)
	(via
		(at 78.920594 -28.91028)
		(size 0.508)
		(drill 0.254)
		(layers "F.Cu" "B.Cu")
		(net "DRIVE_6_ACT")
	)
	(via
		(at 79.068422 -27.934158)
		(size 0.6604)
		(drill 0.3302)
		(layers "F.Cu" "B.Cu")
		(net "DRIVE_6_ACT")
	)
	(via
		(at 105.000044 -80.000348)
		(size 0.4572)
		(drill 0.2032)
		(layers "F.Cu" "B.Cu")
		(net "DRIVE_6_ACT")
	)
	(segment
		(start 80.340454 -40.396922)
		(end 79.44612 -39.502588)
		(width 0.127)
		(layer "In5.Cu")
		(net "DRIVE_6_ACT")
	)
	(segment
		(start 97.6503 -79.2353)
		(end 96.05137 -79.2353)
		(width 0.127)
		(layer "In5.Cu")
		(net "DRIVE_6_ACT")
	)
	(segment
		(start 78.920594 -30.812994)
		(end 78.920594 -28.91028)
		(width 0.127)
		(layer "In5.Cu")
		(net "DRIVE_6_ACT")
	)
	(segment
		(start 79.44612 -39.502588)
		(end 79.44612 -31.33852)
		(width 0.127)
		(layer "In5.Cu")
		(net "DRIVE_6_ACT")
	)
	(segment
		(start 79.44612 -31.33852)
		(end 78.920594 -30.812994)
		(width 0.127)
		(layer "In5.Cu")
		(net "DRIVE_6_ACT")
	)
	(segment
		(start 82.7151 -62.303152)
		(end 80.340454 -59.928506)
		(width 0.127)
		(layer "In5.Cu")
		(net "DRIVE_6_ACT")
	)
	(segment
		(start 86.752684 -68.707)
		(end 84.094066 -68.707)
		(width 0.127)
		(layer "In5.Cu")
		(net "DRIVE_6_ACT")
	)
	(segment
		(start 104.475534 -80.524858)
		(end 98.939858 -80.524858)
		(width 0.127)
		(layer "In5.Cu")
		(net "DRIVE_6_ACT")
	)
	(segment
		(start 84.094066 -68.707)
		(end 82.7151 -67.328034)
		(width 0.127)
		(layer "In5.Cu")
		(net "DRIVE_6_ACT")
	)
	(segment
		(start 98.939858 -80.524858)
		(end 97.6503 -79.2353)
		(width 0.127)
		(layer "In5.Cu")
		(net "DRIVE_6_ACT")
	)
	(segment
		(start 105.000044 -80.000348)
		(end 104.475534 -80.524858)
		(width 0.127)
		(layer "In5.Cu")
		(net "DRIVE_6_ACT")
	)
	(segment
		(start 82.7151 -67.328034)
		(end 82.7151 -62.303152)
		(width 0.127)
		(layer "In5.Cu")
		(net "DRIVE_6_ACT")
	)
	(segment
		(start 90.805 -72.759316)
		(end 86.752684 -68.707)
		(width 0.127)
		(layer "In5.Cu")
		(net "DRIVE_6_ACT")
	)
	(segment
		(start 96.05137 -79.2353)
		(end 90.805 -73.98893)
		(width 0.127)
		(layer "In5.Cu")
		(net "DRIVE_6_ACT")
	)
	(segment
		(start 90.805 -73.98893)
		(end 90.805 -72.759316)
		(width 0.127)
		(layer "In5.Cu")
		(net "DRIVE_6_ACT")
	)
	(segment
		(start 80.340454 -59.928506)
		(end 80.340454 -40.396922)
		(width 0.127)
		(layer "In5.Cu")
		(net "DRIVE_6_ACT")
	)
	(segment
		(start 117.489986 -23.5458)
		(end 81.488788 -23.5458)
		(width 0.127)
		(layer "F.Cu")
		(net "DRIVE_5_ACT")
	)
	(segment
		(start 81.488788 -23.5458)
		(end 78.41234 -26.622248)
		(width 0.127)
		(layer "F.Cu")
		(net "DRIVE_5_ACT")
	)
	(segment
		(start 78.41234 -29.111194)
		(end 78.071726 -29.451808)
		(width 0.127)
		(layer "F.Cu")
		(net "DRIVE_5_ACT")
	)
	(segment
		(start 105.499916 -81.500218)
		(end 105.999788 -82.00009)
		(width 0.127)
		(layer "F.Cu")
		(net "DRIVE_5_ACT")
	)
	(segment
		(start 78.41234 -26.622248)
		(end 78.41234 -29.111194)
		(width 0.127)
		(layer "F.Cu")
		(net "DRIVE_5_ACT")
	)
	(segment
		(start 78.071726 -29.451808)
		(end 77.350366 -30.173168)
		(width 0.127)
		(layer "F.Cu")
		(net "DRIVE_5_ACT")
	)
	(segment
		(start 120.200166 -7.600188)
		(end 119.567706 -8.232648)
		(width 0.127)
		(layer "F.Cu")
		(net "DRIVE_5_ACT")
	)
	(segment
		(start 119.567706 -21.46808)
		(end 117.489986 -23.5458)
		(width 0.127)
		(layer "F.Cu")
		(net "DRIVE_5_ACT")
	)
	(segment
		(start 119.567706 -8.232648)
		(end 119.567706 -21.46808)
		(width 0.127)
		(layer "F.Cu")
		(net "DRIVE_5_ACT")
	)
	(via
		(at 77.350366 -30.173168)
		(size 0.508)
		(drill 0.254)
		(layers "F.Cu" "B.Cu")
		(net "DRIVE_5_ACT")
	)
	(via
		(at 105.999788 -82.00009)
		(size 0.4572)
		(drill 0.2032)
		(layers "F.Cu" "B.Cu")
		(net "DRIVE_5_ACT")
	)
	(via
		(at 78.071726 -29.451808)
		(size 0.6604)
		(drill 0.3302)
		(layers "F.Cu" "B.Cu")
		(net "DRIVE_5_ACT")
	)
	(segment
		(start 77.363066 -31.627826)
		(end 77.363066 -30.185868)
		(width 0.127)
		(layer "In5.Cu")
		(net "DRIVE_5_ACT")
	)
	(segment
		(start 84.844128 -79.588868)
		(end 84.844128 -71.808594)
		(width 0.127)
		(layer "In5.Cu")
		(net "DRIVE_5_ACT")
	)
	(segment
		(start 85.144356 -80.098138)
		(end 85.144356 -79.889096)
		(width 0.127)
		(layer "In5.Cu")
		(net "DRIVE_5_ACT")
	)
	(segment
		(start 98.227388 -83.43138)
		(end 96.558608 -81.7626)
		(width 0.127)
		(layer "In5.Cu")
		(net "DRIVE_5_ACT")
	)
	(segment
		(start 79.322422 -64.00673)
		(end 79.322422 -63.383922)
		(width 0.127)
		(layer "In5.Cu")
		(net "DRIVE_5_ACT")
	)
	(segment
		(start 105.44302 -82.00009)
		(end 104.590088 -82.853022)
		(width 0.127)
		(layer "In5.Cu")
		(net "DRIVE_5_ACT")
	)
	(segment
		(start 79.322168 -64.849248)
		(end 79.322676 -64.84874)
		(width 0.127)
		(layer "In5.Cu")
		(net "DRIVE_5_ACT")
	)
	(segment
		(start 79.322168 -65.311274)
		(end 79.322168 -64.849248)
		(width 0.127)
		(layer "In5.Cu")
		(net "DRIVE_5_ACT")
	)
	(segment
		(start 79.322422 -63.383922)
		(end 77.86497 -61.92647)
		(width 0.127)
		(layer "In5.Cu")
		(net "DRIVE_5_ACT")
	)
	(segment
		(start 77.363066 -30.185868)
		(end 77.350366 -30.173168)
		(width 0.127)
		(layer "In5.Cu")
		(net "DRIVE_5_ACT")
	)
	(segment
		(start 96.558608 -81.7626)
		(end 86.808818 -81.7626)
		(width 0.127)
		(layer "In5.Cu")
		(net "DRIVE_5_ACT")
	)
	(segment
		(start 79.3115 -65.321942)
		(end 79.322168 -65.311274)
		(width 0.127)
		(layer "In5.Cu")
		(net "DRIVE_5_ACT")
	)
	(segment
		(start 104.590088 -82.853022)
		(end 104.590088 -82.967068)
		(width 0.127)
		(layer "In5.Cu")
		(net "DRIVE_5_ACT")
	)
	(segment
		(start 86.808818 -81.7626)
		(end 85.144356 -80.098138)
		(width 0.127)
		(layer "In5.Cu")
		(net "DRIVE_5_ACT")
	)
	(segment
		(start 77.86497 -32.12973)
		(end 77.363066 -31.627826)
		(width 0.127)
		(layer "In5.Cu")
		(net "DRIVE_5_ACT")
	)
	(segment
		(start 104.125776 -83.43138)
		(end 98.227388 -83.43138)
		(width 0.127)
		(layer "In5.Cu")
		(net "DRIVE_5_ACT")
	)
	(segment
		(start 79.322676 -64.006984)
		(end 79.322422 -64.00673)
		(width 0.127)
		(layer "In5.Cu")
		(net "DRIVE_5_ACT")
	)
	(segment
		(start 85.144356 -79.889096)
		(end 84.844128 -79.588868)
		(width 0.127)
		(layer "In5.Cu")
		(net "DRIVE_5_ACT")
	)
	(segment
		(start 84.844128 -71.808594)
		(end 79.3115 -66.275966)
		(width 0.127)
		(layer "In5.Cu")
		(net "DRIVE_5_ACT")
	)
	(segment
		(start 79.322676 -64.84874)
		(end 79.322676 -64.006984)
		(width 0.127)
		(layer "In5.Cu")
		(net "DRIVE_5_ACT")
	)
	(segment
		(start 79.3115 -66.275966)
		(end 79.3115 -65.321942)
		(width 0.127)
		(layer "In5.Cu")
		(net "DRIVE_5_ACT")
	)
	(segment
		(start 105.999788 -82.00009)
		(end 105.44302 -82.00009)
		(width 0.127)
		(layer "In5.Cu")
		(net "DRIVE_5_ACT")
	)
	(segment
		(start 77.86497 -61.92647)
		(end 77.86497 -32.12973)
		(width 0.127)
		(layer "In5.Cu")
		(net "DRIVE_5_ACT")
	)
	(segment
		(start 104.590088 -82.967068)
		(end 104.125776 -83.43138)
		(width 0.127)
		(layer "In5.Cu")
		(net "DRIVE_5_ACT")
	)
	(segment
		(start 107.499912 -79.500222)
		(end 107.00004 -80.000094)
		(width 0.127)
		(layer "F.Cu")
		(net "DRIVE_4_ACT")
	)
	(segment
		(start 77.773784 -26.255726)
		(end 80.99171 -23.0378)
		(width 0.127)
		(layer "F.Cu")
		(net "DRIVE_4_ACT")
	)
	(segment
		(start 117.27942 -23.0378)
		(end 119.032782 -21.284438)
		(width 0.127)
		(layer "F.Cu")
		(net "DRIVE_4_ACT")
	)
	(segment
		(start 80.99171 -23.0378)
		(end 117.27942 -23.0378)
		(width 0.127)
		(layer "F.Cu")
		(net "DRIVE_4_ACT")
	)
	(segment
		(start 119.032782 -21.284438)
		(end 119.032782 -7.367524)
		(width 0.127)
		(layer "F.Cu")
		(net "DRIVE_4_ACT")
	)
	(segment
		(start 77.773784 -27.993086)
		(end 77.773784 -26.999438)
		(width 0.127)
		(layer "F.Cu")
		(net "DRIVE_4_ACT")
	)
	(segment
		(start 77.773784 -26.999438)
		(end 77.773784 -26.255726)
		(width 0.127)
		(layer "F.Cu")
		(net "DRIVE_4_ACT")
	)
	(segment
		(start 119.032782 -7.367524)
		(end 120.200166 -6.20014)
		(width 0.127)
		(layer "F.Cu")
		(net "DRIVE_4_ACT")
	)
	(via
		(at 77.773784 -26.999438)
		(size 0.6604)
		(drill 0.3302)
		(layers "F.Cu" "B.Cu")
		(net "DRIVE_4_ACT")
	)
	(via
		(at 77.773784 -27.993086)
		(size 0.508)
		(drill 0.254)
		(layers "F.Cu" "B.Cu")
		(net "DRIVE_4_ACT")
	)
	(via
		(at 107.00004 -80.000094)
		(size 0.4572)
		(drill 0.2032)
		(layers "F.Cu" "B.Cu")
		(net "DRIVE_4_ACT")
	)
	(segment
		(start 91.313 -73.778364)
		(end 95.893636 -78.359)
		(width 0.127)
		(layer "In5.Cu")
		(net "DRIVE_4_ACT")
	)
	(segment
		(start 95.893636 -78.359)
		(end 97.79 -78.359)
		(width 0.127)
		(layer "In5.Cu")
		(net "DRIVE_4_ACT")
	)
	(segment
		(start 80.848454 -59.71794)
		(end 84.1502 -63.019686)
		(width 0.127)
		(layer "In5.Cu")
		(net "DRIVE_4_ACT")
	)
	(segment
		(start 84.1502 -63.019686)
		(end 84.1502 -66.806826)
		(width 0.127)
		(layer "In5.Cu")
		(net "DRIVE_4_ACT")
	)
	(segment
		(start 85.54212 -68.198746)
		(end 86.962996 -68.198746)
		(width 0.127)
		(layer "In5.Cu")
		(net "DRIVE_4_ACT")
	)
	(segment
		(start 77.773784 -27.993086)
		(end 78.721966 -27.993086)
		(width 0.127)
		(layer "In5.Cu")
		(net "DRIVE_4_ACT")
	)
	(segment
		(start 80.848454 -40.186356)
		(end 80.848454 -59.71794)
		(width 0.127)
		(layer "In5.Cu")
		(net "DRIVE_4_ACT")
	)
	(segment
		(start 78.721966 -27.993086)
		(end 79.444088 -28.715208)
		(width 0.127)
		(layer "In5.Cu")
		(net "DRIVE_4_ACT")
	)
	(segment
		(start 79.95412 -39.292022)
		(end 80.848454 -40.186356)
		(width 0.127)
		(layer "In5.Cu")
		(net "DRIVE_4_ACT")
	)
	(segment
		(start 84.1502 -66.806826)
		(end 85.54212 -68.198746)
		(width 0.127)
		(layer "In5.Cu")
		(net "DRIVE_4_ACT")
	)
	(segment
		(start 86.962996 -68.198746)
		(end 91.313 -72.54875)
		(width 0.127)
		(layer "In5.Cu")
		(net "DRIVE_4_ACT")
	)
	(segment
		(start 79.444088 -28.715208)
		(end 79.444088 -30.617922)
		(width 0.127)
		(layer "In5.Cu")
		(net "DRIVE_4_ACT")
	)
	(segment
		(start 91.313 -72.54875)
		(end 91.313 -73.778364)
		(width 0.127)
		(layer "In5.Cu")
		(net "DRIVE_4_ACT")
	)
	(segment
		(start 79.95412 -31.127954)
		(end 79.95412 -39.292022)
		(width 0.127)
		(layer "In5.Cu")
		(net "DRIVE_4_ACT")
	)
	(segment
		(start 106.454448 -79.454502)
		(end 107.00004 -80.000094)
		(width 0.127)
		(layer "In5.Cu")
		(net "DRIVE_4_ACT")
	)
	(segment
		(start 98.885502 -79.454502)
		(end 106.454448 -79.454502)
		(width 0.127)
		(layer "In5.Cu")
		(net "DRIVE_4_ACT")
	)
	(segment
		(start 79.444088 -30.617922)
		(end 79.95412 -31.127954)
		(width 0.127)
		(layer "In5.Cu")
		(net "DRIVE_4_ACT")
	)
	(segment
		(start 97.79 -78.359)
		(end 98.885502 -79.454502)
		(width 0.127)
		(layer "In5.Cu")
		(net "DRIVE_4_ACT")
	)
	(segment
		(start 84.664296 -57.83199)
		(end 83.282536 -56.45023)
		(width 0.127)
		(layer "F.Cu")
		(net "DRIVE_39_ACT")
	)
	(segment
		(start 108.869988 -41.178226)
		(end 113.897664 -41.178226)
		(width 0.127)
		(layer "F.Cu")
		(net "DRIVE_39_ACT")
	)
	(segment
		(start 146.540728 -17.754346)
		(end 146.540728 -9.459468)
		(width 0.127)
		(layer "F.Cu")
		(net "DRIVE_39_ACT")
	)
	(segment
		(start 96.894396 -59.38012)
		(end 90.034364 -59.38012)
		(width 0.127)
		(layer "F.Cu")
		(net "DRIVE_39_ACT")
	)
	(segment
		(start 88.486234 -57.83199)
		(end 84.664296 -57.83199)
		(width 0.127)
		(layer "F.Cu")
		(net "DRIVE_39_ACT")
	)
	(segment
		(start 98.86442 -51.183794)
		(end 108.869988 -41.178226)
		(width 0.127)
		(layer "F.Cu")
		(net "DRIVE_39_ACT")
	)
	(segment
		(start 84.534248 -51.183794)
		(end 98.86442 -51.183794)
		(width 0.127)
		(layer "F.Cu")
		(net "DRIVE_39_ACT")
	)
	(segment
		(start 90.034364 -59.38012)
		(end 88.486234 -57.83199)
		(width 0.127)
		(layer "F.Cu")
		(net "DRIVE_39_ACT")
	)
	(segment
		(start 99.0346 -58.7502)
		(end 97.524316 -58.7502)
		(width 0.127)
		(layer "F.Cu")
		(net "DRIVE_39_ACT")
	)
	(segment
		(start 146.540982 -17.842992)
		(end 146.540982 -17.7546)
		(width 0.127)
		(layer "F.Cu")
		(net "DRIVE_39_ACT")
	)
	(segment
		(start 99.283774 -58.999374)
		(end 99.0346 -58.7502)
		(width 0.127)
		(layer "F.Cu")
		(net "DRIVE_39_ACT")
	)
	(segment
		(start 97.524316 -58.7502)
		(end 96.894396 -59.38012)
		(width 0.127)
		(layer "F.Cu")
		(net "DRIVE_39_ACT")
	)
	(segment
		(start 146.540728 -9.459468)
		(end 147.200112 -8.800084)
		(width 0.127)
		(layer "F.Cu")
		(net "DRIVE_39_ACT")
	)
	(segment
		(start 100.499926 -59.500008)
		(end 99.999292 -58.999374)
		(width 0.127)
		(layer "F.Cu")
		(net "DRIVE_39_ACT")
	)
	(segment
		(start 83.282536 -56.45023)
		(end 83.282536 -52.435506)
		(width 0.127)
		(layer "F.Cu")
		(net "DRIVE_39_ACT")
	)
	(segment
		(start 83.282536 -52.435506)
		(end 84.534248 -51.183794)
		(width 0.127)
		(layer "F.Cu")
		(net "DRIVE_39_ACT")
	)
	(segment
		(start 99.999292 -58.999374)
		(end 99.283774 -58.999374)
		(width 0.127)
		(layer "F.Cu")
		(net "DRIVE_39_ACT")
	)
	(segment
		(start 123.205748 -41.178226)
		(end 146.540982 -17.842992)
		(width 0.127)
		(layer "F.Cu")
		(net "DRIVE_39_ACT")
	)
	(segment
		(start 113.897664 -41.178226)
		(end 123.205748 -41.178226)
		(width 0.127)
		(layer "F.Cu")
		(net "DRIVE_39_ACT")
	)
	(segment
		(start 146.540982 -17.7546)
		(end 146.540728 -17.754346)
		(width 0.127)
		(layer "F.Cu")
		(net "DRIVE_39_ACT")
	)
	(via
		(at 113.897664 -41.178226)
		(size 0.6604)
		(drill 0.3302)
		(layers "F.Cu" "B.Cu")
		(net "DRIVE_39_ACT")
	)
	(segment
		(start 108.837476 -40.492172)
		(end 115.943634 -40.492172)
		(width 0.127)
		(layer "F.Cu")
		(net "DRIVE_38_ACT")
	)
	(segment
		(start 98.834956 -50.494692)
		(end 108.837476 -40.492172)
		(width 0.127)
		(layer "F.Cu")
		(net "DRIVE_38_ACT")
	)
	(segment
		(start 94.691708 -50.494692)
		(end 98.834956 -50.494692)
		(width 0.127)
		(layer "F.Cu")
		(net "DRIVE_38_ACT")
	)
	(segment
		(start 94.12478 -50.347626)
		(end 94.544642 -50.347626)
		(width 0.127)
		(layer "F.Cu")
		(net "DRIVE_38_ACT")
	)
	(segment
		(start 146.032728 -17.63268)
		(end 146.032728 -8.56742)
		(width 0.127)
		(layer "F.Cu")
		(net "DRIVE_38_ACT")
	)
	(segment
		(start 115.943634 -40.492172)
		(end 123.173236 -40.492172)
		(width 0.127)
		(layer "F.Cu")
		(net "DRIVE_38_ACT")
	)
	(segment
		(start 105.499916 -60.500006)
		(end 105.999788 -60.000134)
		(width 0.127)
		(layer "F.Cu")
		(net "DRIVE_38_ACT")
	)
	(segment
		(start 146.032728 -8.56742)
		(end 147.200112 -7.400036)
		(width 0.127)
		(layer "F.Cu")
		(net "DRIVE_38_ACT")
	)
	(segment
		(start 94.544642 -50.347626)
		(end 94.691708 -50.494692)
		(width 0.127)
		(layer "F.Cu")
		(net "DRIVE_38_ACT")
	)
	(segment
		(start 123.173236 -40.492172)
		(end 146.032728 -17.63268)
		(width 0.127)
		(layer "F.Cu")
		(net "DRIVE_38_ACT")
	)
	(via
		(at 94.12478 -50.347626)
		(size 0.508)
		(drill 0.254)
		(layers "F.Cu" "B.Cu")
		(net "DRIVE_38_ACT")
	)
	(via
		(at 105.999788 -60.000134)
		(size 0.4572)
		(drill 0.2032)
		(layers "F.Cu" "B.Cu")
		(net "DRIVE_38_ACT")
	)
	(via
		(at 115.943634 -40.492172)
		(size 0.6604)
		(drill 0.3302)
		(layers "F.Cu" "B.Cu")
		(net "DRIVE_38_ACT")
	)
	(segment
		(start 94.12478 -52.078636)
		(end 94.751144 -52.705)
		(width 0.127)
		(layer "In5.Cu")
		(net "DRIVE_38_ACT")
	)
	(segment
		(start 94.12478 -50.347626)
		(end 94.12478 -52.078636)
		(width 0.127)
		(layer "In5.Cu")
		(net "DRIVE_38_ACT")
	)
	(segment
		(start 97.8662 -53.443886)
		(end 97.8662 -55.5752)
		(width 0.127)
		(layer "In5.Cu")
		(net "DRIVE_38_ACT")
	)
	(segment
		(start 97.127314 -52.705)
		(end 97.8662 -53.443886)
		(width 0.127)
		(layer "In5.Cu")
		(net "DRIVE_38_ACT")
	)
	(segment
		(start 97.8662 -55.5752)
		(end 98.883216 -56.592216)
		(width 0.127)
		(layer "In5.Cu")
		(net "DRIVE_38_ACT")
	)
	(segment
		(start 102.997762 -56.592216)
		(end 104.762046 -58.3565)
		(width 0.127)
		(layer "In5.Cu")
		(net "DRIVE_38_ACT")
	)
	(segment
		(start 104.980232 -58.3565)
		(end 105.999788 -59.376056)
		(width 0.127)
		(layer "In5.Cu")
		(net "DRIVE_38_ACT")
	)
	(segment
		(start 105.999788 -59.376056)
		(end 105.999788 -60.000134)
		(width 0.127)
		(layer "In5.Cu")
		(net "DRIVE_38_ACT")
	)
	(segment
		(start 98.883216 -56.592216)
		(end 102.997762 -56.592216)
		(width 0.127)
		(layer "In5.Cu")
		(net "DRIVE_38_ACT")
	)
	(segment
		(start 104.762046 -58.3565)
		(end 104.980232 -58.3565)
		(width 0.127)
		(layer "In5.Cu")
		(net "DRIVE_38_ACT")
	)
	(segment
		(start 94.751144 -52.705)
		(end 97.127314 -52.705)
		(width 0.127)
		(layer "In5.Cu")
		(net "DRIVE_38_ACT")
	)
	(segment
		(start 144.74063 -8.259572)
		(end 145.400014 -7.600188)
		(width 0.127)
		(layer "F.Cu")
		(net "DRIVE_37_ACT")
	)
	(segment
		(start 98.67265 -49.938432)
		(end 108.709206 -39.901876)
		(width 0.127)
		(layer "F.Cu")
		(net "DRIVE_37_ACT")
	)
	(segment
		(start 97.739708 -59.309)
		(end 97.122488 -59.92622)
		(width 0.127)
		(layer "F.Cu")
		(net "DRIVE_37_ACT")
	)
	(segment
		(start 97.122488 -59.92622)
		(end 89.80551 -59.92622)
		(width 0.127)
		(layer "F.Cu")
		(net "DRIVE_37_ACT")
	)
	(segment
		(start 123.044966 -39.901876)
		(end 144.74063 -18.206212)
		(width 0.127)
		(layer "F.Cu")
		(net "DRIVE_37_ACT")
	)
	(segment
		(start 108.709206 -39.901876)
		(end 118.132352 -39.901876)
		(width 0.127)
		(layer "F.Cu")
		(net "DRIVE_37_ACT")
	)
	(segment
		(start 88.21928 -58.33999)
		(end 84.45373 -58.33999)
		(width 0.127)
		(layer "F.Cu")
		(net "DRIVE_37_ACT")
	)
	(segment
		(start 93.927676 -49.818036)
		(end 96.040448 -49.818036)
		(width 0.127)
		(layer "F.Cu")
		(net "DRIVE_37_ACT")
	)
	(segment
		(start 99.499928 -59.500008)
		(end 99.106228 -59.500008)
		(width 0.127)
		(layer "F.Cu")
		(net "DRIVE_37_ACT")
	)
	(segment
		(start 98.91522 -59.309)
		(end 97.739708 -59.309)
		(width 0.127)
		(layer "F.Cu")
		(net "DRIVE_37_ACT")
	)
	(segment
		(start 84.366862 -50.632614)
		(end 93.113098 -50.632614)
		(width 0.127)
		(layer "F.Cu")
		(net "DRIVE_37_ACT")
	)
	(segment
		(start 118.132352 -39.901876)
		(end 123.044966 -39.901876)
		(width 0.127)
		(layer "F.Cu")
		(net "DRIVE_37_ACT")
	)
	(segment
		(start 82.774536 -52.22494)
		(end 84.366862 -50.632614)
		(width 0.127)
		(layer "F.Cu")
		(net "DRIVE_37_ACT")
	)
	(segment
		(start 89.80551 -59.92622)
		(end 88.21928 -58.33999)
		(width 0.127)
		(layer "F.Cu")
		(net "DRIVE_37_ACT")
	)
	(segment
		(start 99.106228 -59.500008)
		(end 98.91522 -59.309)
		(width 0.127)
		(layer "F.Cu")
		(net "DRIVE_37_ACT")
	)
	(segment
		(start 93.113098 -50.632614)
		(end 93.927676 -49.818036)
		(width 0.127)
		(layer "F.Cu")
		(net "DRIVE_37_ACT")
	)
	(segment
		(start 144.74063 -18.206212)
		(end 144.74063 -8.259572)
		(width 0.127)
		(layer "F.Cu")
		(net "DRIVE_37_ACT")
	)
	(segment
		(start 96.040448 -49.818036)
		(end 96.160844 -49.938432)
		(width 0.127)
		(layer "F.Cu")
		(net "DRIVE_37_ACT")
	)
	(segment
		(start 96.160844 -49.938432)
		(end 98.67265 -49.938432)
		(width 0.127)
		(layer "F.Cu")
		(net "DRIVE_37_ACT")
	)
	(segment
		(start 84.45373 -58.33999)
		(end 82.774536 -56.660796)
		(width 0.127)
		(layer "F.Cu")
		(net "DRIVE_37_ACT")
	)
	(segment
		(start 82.774536 -56.660796)
		(end 82.774536 -52.22494)
		(width 0.127)
		(layer "F.Cu")
		(net "DRIVE_37_ACT")
	)
	(via
		(at 118.132352 -39.901876)
		(size 0.6604)
		(drill 0.3302)
		(layers "F.Cu" "B.Cu")
		(net "DRIVE_37_ACT")
	)
	(segment
		(start 144.23263 -7.367524)
		(end 144.23263 -17.995646)
		(width 0.127)
		(layer "F.Cu")
		(net "DRIVE_36_ACT")
	)
	(segment
		(start 106.499914 -62.500002)
		(end 106.000042 -62.00013)
		(width 0.127)
		(layer "F.Cu")
		(net "DRIVE_36_ACT")
	)
	(segment
		(start 122.887232 -39.341044)
		(end 120.114314 -39.341044)
		(width 0.127)
		(layer "F.Cu")
		(net "DRIVE_36_ACT")
	)
	(segment
		(start 145.400014 -6.20014)
		(end 144.23263 -7.367524)
		(width 0.127)
		(layer "F.Cu")
		(net "DRIVE_36_ACT")
	)
	(segment
		(start 144.23263 -17.995646)
		(end 122.887232 -39.341044)
		(width 0.127)
		(layer "F.Cu")
		(net "DRIVE_36_ACT")
	)
	(segment
		(start 96.37141 -49.430432)
		(end 98.462084 -49.430432)
		(width 0.127)
		(layer "F.Cu")
		(net "DRIVE_36_ACT")
	)
	(segment
		(start 108.551472 -39.341044)
		(end 120.114314 -39.341044)
		(width 0.127)
		(layer "F.Cu")
		(net "DRIVE_36_ACT")
	)
	(segment
		(start 98.462084 -49.430432)
		(end 108.551472 -39.341044)
		(width 0.127)
		(layer "F.Cu")
		(net "DRIVE_36_ACT")
	)
	(via
		(at 106.000042 -62.00013)
		(size 0.4572)
		(drill 0.2032)
		(layers "F.Cu" "B.Cu")
		(net "DRIVE_36_ACT")
	)
	(via
		(at 96.37141 -49.430432)
		(size 0.508)
		(drill 0.254)
		(layers "F.Cu" "B.Cu")
		(net "DRIVE_36_ACT")
	)
	(via
		(at 120.114314 -39.341044)
		(size 0.6604)
		(drill 0.3302)
		(layers "F.Cu" "B.Cu")
		(net "DRIVE_36_ACT")
	)
	(segment
		(start 99.005136 -53.56225)
		(end 99.158552 -53.56225)
		(width 0.127)
		(layer "In5.Cu")
		(net "DRIVE_36_ACT")
	)
	(segment
		(start 99.603052 -54.160166)
		(end 100.01504 -54.572154)
		(width 0.127)
		(layer "In5.Cu")
		(net "DRIVE_36_ACT")
	)
	(segment
		(start 96.517206 -49.430432)
		(end 97.067624 -49.98085)
		(width 0.127)
		(layer "In5.Cu")
		(net "DRIVE_36_ACT")
	)
	(segment
		(start 96.37141 -49.430432)
		(end 96.517206 -49.430432)
		(width 0.127)
		(layer "In5.Cu")
		(net "DRIVE_36_ACT")
	)
	(segment
		(start 97.067624 -51.624738)
		(end 99.005136 -53.56225)
		(width 0.127)
		(layer "In5.Cu")
		(net "DRIVE_36_ACT")
	)
	(segment
		(start 99.603052 -54.00675)
		(end 99.603052 -54.160166)
		(width 0.127)
		(layer "In5.Cu")
		(net "DRIVE_36_ACT")
	)
	(segment
		(start 99.158552 -53.56225)
		(end 99.603052 -54.00675)
		(width 0.127)
		(layer "In5.Cu")
		(net "DRIVE_36_ACT")
	)
	(segment
		(start 104.487472 -54.891178)
		(end 104.487472 -57.294526)
		(width 0.127)
		(layer "In5.Cu")
		(net "DRIVE_36_ACT")
	)
	(segment
		(start 100.01504 -54.572154)
		(end 104.168448 -54.572154)
		(width 0.127)
		(layer "In5.Cu")
		(net "DRIVE_36_ACT")
	)
	(segment
		(start 104.487472 -57.294526)
		(end 106.393742 -59.200796)
		(width 0.127)
		(layer "In5.Cu")
		(net "DRIVE_36_ACT")
	)
	(segment
		(start 97.067624 -49.98085)
		(end 97.067624 -51.624738)
		(width 0.127)
		(layer "In5.Cu")
		(net "DRIVE_36_ACT")
	)
	(segment
		(start 106.393742 -61.60643)
		(end 106.000042 -62.00013)
		(width 0.127)
		(layer "In5.Cu")
		(net "DRIVE_36_ACT")
	)
	(segment
		(start 104.168448 -54.572154)
		(end 104.487472 -54.891178)
		(width 0.127)
		(layer "In5.Cu")
		(net "DRIVE_36_ACT")
	)
	(segment
		(start 106.393742 -59.200796)
		(end 106.393742 -61.60643)
		(width 0.127)
		(layer "In5.Cu")
		(net "DRIVE_36_ACT")
	)
	(segment
		(start 98.325178 -48.848772)
		(end 108.379006 -38.794944)
		(width 0.127)
		(layer "F.Cu")
		(net "DRIVE_35_ACT")
	)
	(segment
		(start 103.49992 -60.500006)
		(end 103.000048 -60.000134)
		(width 0.127)
		(layer "F.Cu")
		(net "DRIVE_35_ACT")
	)
	(segment
		(start 122.714766 -38.794944)
		(end 142.940786 -18.568924)
		(width 0.127)
		(layer "F.Cu")
		(net "DRIVE_35_ACT")
	)
	(segment
		(start 112.995964 -38.794944)
		(end 122.714766 -38.794944)
		(width 0.127)
		(layer "F.Cu")
		(net "DRIVE_35_ACT")
	)
	(segment
		(start 142.940786 -9.459468)
		(end 143.60017 -8.800084)
		(width 0.127)
		(layer "F.Cu")
		(net "DRIVE_35_ACT")
	)
	(segment
		(start 93.613732 -49.41316)
		(end 94.17812 -48.848772)
		(width 0.127)
		(layer "F.Cu")
		(net "DRIVE_35_ACT")
	)
	(segment
		(start 94.17812 -48.848772)
		(end 98.325178 -48.848772)
		(width 0.127)
		(layer "F.Cu")
		(net "DRIVE_35_ACT")
	)
	(segment
		(start 108.379006 -38.794944)
		(end 112.995964 -38.794944)
		(width 0.127)
		(layer "F.Cu")
		(net "DRIVE_35_ACT")
	)
	(segment
		(start 142.940786 -18.568924)
		(end 142.940786 -9.459468)
		(width 0.127)
		(layer "F.Cu")
		(net "DRIVE_35_ACT")
	)
	(via
		(at 103.000048 -60.000134)
		(size 0.4572)
		(drill 0.2032)
		(layers "F.Cu" "B.Cu")
		(net "DRIVE_35_ACT")
	)
	(via
		(at 112.995964 -38.794944)
		(size 0.6604)
		(drill 0.3302)
		(layers "F.Cu" "B.Cu")
		(net "DRIVE_35_ACT")
	)
	(via
		(at 93.613732 -49.41316)
		(size 0.508)
		(drill 0.254)
		(layers "F.Cu" "B.Cu")
		(net "DRIVE_35_ACT")
	)
	(segment
		(start 102.12451 -58.567574)
		(end 102.541832 -58.984896)
		(width 0.127)
		(layer "In5.Cu")
		(net "DRIVE_35_ACT")
	)
	(segment
		(start 98.978974 -58.567574)
		(end 102.12451 -58.567574)
		(width 0.127)
		(layer "In5.Cu")
		(net "DRIVE_35_ACT")
	)
	(segment
		(start 103.000048 -59.794648)
		(end 103.000048 -60.000134)
		(width 0.127)
		(layer "In5.Cu")
		(net "DRIVE_35_ACT")
	)
	(segment
		(start 102.541832 -58.984896)
		(end 102.541832 -59.336432)
		(width 0.127)
		(layer "In5.Cu")
		(net "DRIVE_35_ACT")
	)
	(segment
		(start 102.541832 -59.336432)
		(end 103.000048 -59.794648)
		(width 0.127)
		(layer "In5.Cu")
		(net "DRIVE_35_ACT")
	)
	(segment
		(start 93.10878 -49.926494)
		(end 93.10878 -52.69738)
		(width 0.127)
		(layer "In5.Cu")
		(net "DRIVE_35_ACT")
	)
	(segment
		(start 93.10878 -52.69738)
		(end 98.978974 -58.567574)
		(width 0.127)
		(layer "In5.Cu")
		(net "DRIVE_35_ACT")
	)
	(segment
		(start 93.230446 -49.796446)
		(end 93.230446 -49.804828)
		(width 0.127)
		(layer "In5.Cu")
		(net "DRIVE_35_ACT")
	)
	(segment
		(start 93.613732 -49.41316)
		(end 93.230446 -49.796446)
		(width 0.127)
		(layer "In5.Cu")
		(net "DRIVE_35_ACT")
	)
	(segment
		(start 93.230446 -49.804828)
		(end 93.10878 -49.926494)
		(width 0.127)
		(layer "In5.Cu")
		(net "DRIVE_35_ACT")
	)
	(segment
		(start 93.473016 -48.3235)
		(end 97.566734 -48.3235)
		(width 0.127)
		(layer "F.Cu")
		(net "DRIVE_34_ACT")
	)
	(segment
		(start 142.432786 -18.358358)
		(end 142.432786 -8.56742)
		(width 0.127)
		(layer "F.Cu")
		(net "DRIVE_34_ACT")
	)
	(segment
		(start 97.566734 -48.3235)
		(end 107.64139 -38.248844)
		(width 0.127)
		(layer "F.Cu")
		(net "DRIVE_34_ACT")
	)
	(segment
		(start 107.64139 -38.248844)
		(end 116.160804 -38.248844)
		(width 0.127)
		(layer "F.Cu")
		(net "DRIVE_34_ACT")
	)
	(segment
		(start 116.160804 -38.248844)
		(end 122.5423 -38.248844)
		(width 0.127)
		(layer "F.Cu")
		(net "DRIVE_34_ACT")
	)
	(segment
		(start 93.08084 -48.715676)
		(end 93.473016 -48.3235)
		(width 0.127)
		(layer "F.Cu")
		(net "DRIVE_34_ACT")
	)
	(segment
		(start 122.5423 -38.248844)
		(end 142.432786 -18.358358)
		(width 0.127)
		(layer "F.Cu")
		(net "DRIVE_34_ACT")
	)
	(segment
		(start 102.499922 -60.500006)
		(end 102.00005 -60.000134)
		(width 0.127)
		(layer "F.Cu")
		(net "DRIVE_34_ACT")
	)
	(segment
		(start 142.432786 -8.56742)
		(end 143.60017 -7.400036)
		(width 0.127)
		(layer "F.Cu")
		(net "DRIVE_34_ACT")
	)
	(via
		(at 116.160804 -38.248844)
		(size 0.6604)
		(drill 0.3302)
		(layers "F.Cu" "B.Cu")
		(net "DRIVE_34_ACT")
	)
	(via
		(at 102.00005 -60.000134)
		(size 0.4572)
		(drill 0.2032)
		(layers "F.Cu" "B.Cu")
		(net "DRIVE_34_ACT")
	)
	(via
		(at 93.08084 -48.715676)
		(size 0.508)
		(drill 0.254)
		(layers "F.Cu" "B.Cu")
		(net "DRIVE_34_ACT")
	)
	(segment
		(start 93.08084 -48.715676)
		(end 92.60078 -49.195736)
		(width 0.127)
		(layer "In5.Cu")
		(net "DRIVE_34_ACT")
	)
	(segment
		(start 92.60078 -49.195736)
		(end 92.60078 -52.907946)
		(width 0.127)
		(layer "In5.Cu")
		(net "DRIVE_34_ACT")
	)
	(segment
		(start 99.299268 -59.606434)
		(end 101.60635 -59.606434)
		(width 0.127)
		(layer "In5.Cu")
		(net "DRIVE_34_ACT")
	)
	(segment
		(start 92.60078 -52.907946)
		(end 99.299268 -59.606434)
		(width 0.127)
		(layer "In5.Cu")
		(net "DRIVE_34_ACT")
	)
	(segment
		(start 101.60635 -59.606434)
		(end 102.00005 -60.000134)
		(width 0.127)
		(layer "In5.Cu")
		(net "DRIVE_34_ACT")
	)
	(segment
		(start 99.499928 -60.500006)
		(end 89.66073 -60.500006)
		(width 0.127)
		(layer "F.Cu")
		(net "DRIVE_33_ACT")
	)
	(segment
		(start 141.140688 -8.259572)
		(end 141.140688 -18.93189)
		(width 0.127)
		(layer "F.Cu")
		(net "DRIVE_33_ACT")
	)
	(segment
		(start 84.344256 -49.936654)
		(end 91.125802 -49.936654)
		(width 0.127)
		(layer "F.Cu")
		(net "DRIVE_33_ACT")
	)
	(segment
		(start 96.888046 -47.8155)
		(end 107.04068 -37.662866)
		(width 0.127)
		(layer "F.Cu")
		(net "DRIVE_33_ACT")
	)
	(segment
		(start 82.266536 -57.374536)
		(end 82.266536 -52.014374)
		(width 0.127)
		(layer "F.Cu")
		(net "DRIVE_33_ACT")
	)
	(segment
		(start 93.246956 -47.8155)
		(end 96.888046 -47.8155)
		(width 0.127)
		(layer "F.Cu")
		(net "DRIVE_33_ACT")
	)
	(segment
		(start 83.73999 -58.84799)
		(end 82.266536 -57.374536)
		(width 0.127)
		(layer "F.Cu")
		(net "DRIVE_33_ACT")
	)
	(segment
		(start 88.008714 -58.84799)
		(end 83.73999 -58.84799)
		(width 0.127)
		(layer "F.Cu")
		(net "DRIVE_33_ACT")
	)
	(segment
		(start 91.125802 -49.936654)
		(end 93.246956 -47.8155)
		(width 0.127)
		(layer "F.Cu")
		(net "DRIVE_33_ACT")
	)
	(segment
		(start 107.04068 -37.662866)
		(end 110.257082 -37.662866)
		(width 0.127)
		(layer "F.Cu")
		(net "DRIVE_33_ACT")
	)
	(segment
		(start 141.140688 -18.93189)
		(end 122.409712 -37.662866)
		(width 0.127)
		(layer "F.Cu")
		(net "DRIVE_33_ACT")
	)
	(segment
		(start 141.800072 -7.600188)
		(end 141.140688 -8.259572)
		(width 0.127)
		(layer "F.Cu")
		(net "DRIVE_33_ACT")
	)
	(segment
		(start 122.409712 -37.662866)
		(end 110.257082 -37.662866)
		(width 0.127)
		(layer "F.Cu")
		(net "DRIVE_33_ACT")
	)
	(segment
		(start 82.266536 -52.014374)
		(end 84.344256 -49.936654)
		(width 0.127)
		(layer "F.Cu")
		(net "DRIVE_33_ACT")
	)
	(segment
		(start 89.66073 -60.500006)
		(end 88.008714 -58.84799)
		(width 0.127)
		(layer "F.Cu")
		(net "DRIVE_33_ACT")
	)
	(via
		(at 110.257082 -37.662866)
		(size 0.6604)
		(drill 0.3302)
		(layers "F.Cu" "B.Cu")
		(net "DRIVE_33_ACT")
	)
	(segment
		(start 118.108476 -37.116766)
		(end 122.237246 -37.116766)
		(width 0.127)
		(layer "F.Cu")
		(net "DRIVE_32_ACT")
	)
	(segment
		(start 96.764094 -47.167038)
		(end 106.814366 -37.116766)
		(width 0.127)
		(layer "F.Cu")
		(net "DRIVE_32_ACT")
	)
	(segment
		(start 100.499926 -60.500006)
		(end 99.96932 -59.9694)
		(width 0.127)
		(layer "F.Cu")
		(net "DRIVE_32_ACT")
	)
	(segment
		(start 106.814366 -37.116766)
		(end 118.108476 -37.116766)
		(width 0.127)
		(layer "F.Cu")
		(net "DRIVE_32_ACT")
	)
	(segment
		(start 92.498926 -47.844964)
		(end 93.176852 -47.167038)
		(width 0.127)
		(layer "F.Cu")
		(net "DRIVE_32_ACT")
	)
	(segment
		(start 122.237246 -37.116766)
		(end 140.632688 -18.721324)
		(width 0.127)
		(layer "F.Cu")
		(net "DRIVE_32_ACT")
	)
	(segment
		(start 93.176852 -47.167038)
		(end 96.764094 -47.167038)
		(width 0.127)
		(layer "F.Cu")
		(net "DRIVE_32_ACT")
	)
	(segment
		(start 99.96932 -59.9694)
		(end 98.806 -59.9694)
		(width 0.127)
		(layer "F.Cu")
		(net "DRIVE_32_ACT")
	)
	(segment
		(start 140.632688 -18.721324)
		(end 140.632688 -7.367524)
		(width 0.127)
		(layer "F.Cu")
		(net "DRIVE_32_ACT")
	)
	(segment
		(start 140.632688 -7.367524)
		(end 141.800072 -6.20014)
		(width 0.127)
		(layer "F.Cu")
		(net "DRIVE_32_ACT")
	)
	(via
		(at 98.806 -59.9694)
		(size 0.4572)
		(drill 0.2032)
		(layers "F.Cu" "B.Cu")
		(net "DRIVE_32_ACT")
	)
	(via
		(at 92.498926 -47.844964)
		(size 0.508)
		(drill 0.254)
		(layers "F.Cu" "B.Cu")
		(net "DRIVE_32_ACT")
	)
	(via
		(at 118.108476 -37.116766)
		(size 0.6604)
		(drill 0.3302)
		(layers "F.Cu" "B.Cu")
		(net "DRIVE_32_ACT")
	)
	(segment
		(start 92.498926 -47.844964)
		(end 92.09278 -48.25111)
		(width 0.127)
		(layer "In5.Cu")
		(net "DRIVE_32_ACT")
	)
	(segment
		(start 92.09278 -48.25111)
		(end 92.09278 -53.25618)
		(width 0.127)
		(layer "In5.Cu")
		(net "DRIVE_32_ACT")
	)
	(segment
		(start 92.09278 -53.25618)
		(end 98.806 -59.9694)
		(width 0.127)
		(layer "In5.Cu")
		(net "DRIVE_32_ACT")
	)
	(segment
		(start 91.638628 -38.708838)
		(end 93.81109 -36.536376)
		(width 0.127)
		(layer "F.Cu")
		(net "DRIVE_31_ACT")
	)
	(segment
		(start 121.992898 -36.536376)
		(end 123.700032 -34.829242)
		(width 0.127)
		(layer "F.Cu")
		(net "DRIVE_31_ACT")
	)
	(segment
		(start 92.01404 -46.82744)
		(end 90.894662 -45.708062)
		(width 0.127)
		(layer "F.Cu")
		(net "DRIVE_31_ACT")
	)
	(segment
		(start 107.499912 -63.5)
		(end 107.00004 -63.000128)
		(width 0.127)
		(layer "F.Cu")
		(net "DRIVE_31_ACT")
	)
	(segment
		(start 91.638628 -43.816778)
		(end 91.638628 -38.708838)
		(width 0.127)
		(layer "F.Cu")
		(net "DRIVE_31_ACT")
	)
	(segment
		(start 90.894662 -45.708062)
		(end 90.894662 -44.560744)
		(width 0.127)
		(layer "F.Cu")
		(net "DRIVE_31_ACT")
	)
	(segment
		(start 123.700032 -34.829242)
		(end 139.34059 -19.188684)
		(width 0.127)
		(layer "F.Cu")
		(net "DRIVE_31_ACT")
	)
	(segment
		(start 139.34059 -19.188684)
		(end 139.34059 -9.459468)
		(width 0.127)
		(layer "F.Cu")
		(net "DRIVE_31_ACT")
	)
	(segment
		(start 93.81109 -36.536376)
		(end 121.992898 -36.536376)
		(width 0.127)
		(layer "F.Cu")
		(net "DRIVE_31_ACT")
	)
	(segment
		(start 139.34059 -9.459468)
		(end 139.999974 -8.800084)
		(width 0.127)
		(layer "F.Cu")
		(net "DRIVE_31_ACT")
	)
	(segment
		(start 90.894662 -44.560744)
		(end 91.638628 -43.816778)
		(width 0.127)
		(layer "F.Cu")
		(net "DRIVE_31_ACT")
	)
	(via
		(at 123.700032 -34.829242)
		(size 0.6604)
		(drill 0.3302)
		(layers "F.Cu" "B.Cu")
		(net "DRIVE_31_ACT")
	)
	(via
		(at 107.00004 -63.000128)
		(size 0.4572)
		(drill 0.2032)
		(layers "F.Cu" "B.Cu")
		(net "DRIVE_31_ACT")
	)
	(via
		(at 92.01404 -46.82744)
		(size 0.508)
		(drill 0.254)
		(layers "F.Cu" "B.Cu")
		(net "DRIVE_31_ACT")
	)
	(segment
		(start 100.45192 -53.048408)
		(end 101.009958 -53.606446)
		(width 0.127)
		(layer "In5.Cu")
		(net "DRIVE_31_ACT")
	)
	(segment
		(start 107.39374 -62.606428)
		(end 107.00004 -63.000128)
		(width 0.127)
		(layer "In5.Cu")
		(net "DRIVE_31_ACT")
	)
	(segment
		(start 95.804228 -47.621698)
		(end 99.552252 -51.369722)
		(width 0.127)
		(layer "In5.Cu")
		(net "DRIVE_31_ACT")
	)
	(segment
		(start 101.009958 -53.606446)
		(end 105.163366 -53.606446)
		(width 0.127)
		(layer "In5.Cu")
		(net "DRIVE_31_ACT")
	)
	(segment
		(start 105.163366 -53.606446)
		(end 105.52557 -53.96865)
		(width 0.127)
		(layer "In5.Cu")
		(net "DRIVE_31_ACT")
	)
	(segment
		(start 92.01404 -46.82744)
		(end 93.538802 -46.82744)
		(width 0.127)
		(layer "In5.Cu")
		(net "DRIVE_31_ACT")
	)
	(segment
		(start 94.33306 -47.621698)
		(end 95.804228 -47.621698)
		(width 0.127)
		(layer "In5.Cu")
		(net "DRIVE_31_ACT")
	)
	(segment
		(start 105.52557 -57.08269)
		(end 105.937304 -57.494424)
		(width 0.127)
		(layer "In5.Cu")
		(net "DRIVE_31_ACT")
	)
	(segment
		(start 105.52557 -53.96865)
		(end 105.52557 -57.08269)
		(width 0.127)
		(layer "In5.Cu")
		(net "DRIVE_31_ACT")
	)
	(segment
		(start 107.39374 -57.836816)
		(end 107.39374 -62.606428)
		(width 0.127)
		(layer "In5.Cu")
		(net "DRIVE_31_ACT")
	)
	(segment
		(start 99.886516 -52.483004)
		(end 100.039932 -52.483004)
		(width 0.127)
		(layer "In5.Cu")
		(net "DRIVE_31_ACT")
	)
	(segment
		(start 100.039932 -52.483004)
		(end 100.45192 -52.894992)
		(width 0.127)
		(layer "In5.Cu")
		(net "DRIVE_31_ACT")
	)
	(segment
		(start 105.937304 -57.494424)
		(end 107.051348 -57.494424)
		(width 0.127)
		(layer "In5.Cu")
		(net "DRIVE_31_ACT")
	)
	(segment
		(start 93.538802 -46.82744)
		(end 94.33306 -47.621698)
		(width 0.127)
		(layer "In5.Cu")
		(net "DRIVE_31_ACT")
	)
	(segment
		(start 99.552252 -51.369722)
		(end 99.552252 -52.14874)
		(width 0.127)
		(layer "In5.Cu")
		(net "DRIVE_31_ACT")
	)
	(segment
		(start 99.552252 -52.14874)
		(end 99.886516 -52.483004)
		(width 0.127)
		(layer "In5.Cu")
		(net "DRIVE_31_ACT")
	)
	(segment
		(start 107.051348 -57.494424)
		(end 107.39374 -57.836816)
		(width 0.127)
		(layer "In5.Cu")
		(net "DRIVE_31_ACT")
	)
	(segment
		(start 100.45192 -52.894992)
		(end 100.45192 -53.048408)
		(width 0.127)
		(layer "In5.Cu")
		(net "DRIVE_31_ACT")
	)
	(segment
		(start 93.638624 -35.990276)
		(end 91.130628 -38.498272)
		(width 0.127)
		(layer "F.Cu")
		(net "DRIVE_30_ACT")
	)
	(segment
		(start 105.499916 -61.49975)
		(end 105.000298 -61.000132)
		(width 0.127)
		(layer "F.Cu")
		(net "DRIVE_30_ACT")
	)
	(segment
		(start 138.83259 -18.924016)
		(end 138.83259 -8.56742)
		(width 0.127)
		(layer "F.Cu")
		(net "DRIVE_30_ACT")
	)
	(segment
		(start 124.694442 -33.062164)
		(end 121.76633 -35.990276)
		(width 0.127)
		(layer "F.Cu")
		(net "DRIVE_30_ACT")
	)
	(segment
		(start 121.76633 -35.990276)
		(end 93.638624 -35.990276)
		(width 0.127)
		(layer "F.Cu")
		(net "DRIVE_30_ACT")
	)
	(segment
		(start 89.952322 -44.784518)
		(end 89.952322 -46.593506)
		(width 0.127)
		(layer "F.Cu")
		(net "DRIVE_30_ACT")
	)
	(segment
		(start 124.694442 -33.062164)
		(end 138.83259 -18.924016)
		(width 0.127)
		(layer "F.Cu")
		(net "DRIVE_30_ACT")
	)
	(segment
		(start 91.130628 -38.498272)
		(end 91.130628 -43.606212)
		(width 0.127)
		(layer "F.Cu")
		(net "DRIVE_30_ACT")
	)
	(segment
		(start 91.130628 -43.606212)
		(end 89.952322 -44.784518)
		(width 0.127)
		(layer "F.Cu")
		(net "DRIVE_30_ACT")
	)
	(segment
		(start 138.83259 -8.56742)
		(end 139.999974 -7.400036)
		(width 0.127)
		(layer "F.Cu")
		(net "DRIVE_30_ACT")
	)
	(segment
		(start 105.499916 -61.500004)
		(end 105.499916 -61.49975)
		(width 0.127)
		(layer "F.Cu")
		(net "DRIVE_30_ACT")
	)
	(via
		(at 89.952322 -46.593506)
		(size 0.508)
		(drill 0.254)
		(layers "F.Cu" "B.Cu")
		(net "DRIVE_30_ACT")
	)
	(via
		(at 124.694442 -33.062164)
		(size 0.6604)
		(drill 0.3302)
		(layers "F.Cu" "B.Cu")
		(net "DRIVE_30_ACT")
	)
	(via
		(at 105.000298 -61.000132)
		(size 0.4572)
		(drill 0.2032)
		(layers "F.Cu" "B.Cu")
		(net "DRIVE_30_ACT")
	)
	(segment
		(start 89.952322 -46.593506)
		(end 90.694256 -47.33544)
		(width 0.127)
		(layer "In5.Cu")
		(net "DRIVE_30_ACT")
	)
	(segment
		(start 104.541066 -58.984134)
		(end 104.541066 -60.065666)
		(width 0.127)
		(layer "In5.Cu")
		(net "DRIVE_30_ACT")
	)
	(segment
		(start 95.3516 -54.1528)
		(end 97.102676 -54.1528)
		(width 0.127)
		(layer "In5.Cu")
		(net "DRIVE_30_ACT")
	)
	(segment
		(start 97.280476 -54.3306)
		(end 97.280476 -55.878476)
		(width 0.127)
		(layer "In5.Cu")
		(net "DRIVE_30_ACT")
	)
	(segment
		(start 99.008438 -57.606438)
		(end 103.16337 -57.606438)
		(width 0.127)
		(layer "In5.Cu")
		(net "DRIVE_30_ACT")
	)
	(segment
		(start 93.61678 -52.41798)
		(end 95.3516 -54.1528)
		(width 0.127)
		(layer "In5.Cu")
		(net "DRIVE_30_ACT")
	)
	(segment
		(start 90.694256 -47.33544)
		(end 92.96781 -47.33544)
		(width 0.127)
		(layer "In5.Cu")
		(net "DRIVE_30_ACT")
	)
	(segment
		(start 94.121986 -48.489616)
		(end 94.121986 -49.631854)
		(width 0.127)
		(layer "In5.Cu")
		(net "DRIVE_30_ACT")
	)
	(segment
		(start 103.16337 -57.606438)
		(end 104.541066 -58.984134)
		(width 0.127)
		(layer "In5.Cu")
		(net "DRIVE_30_ACT")
	)
	(segment
		(start 105.000298 -60.524898)
		(end 105.000298 -61.000132)
		(width 0.127)
		(layer "In5.Cu")
		(net "DRIVE_30_ACT")
	)
	(segment
		(start 92.96781 -47.33544)
		(end 94.121986 -48.489616)
		(width 0.127)
		(layer "In5.Cu")
		(net "DRIVE_30_ACT")
	)
	(segment
		(start 97.102676 -54.1528)
		(end 97.280476 -54.3306)
		(width 0.127)
		(layer "In5.Cu")
		(net "DRIVE_30_ACT")
	)
	(segment
		(start 97.280476 -55.878476)
		(end 99.008438 -57.606438)
		(width 0.127)
		(layer "In5.Cu")
		(net "DRIVE_30_ACT")
	)
	(segment
		(start 93.61678 -50.13706)
		(end 93.61678 -52.41798)
		(width 0.127)
		(layer "In5.Cu")
		(net "DRIVE_30_ACT")
	)
	(segment
		(start 94.121986 -49.631854)
		(end 93.61678 -50.13706)
		(width 0.127)
		(layer "In5.Cu")
		(net "DRIVE_30_ACT")
	)
	(segment
		(start 104.541066 -60.065666)
		(end 105.000298 -60.524898)
		(width 0.127)
		(layer "In5.Cu")
		(net "DRIVE_30_ACT")
	)
	(segment
		(start 75.02779 -25.457658)
		(end 77.485494 -25.457658)
		(width 0.127)
		(layer "F.Cu")
		(net "DRIVE_3_ACT")
	)
	(segment
		(start 118.400068 -8.800084)
		(end 117.75694 -9.443212)
		(width 0.127)
		(layer "F.Cu")
		(net "DRIVE_3_ACT")
	)
	(segment
		(start 116.032026 -22.479254)
		(end 116.031772 -22.479)
		(width 0.127)
		(layer "F.Cu")
		(net "DRIVE_3_ACT")
	)
	(segment
		(start 116.584222 -22.479254)
		(end 116.032026 -22.479254)
		(width 0.127)
		(layer "F.Cu")
		(net "DRIVE_3_ACT")
	)
	(segment
		(start 117.75694 -21.306536)
		(end 116.584222 -22.479254)
		(width 0.127)
		(layer "F.Cu")
		(net "DRIVE_3_ACT")
	)
	(segment
		(start 109.499908 -72.500236)
		(end 109.99978 -73.000108)
		(width 0.127)
		(layer "F.Cu")
		(net "DRIVE_3_ACT")
	)
	(segment
		(start 116.031772 -22.479)
		(end 80.464152 -22.479)
		(width 0.127)
		(layer "F.Cu")
		(net "DRIVE_3_ACT")
	)
	(segment
		(start 77.485494 -25.457658)
		(end 77.87513 -25.068022)
		(width 0.127)
		(layer "F.Cu")
		(net "DRIVE_3_ACT")
	)
	(segment
		(start 80.464152 -22.479)
		(end 77.87513 -25.068022)
		(width 0.127)
		(layer "F.Cu")
		(net "DRIVE_3_ACT")
	)
	(segment
		(start 117.75694 -9.443212)
		(end 117.75694 -21.306536)
		(width 0.127)
		(layer "F.Cu")
		(net "DRIVE_3_ACT")
	)
	(via
		(at 109.99978 -73.000108)
		(size 0.4572)
		(drill 0.2032)
		(layers "F.Cu" "B.Cu")
		(net "DRIVE_3_ACT")
	)
	(via
		(at 77.87513 -25.068022)
		(size 0.6604)
		(drill 0.3302)
		(layers "F.Cu" "B.Cu")
		(net "DRIVE_3_ACT")
	)
	(via
		(at 75.02779 -25.457658)
		(size 0.508)
		(drill 0.254)
		(layers "F.Cu" "B.Cu")
		(net "DRIVE_3_ACT")
	)
	(segment
		(start 80.460088 -27.34945)
		(end 80.460088 -30.19679)
		(width 0.127)
		(layer "In5.Cu")
		(net "DRIVE_3_ACT")
	)
	(segment
		(start 81.864454 -59.296808)
		(end 85.8774 -63.309754)
		(width 0.127)
		(layer "In5.Cu")
		(net "DRIVE_3_ACT")
	)
	(segment
		(start 78.568296 -25.457658)
		(end 80.460088 -27.34945)
		(width 0.127)
		(layer "In5.Cu")
		(net "DRIVE_3_ACT")
	)
	(segment
		(start 92.425266 -71.53529)
		(end 108.534962 -71.53529)
		(width 0.127)
		(layer "In5.Cu")
		(net "DRIVE_3_ACT")
	)
	(segment
		(start 81.864454 -39.765224)
		(end 81.864454 -59.296808)
		(width 0.127)
		(layer "In5.Cu")
		(net "DRIVE_3_ACT")
	)
	(segment
		(start 75.02779 -25.457658)
		(end 78.568296 -25.457658)
		(width 0.127)
		(layer "In5.Cu")
		(net "DRIVE_3_ACT")
	)
	(segment
		(start 80.97012 -30.706822)
		(end 80.97012 -38.87089)
		(width 0.127)
		(layer "In5.Cu")
		(net "DRIVE_3_ACT")
	)
	(segment
		(start 80.97012 -38.87089)
		(end 81.864454 -39.765224)
		(width 0.127)
		(layer "In5.Cu")
		(net "DRIVE_3_ACT")
	)
	(segment
		(start 108.534962 -71.53529)
		(end 109.99978 -73.000108)
		(width 0.127)
		(layer "In5.Cu")
		(net "DRIVE_3_ACT")
	)
	(segment
		(start 85.8774 -64.987424)
		(end 92.425266 -71.53529)
		(width 0.127)
		(layer "In5.Cu")
		(net "DRIVE_3_ACT")
	)
	(segment
		(start 80.460088 -30.19679)
		(end 80.97012 -30.706822)
		(width 0.127)
		(layer "In5.Cu")
		(net "DRIVE_3_ACT")
	)
	(segment
		(start 85.8774 -63.309754)
		(end 85.8774 -64.987424)
		(width 0.127)
		(layer "In5.Cu")
		(net "DRIVE_3_ACT")
	)
	(segment
		(start 93.466158 -35.444176)
		(end 90.622628 -38.287706)
		(width 0.127)
		(layer "F.Cu")
		(net "DRIVE_29_ACT")
	)
	(segment
		(start 137.540746 -8.259572)
		(end 138.20013 -7.600188)
		(width 0.127)
		(layer "F.Cu")
		(net "DRIVE_29_ACT")
	)
	(segment
		(start 121.539762 -35.444176)
		(end 93.466158 -35.444176)
		(width 0.127)
		(layer "F.Cu")
		(net "DRIVE_29_ACT")
	)
	(segment
		(start 90.622628 -38.287706)
		(end 90.622628 -43.395646)
		(width 0.127)
		(layer "F.Cu")
		(net "DRIVE_29_ACT")
	)
	(segment
		(start 137.540746 -19.443192)
		(end 137.540746 -8.259572)
		(width 0.127)
		(layer "F.Cu")
		(net "DRIVE_29_ACT")
	)
	(segment
		(start 125.595888 -31.38805)
		(end 137.540746 -19.443192)
		(width 0.127)
		(layer "F.Cu")
		(net "DRIVE_29_ACT")
	)
	(segment
		(start 125.595888 -31.38805)
		(end 121.539762 -35.444176)
		(width 0.127)
		(layer "F.Cu")
		(net "DRIVE_29_ACT")
	)
	(segment
		(start 103.49992 -61.500004)
		(end 103.000048 -61.000132)
		(width 0.127)
		(layer "F.Cu")
		(net "DRIVE_29_ACT")
	)
	(segment
		(start 89.337642 -44.680632)
		(end 89.337642 -45.338746)
		(width 0.127)
		(layer "F.Cu")
		(net "DRIVE_29_ACT")
	)
	(segment
		(start 90.622628 -43.395646)
		(end 89.337642 -44.680632)
		(width 0.127)
		(layer "F.Cu")
		(net "DRIVE_29_ACT")
	)
	(via
		(at 125.595888 -31.38805)
		(size 0.6604)
		(drill 0.3302)
		(layers "F.Cu" "B.Cu")
		(net "DRIVE_29_ACT")
	)
	(via
		(at 103.000048 -61.000132)
		(size 0.4572)
		(drill 0.2032)
		(layers "F.Cu" "B.Cu")
		(net "DRIVE_29_ACT")
	)
	(via
		(at 89.337642 -45.338746)
		(size 0.508)
		(drill 0.254)
		(layers "F.Cu" "B.Cu")
		(net "DRIVE_29_ACT")
	)
	(segment
		(start 89.337642 -45.338746)
		(end 89.337642 -48.622458)
		(width 0.127)
		(layer "In5.Cu")
		(net "DRIVE_29_ACT")
	)
	(segment
		(start 98.683064 -60.6044)
		(end 102.604316 -60.6044)
		(width 0.127)
		(layer "In5.Cu")
		(net "DRIVE_29_ACT")
	)
	(segment
		(start 91.58478 -53.506116)
		(end 98.683064 -60.6044)
		(width 0.127)
		(layer "In5.Cu")
		(net "DRIVE_29_ACT")
	)
	(segment
		(start 91.58478 -50.869596)
		(end 91.58478 -53.506116)
		(width 0.127)
		(layer "In5.Cu")
		(net "DRIVE_29_ACT")
	)
	(segment
		(start 89.337642 -48.622458)
		(end 91.58478 -50.869596)
		(width 0.127)
		(layer "In5.Cu")
		(net "DRIVE_29_ACT")
	)
	(segment
		(start 102.604316 -60.6044)
		(end 103.000048 -61.000132)
		(width 0.127)
		(layer "In5.Cu")
		(net "DRIVE_29_ACT")
	)
	(segment
		(start 89.308686 -61.011816)
		(end 88.976962 -60.680092)
		(width 0.127)
		(layer "F.Cu")
		(net "DRIVE_28_ACT")
	)
	(segment
		(start 87.69096 -59.39409)
		(end 83.39709 -59.39409)
		(width 0.127)
		(layer "F.Cu")
		(net "DRIVE_28_ACT")
	)
	(segment
		(start 90.114374 -38.077394)
		(end 93.255592 -34.936176)
		(width 0.127)
		(layer "F.Cu")
		(net "DRIVE_28_ACT")
	)
	(segment
		(start 100.011738 -61.011816)
		(end 89.308686 -61.011816)
		(width 0.127)
		(layer "F.Cu")
		(net "DRIVE_28_ACT")
	)
	(segment
		(start 90.114374 -38.498018)
		(end 90.114374 -38.077394)
		(width 0.127)
		(layer "F.Cu")
		(net "DRIVE_28_ACT")
	)
	(segment
		(start 88.976962 -60.680092)
		(end 87.69096 -59.39409)
		(width 0.127)
		(layer "F.Cu")
		(net "DRIVE_28_ACT")
	)
	(segment
		(start 137.032746 -19.127216)
		(end 137.032746 -7.367524)
		(width 0.127)
		(layer "F.Cu")
		(net "DRIVE_28_ACT")
	)
	(segment
		(start 100.499926 -61.500004)
		(end 100.011738 -61.011816)
		(width 0.127)
		(layer "F.Cu")
		(net "DRIVE_28_ACT")
	)
	(segment
		(start 81.758536 -51.541172)
		(end 90.114628 -43.18508)
		(width 0.127)
		(layer "F.Cu")
		(net "DRIVE_28_ACT")
	)
	(segment
		(start 83.39709 -59.39409)
		(end 81.758536 -57.755536)
		(width 0.127)
		(layer "F.Cu")
		(net "DRIVE_28_ACT")
	)
	(segment
		(start 121.223786 -34.936176)
		(end 137.032746 -19.127216)
		(width 0.127)
		(layer "F.Cu")
		(net "DRIVE_28_ACT")
	)
	(segment
		(start 90.114628 -38.498272)
		(end 90.114374 -38.498018)
		(width 0.127)
		(layer "F.Cu")
		(net "DRIVE_28_ACT")
	)
	(segment
		(start 81.758536 -57.755536)
		(end 81.758536 -51.541172)
		(width 0.127)
		(layer "F.Cu")
		(net "DRIVE_28_ACT")
	)
	(segment
		(start 137.032746 -7.367524)
		(end 138.20013 -6.20014)
		(width 0.127)
		(layer "F.Cu")
		(net "DRIVE_28_ACT")
	)
	(segment
		(start 93.255592 -34.936176)
		(end 121.223786 -34.936176)
		(width 0.127)
		(layer "F.Cu")
		(net "DRIVE_28_ACT")
	)
	(segment
		(start 90.114628 -43.18508)
		(end 90.114628 -38.498272)
		(width 0.127)
		(layer "F.Cu")
		(net "DRIVE_28_ACT")
	)
	(via
		(at 88.976962 -60.680092)
		(size 0.6604)
		(drill 0.3302)
		(layers "F.Cu" "B.Cu")
		(net "DRIVE_28_ACT")
	)
	(segment
		(start 91.186 -34.29)
		(end 121.151396 -34.29)
		(width 0.127)
		(layer "F.Cu")
		(net "DRIVE_27_ACT")
	)
	(segment
		(start 135.740902 -19.700494)
		(end 135.740902 -9.459214)
		(width 0.127)
		(layer "F.Cu")
		(net "DRIVE_27_ACT")
	)
	(segment
		(start 121.151396 -34.29)
		(end 135.740902 -19.700494)
		(width 0.127)
		(layer "F.Cu")
		(net "DRIVE_27_ACT")
	)
	(segment
		(start 102.499922 -61.500004)
		(end 102.00005 -61.000132)
		(width 0.127)
		(layer "F.Cu")
		(net "DRIVE_27_ACT")
	)
	(segment
		(start 86.845902 -36.842446)
		(end 87.486236 -36.842446)
		(width 0.127)
		(layer "F.Cu")
		(net "DRIVE_27_ACT")
	)
	(segment
		(start 89.845388 -34.417)
		(end 89.972388 -34.29)
		(width 0.127)
		(layer "F.Cu")
		(net "DRIVE_27_ACT")
	)
	(segment
		(start 89.845388 -34.483294)
		(end 89.845388 -34.417)
		(width 0.127)
		(layer "F.Cu")
		(net "DRIVE_27_ACT")
	)
	(segment
		(start 135.740902 -9.459214)
		(end 136.400032 -8.800084)
		(width 0.127)
		(layer "F.Cu")
		(net "DRIVE_27_ACT")
	)
	(segment
		(start 89.972388 -34.29)
		(end 91.186 -34.29)
		(width 0.127)
		(layer "F.Cu")
		(net "DRIVE_27_ACT")
	)
	(segment
		(start 87.486236 -36.842446)
		(end 89.845388 -34.483294)
		(width 0.127)
		(layer "F.Cu")
		(net "DRIVE_27_ACT")
	)
	(via
		(at 102.00005 -61.000132)
		(size 0.4572)
		(drill 0.2032)
		(layers "F.Cu" "B.Cu")
		(net "DRIVE_27_ACT")
	)
	(via
		(at 86.845902 -36.842446)
		(size 0.508)
		(drill 0.254)
		(layers "F.Cu" "B.Cu")
		(net "DRIVE_27_ACT")
	)
	(via
		(at 91.186 -34.29)
		(size 0.6604)
		(drill 0.3302)
		(layers "F.Cu" "B.Cu")
		(net "DRIVE_27_ACT")
	)
	(segment
		(start 91.07678 -51.322478)
		(end 87.853266 -48.098964)
		(width 0.127)
		(layer "In5.Cu")
		(net "DRIVE_27_ACT")
	)
	(segment
		(start 101.60635 -61.393832)
		(end 98.75393 -61.393832)
		(width 0.127)
		(layer "In5.Cu")
		(net "DRIVE_27_ACT")
	)
	(segment
		(start 98.75393 -61.393832)
		(end 91.07678 -53.716682)
		(width 0.127)
		(layer "In5.Cu")
		(net "DRIVE_27_ACT")
	)
	(segment
		(start 87.853266 -48.098964)
		(end 87.853266 -37.84981)
		(width 0.127)
		(layer "In5.Cu")
		(net "DRIVE_27_ACT")
	)
	(segment
		(start 87.853266 -37.84981)
		(end 86.845902 -36.842446)
		(width 0.127)
		(layer "In5.Cu")
		(net "DRIVE_27_ACT")
	)
	(segment
		(start 91.07678 -53.716682)
		(end 91.07678 -51.322478)
		(width 0.127)
		(layer "In5.Cu")
		(net "DRIVE_27_ACT")
	)
	(segment
		(start 102.00005 -61.000132)
		(end 101.60635 -61.393832)
		(width 0.127)
		(layer "In5.Cu")
		(net "DRIVE_27_ACT")
	)
	(segment
		(start 106.499914 -63.5)
		(end 106.000042 -63.000128)
		(width 0.127)
		(layer "F.Cu")
		(net "DRIVE_26_ACT")
	)
	(segment
		(start 84.622132 -34.043112)
		(end 84.996274 -33.66897)
		(width 0.127)
		(layer "F.Cu")
		(net "DRIVE_26_ACT")
	)
	(segment
		(start 121.05386 -33.66897)
		(end 135.232648 -19.490182)
		(width 0.127)
		(layer "F.Cu")
		(net "DRIVE_26_ACT")
	)
	(segment
		(start 83.185 -34.043112)
		(end 84.622132 -34.043112)
		(width 0.127)
		(layer "F.Cu")
		(net "DRIVE_26_ACT")
	)
	(segment
		(start 81.546954 -34.043112)
		(end 83.185 -34.043112)
		(width 0.127)
		(layer "F.Cu")
		(net "DRIVE_26_ACT")
	)
	(segment
		(start 135.232648 -8.56742)
		(end 136.400032 -7.400036)
		(width 0.127)
		(layer "F.Cu")
		(net "DRIVE_26_ACT")
	)
	(segment
		(start 135.232648 -19.490182)
		(end 135.232648 -8.56742)
		(width 0.127)
		(layer "F.Cu")
		(net "DRIVE_26_ACT")
	)
	(segment
		(start 84.996274 -33.66897)
		(end 121.05386 -33.66897)
		(width 0.127)
		(layer "F.Cu")
		(net "DRIVE_26_ACT")
	)
	(via
		(at 106.000042 -63.000128)
		(size 0.4572)
		(drill 0.2032)
		(layers "F.Cu" "B.Cu")
		(net "DRIVE_26_ACT")
	)
	(via
		(at 81.546954 -34.043112)
		(size 0.508)
		(drill 0.254)
		(layers "F.Cu" "B.Cu")
		(net "DRIVE_26_ACT")
	)
	(via
		(at 83.185 -34.043112)
		(size 0.6604)
		(drill 0.3302)
		(layers "F.Cu" "B.Cu")
		(net "DRIVE_26_ACT")
	)
	(segment
		(start 82.372454 -39.554658)
		(end 82.372454 -58.69686)
		(width 0.127)
		(layer "In5.Cu")
		(net "DRIVE_26_ACT")
	)
	(segment
		(start 107.006136 -63.4492)
		(end 106.449114 -63.4492)
		(width 0.127)
		(layer "In5.Cu")
		(net "DRIVE_26_ACT")
	)
	(segment
		(start 105.163366 -68.393818)
		(end 105.393744 -68.16344)
		(width 0.127)
		(layer "In5.Cu")
		(net "DRIVE_26_ACT")
	)
	(segment
		(start 81.546954 -34.043112)
		(end 81.546954 -38.729158)
		(width 0.127)
		(layer "In5.Cu")
		(net "DRIVE_26_ACT")
	)
	(segment
		(start 107.39374 -63.836804)
		(end 107.006136 -63.4492)
		(width 0.127)
		(layer "In5.Cu")
		(net "DRIVE_26_ACT")
	)
	(segment
		(start 105.393744 -68.16344)
		(end 105.393744 -68.049394)
		(width 0.127)
		(layer "In5.Cu")
		(net "DRIVE_26_ACT")
	)
	(segment
		(start 92.069412 -68.393818)
		(end 105.163366 -68.393818)
		(width 0.127)
		(layer "In5.Cu")
		(net "DRIVE_26_ACT")
	)
	(segment
		(start 105.393744 -68.049394)
		(end 107.049316 -66.393822)
		(width 0.127)
		(layer "In5.Cu")
		(net "DRIVE_26_ACT")
	)
	(segment
		(start 107.049316 -66.393822)
		(end 107.163362 -66.393822)
		(width 0.127)
		(layer "In5.Cu")
		(net "DRIVE_26_ACT")
	)
	(segment
		(start 106.449114 -63.4492)
		(end 106.000042 -63.000128)
		(width 0.127)
		(layer "In5.Cu")
		(net "DRIVE_26_ACT")
	)
	(segment
		(start 107.163362 -66.393822)
		(end 107.39374 -66.163444)
		(width 0.127)
		(layer "In5.Cu")
		(net "DRIVE_26_ACT")
	)
	(segment
		(start 82.372454 -58.69686)
		(end 92.069412 -68.393818)
		(width 0.127)
		(layer "In5.Cu")
		(net "DRIVE_26_ACT")
	)
	(segment
		(start 107.39374 -66.163444)
		(end 107.39374 -63.836804)
		(width 0.127)
		(layer "In5.Cu")
		(net "DRIVE_26_ACT")
	)
	(segment
		(start 81.546954 -38.729158)
		(end 82.372454 -39.554658)
		(width 0.127)
		(layer "In5.Cu")
		(net "DRIVE_26_ACT")
	)
	(segment
		(start 120.843294 -33.16097)
		(end 133.858 -20.146264)
		(width 0.127)
		(layer "F.Cu")
		(net "DRIVE_25_ACT")
	)
	(segment
		(start 98.90252 -61.500004)
		(end 99.499928 -61.500004)
		(width 0.127)
		(layer "F.Cu")
		(net "DRIVE_25_ACT")
	)
	(segment
		(start 81.242154 -34.456878)
		(end 81.038954 -34.253678)
		(width 0.127)
		(layer "F.Cu")
		(net "DRIVE_25_ACT")
	)
	(segment
		(start 83.1342 -60.0202)
		(end 81.242154 -58.128154)
		(width 0.127)
		(layer "F.Cu")
		(net "DRIVE_25_ACT")
	)
	(segment
		(start 81.038954 -34.253678)
		(end 81.038954 -33.832546)
		(width 0.127)
		(layer "F.Cu")
		(net "DRIVE_25_ACT")
	)
	(segment
		(start 98.807524 -61.595)
		(end 98.90252 -61.500004)
		(width 0.127)
		(layer "F.Cu")
		(net "DRIVE_25_ACT")
	)
	(segment
		(start 133.9596 -19.990562)
		(end 133.9596 -8.240776)
		(width 0.127)
		(layer "F.Cu")
		(net "DRIVE_25_ACT")
	)
	(segment
		(start 88.9508 -61.595)
		(end 87.376 -60.0202)
		(width 0.127)
		(layer "F.Cu")
		(net "DRIVE_25_ACT")
	)
	(segment
		(start 81.710784 -33.160716)
		(end 81.710784 -33.16097)
		(width 0.127)
		(layer "F.Cu")
		(net "DRIVE_25_ACT")
	)
	(segment
		(start 90.3478 -61.595)
		(end 88.9508 -61.595)
		(width 0.127)
		(layer "F.Cu")
		(net "DRIVE_25_ACT")
	)
	(segment
		(start 81.038954 -33.832546)
		(end 81.710784 -33.160716)
		(width 0.127)
		(layer "F.Cu")
		(net "DRIVE_25_ACT")
	)
	(segment
		(start 81.242154 -58.128154)
		(end 81.242154 -34.456878)
		(width 0.127)
		(layer "F.Cu")
		(net "DRIVE_25_ACT")
	)
	(segment
		(start 133.858 -20.092162)
		(end 133.9596 -19.990562)
		(width 0.127)
		(layer "F.Cu")
		(net "DRIVE_25_ACT")
	)
	(segment
		(start 81.710784 -33.16097)
		(end 120.843294 -33.16097)
		(width 0.127)
		(layer "F.Cu")
		(net "DRIVE_25_ACT")
	)
	(segment
		(start 87.376 -60.0202)
		(end 83.1342 -60.0202)
		(width 0.127)
		(layer "F.Cu")
		(net "DRIVE_25_ACT")
	)
	(segment
		(start 90.3478 -61.595)
		(end 98.807524 -61.595)
		(width 0.127)
		(layer "F.Cu")
		(net "DRIVE_25_ACT")
	)
	(segment
		(start 133.9596 -8.240776)
		(end 134.600188 -7.600188)
		(width 0.127)
		(layer "F.Cu")
		(net "DRIVE_25_ACT")
	)
	(segment
		(start 133.858 -20.146264)
		(end 133.858 -20.092162)
		(width 0.127)
		(layer "F.Cu")
		(net "DRIVE_25_ACT")
	)
	(via
		(at 90.3478 -61.595)
		(size 0.6604)
		(drill 0.3302)
		(layers "F.Cu" "B.Cu")
		(net "DRIVE_25_ACT")
	)
	(segment
		(start 134.600188 -6.20014)
		(end 133.4516 -7.348728)
		(width 0.127)
		(layer "F.Cu")
		(net "DRIVE_24_ACT")
	)
	(segment
		(start 133.4516 -19.779996)
		(end 121.160794 -32.070802)
		(width 0.127)
		(layer "F.Cu")
		(net "DRIVE_24_ACT")
	)
	(segment
		(start 85.342476 -32.034226)
		(end 85.96122 -32.65297)
		(width 0.127)
		(layer "F.Cu")
		(net "DRIVE_24_ACT")
	)
	(segment
		(start 120.578626 -32.65297)
		(end 121.160794 -32.070802)
		(width 0.127)
		(layer "F.Cu")
		(net "DRIVE_24_ACT")
	)
	(segment
		(start 133.4516 -7.348728)
		(end 133.4516 -19.779996)
		(width 0.127)
		(layer "F.Cu")
		(net "DRIVE_24_ACT")
	)
	(segment
		(start 85.96122 -32.65297)
		(end 120.578626 -32.65297)
		(width 0.127)
		(layer "F.Cu")
		(net "DRIVE_24_ACT")
	)
	(segment
		(start 105.499916 -62.500002)
		(end 105.000044 -62.00013)
		(width 0.127)
		(layer "F.Cu")
		(net "DRIVE_24_ACT")
	)
	(via
		(at 85.342476 -32.034226)
		(size 0.508)
		(drill 0.254)
		(layers "F.Cu" "B.Cu")
		(net "DRIVE_24_ACT")
	)
	(via
		(at 105.000044 -62.00013)
		(size 0.4572)
		(drill 0.2032)
		(layers "F.Cu" "B.Cu")
		(net "DRIVE_24_ACT")
	)
	(via
		(at 121.160794 -32.070802)
		(size 0.6604)
		(drill 0.3302)
		(layers "F.Cu" "B.Cu")
		(net "DRIVE_24_ACT")
	)
	(segment
		(start 101.836728 -62.606428)
		(end 101.654356 -62.7888)
		(width 0.127)
		(layer "In5.Cu")
		(net "DRIVE_24_ACT")
	)
	(segment
		(start 105.000044 -62.00013)
		(end 104.606344 -61.60643)
		(width 0.127)
		(layer "In5.Cu")
		(net "DRIVE_24_ACT")
	)
	(segment
		(start 98.711766 -62.7888)
		(end 90.06078 -54.137814)
		(width 0.127)
		(layer "In5.Cu")
		(net "DRIVE_24_ACT")
	)
	(segment
		(start 102.836726 -61.60643)
		(end 102.606348 -61.836808)
		(width 0.127)
		(layer "In5.Cu")
		(net "DRIVE_24_ACT")
	)
	(segment
		(start 85.73389 -37.167566)
		(end 85.73389 -32.42564)
		(width 0.127)
		(layer "In5.Cu")
		(net "DRIVE_24_ACT")
	)
	(segment
		(start 101.654356 -62.7888)
		(end 98.711766 -62.7888)
		(width 0.127)
		(layer "In5.Cu")
		(net "DRIVE_24_ACT")
	)
	(segment
		(start 90.06078 -51.74361)
		(end 86.837266 -48.520096)
		(width 0.127)
		(layer "In5.Cu")
		(net "DRIVE_24_ACT")
	)
	(segment
		(start 86.837266 -48.520096)
		(end 86.837266 -38.270942)
		(width 0.127)
		(layer "In5.Cu")
		(net "DRIVE_24_ACT")
	)
	(segment
		(start 86.837266 -38.270942)
		(end 85.73389 -37.167566)
		(width 0.127)
		(layer "In5.Cu")
		(net "DRIVE_24_ACT")
	)
	(segment
		(start 102.606348 -61.950854)
		(end 101.950774 -62.606428)
		(width 0.127)
		(layer "In5.Cu")
		(net "DRIVE_24_ACT")
	)
	(segment
		(start 104.606344 -61.60643)
		(end 102.836726 -61.60643)
		(width 0.127)
		(layer "In5.Cu")
		(net "DRIVE_24_ACT")
	)
	(segment
		(start 102.606348 -61.836808)
		(end 102.606348 -61.950854)
		(width 0.127)
		(layer "In5.Cu")
		(net "DRIVE_24_ACT")
	)
	(segment
		(start 101.950774 -62.606428)
		(end 101.836728 -62.606428)
		(width 0.127)
		(layer "In5.Cu")
		(net "DRIVE_24_ACT")
	)
	(segment
		(start 90.06078 -54.137814)
		(end 90.06078 -51.74361)
		(width 0.127)
		(layer "In5.Cu")
		(net "DRIVE_24_ACT")
	)
	(segment
		(start 85.73389 -32.42564)
		(end 85.342476 -32.034226)
		(width 0.127)
		(layer "In5.Cu")
		(net "DRIVE_24_ACT")
	)
	(segment
		(start 121.87682 -30.5054)
		(end 120.23725 -32.14497)
		(width 0.127)
		(layer "F.Cu")
		(net "DRIVE_23_ACT")
	)
	(segment
		(start 132.142992 -9.457182)
		(end 132.142992 -20.239228)
		(width 0.127)
		(layer "F.Cu")
		(net "DRIVE_23_ACT")
	)
	(segment
		(start 102.499922 -62.500002)
		(end 102.00005 -62.00013)
		(width 0.127)
		(layer "F.Cu")
		(net "DRIVE_23_ACT")
	)
	(segment
		(start 120.23725 -32.14497)
		(end 86.706964 -32.14497)
		(width 0.127)
		(layer "F.Cu")
		(net "DRIVE_23_ACT")
	)
	(segment
		(start 132.80009 -8.800084)
		(end 132.142992 -9.457182)
		(width 0.127)
		(layer "F.Cu")
		(net "DRIVE_23_ACT")
	)
	(segment
		(start 132.142992 -20.239228)
		(end 121.87682 -30.5054)
		(width 0.127)
		(layer "F.Cu")
		(net "DRIVE_23_ACT")
	)
	(segment
		(start 86.706964 -32.14497)
		(end 86.118446 -31.556452)
		(width 0.127)
		(layer "F.Cu")
		(net "DRIVE_23_ACT")
	)
	(via
		(at 102.00005 -62.00013)
		(size 0.4572)
		(drill 0.2032)
		(layers "F.Cu" "B.Cu")
		(net "DRIVE_23_ACT")
	)
	(via
		(at 121.87682 -30.5054)
		(size 0.6604)
		(drill 0.3302)
		(layers "F.Cu" "B.Cu")
		(net "DRIVE_23_ACT")
	)
	(via
		(at 86.118446 -31.556452)
		(size 0.508)
		(drill 0.254)
		(layers "F.Cu" "B.Cu")
		(net "DRIVE_23_ACT")
	)
	(segment
		(start 86.24189 -31.679896)
		(end 86.118446 -31.556452)
		(width 0.127)
		(layer "In5.Cu")
		(net "DRIVE_23_ACT")
	)
	(segment
		(start 99.035362 -62.39383)
		(end 90.56878 -53.927248)
		(width 0.127)
		(layer "In5.Cu")
		(net "DRIVE_23_ACT")
	)
	(segment
		(start 90.56878 -51.533044)
		(end 87.345266 -48.30953)
		(width 0.127)
		(layer "In5.Cu")
		(net "DRIVE_23_ACT")
	)
	(segment
		(start 102.00005 -62.00013)
		(end 101.60635 -62.39383)
		(width 0.127)
		(layer "In5.Cu")
		(net "DRIVE_23_ACT")
	)
	(segment
		(start 87.345266 -38.060376)
		(end 86.24189 -36.957)
		(width 0.127)
		(layer "In5.Cu")
		(net "DRIVE_23_ACT")
	)
	(segment
		(start 101.60635 -62.39383)
		(end 99.035362 -62.39383)
		(width 0.127)
		(layer "In5.Cu")
		(net "DRIVE_23_ACT")
	)
	(segment
		(start 87.345266 -48.30953)
		(end 87.345266 -38.060376)
		(width 0.127)
		(layer "In5.Cu")
		(net "DRIVE_23_ACT")
	)
	(segment
		(start 90.56878 -53.927248)
		(end 90.56878 -51.533044)
		(width 0.127)
		(layer "In5.Cu")
		(net "DRIVE_23_ACT")
	)
	(segment
		(start 86.24189 -36.957)
		(end 86.24189 -31.679896)
		(width 0.127)
		(layer "In5.Cu")
		(net "DRIVE_23_ACT")
	)
	(segment
		(start 103.49992 -62.500002)
		(end 103.000048 -62.00013)
		(width 0.127)
		(layer "F.Cu")
		(net "DRIVE_22_ACT")
	)
	(segment
		(start 120.584722 -31.02483)
		(end 85.236558 -31.02483)
		(width 0.127)
		(layer "F.Cu")
		(net "DRIVE_22_ACT")
	)
	(segment
		(start 122.625866 -28.983686)
		(end 120.584722 -31.02483)
		(width 0.127)
		(layer "F.Cu")
		(net "DRIVE_22_ACT")
	)
	(segment
		(start 85.236558 -31.02483)
		(end 84.238846 -32.022542)
		(width 0.127)
		(layer "F.Cu")
		(net "DRIVE_22_ACT")
	)
	(segment
		(start 131.632706 -19.976846)
		(end 122.625866 -28.983686)
		(width 0.127)
		(layer "F.Cu")
		(net "DRIVE_22_ACT")
	)
	(segment
		(start 131.632706 -8.56742)
		(end 131.632706 -19.976846)
		(width 0.127)
		(layer "F.Cu")
		(net "DRIVE_22_ACT")
	)
	(segment
		(start 132.80009 -7.400036)
		(end 131.632706 -8.56742)
		(width 0.127)
		(layer "F.Cu")
		(net "DRIVE_22_ACT")
	)
	(segment
		(start 84.238846 -32.022542)
		(end 84.238846 -32.032194)
		(width 0.127)
		(layer "F.Cu")
		(net "DRIVE_22_ACT")
	)
	(via
		(at 122.625866 -28.983686)
		(size 0.6604)
		(drill 0.3302)
		(layers "F.Cu" "B.Cu")
		(net "DRIVE_22_ACT")
	)
	(via
		(at 103.000048 -62.00013)
		(size 0.4572)
		(drill 0.2032)
		(layers "F.Cu" "B.Cu")
		(net "DRIVE_22_ACT")
	)
	(via
		(at 84.238846 -32.032194)
		(size 0.508)
		(drill 0.254)
		(layers "F.Cu" "B.Cu")
		(net "DRIVE_22_ACT")
	)
	(segment
		(start 85.584284 -38.455092)
		(end 85.584284 -48.704246)
		(width 0.127)
		(layer "In5.Cu")
		(net "DRIVE_22_ACT")
	)
	(segment
		(start 98.0821 -64.5541)
		(end 101.889052 -64.5541)
		(width 0.127)
		(layer "In5.Cu")
		(net "DRIVE_22_ACT")
	)
	(segment
		(start 102.601776 -63.841376)
		(end 102.601776 -62.398402)
		(width 0.127)
		(layer "In5.Cu")
		(net "DRIVE_22_ACT")
	)
	(segment
		(start 89.04478 -52.164742)
		(end 89.04478 -54.61889)
		(width 0.127)
		(layer "In5.Cu")
		(net "DRIVE_22_ACT")
	)
	(segment
		(start 84.238846 -32.032194)
		(end 84.238846 -32.367728)
		(width 0.127)
		(layer "In5.Cu")
		(net "DRIVE_22_ACT")
	)
	(segment
		(start 96.710754 -62.284864)
		(end 96.710754 -63.182754)
		(width 0.127)
		(layer "In5.Cu")
		(net "DRIVE_22_ACT")
	)
	(segment
		(start 84.6455 -37.516308)
		(end 85.584284 -38.455092)
		(width 0.127)
		(layer "In5.Cu")
		(net "DRIVE_22_ACT")
	)
	(segment
		(start 85.584284 -48.704246)
		(end 89.04478 -52.164742)
		(width 0.127)
		(layer "In5.Cu")
		(net "DRIVE_22_ACT")
	)
	(segment
		(start 89.04478 -54.61889)
		(end 96.710754 -62.284864)
		(width 0.127)
		(layer "In5.Cu")
		(net "DRIVE_22_ACT")
	)
	(segment
		(start 96.710754 -63.182754)
		(end 98.0821 -64.5541)
		(width 0.127)
		(layer "In5.Cu")
		(net "DRIVE_22_ACT")
	)
	(segment
		(start 101.889052 -64.5541)
		(end 102.601776 -63.841376)
		(width 0.127)
		(layer "In5.Cu")
		(net "DRIVE_22_ACT")
	)
	(segment
		(start 102.601776 -62.398402)
		(end 103.000048 -62.00013)
		(width 0.127)
		(layer "In5.Cu")
		(net "DRIVE_22_ACT")
	)
	(segment
		(start 84.238846 -32.367728)
		(end 84.6455 -32.774382)
		(width 0.127)
		(layer "In5.Cu")
		(net "DRIVE_22_ACT")
	)
	(segment
		(start 84.6455 -32.774382)
		(end 84.6455 -37.516308)
		(width 0.127)
		(layer "In5.Cu")
		(net "DRIVE_22_ACT")
	)
	(segment
		(start 85.03412 -30.498034)
		(end 120.285764 -30.498034)
		(width 0.127)
		(layer "F.Cu")
		(net "DRIVE_21_ACT")
	)
	(segment
		(start 81.621122 -31.075122)
		(end 82.964528 -31.075122)
		(width 0.127)
		(layer "F.Cu")
		(net "DRIVE_21_ACT")
	)
	(segment
		(start 84.457032 -31.075122)
		(end 85.03412 -30.498034)
		(width 0.127)
		(layer "F.Cu")
		(net "DRIVE_21_ACT")
	)
	(segment
		(start 82.964528 -31.075122)
		(end 84.457032 -31.075122)
		(width 0.127)
		(layer "F.Cu")
		(net "DRIVE_21_ACT")
	)
	(segment
		(start 130.340862 -20.442936)
		(end 130.340862 -8.259318)
		(width 0.127)
		(layer "F.Cu")
		(net "DRIVE_21_ACT")
	)
	(segment
		(start 130.340862 -8.259318)
		(end 130.999992 -7.600188)
		(width 0.127)
		(layer "F.Cu")
		(net "DRIVE_21_ACT")
	)
	(segment
		(start 107.499912 -64.499998)
		(end 107.00004 -64.000126)
		(width 0.127)
		(layer "F.Cu")
		(net "DRIVE_21_ACT")
	)
	(segment
		(start 120.285764 -30.498034)
		(end 130.340862 -20.442936)
		(width 0.127)
		(layer "F.Cu")
		(net "DRIVE_21_ACT")
	)
	(via
		(at 107.00004 -64.000126)
		(size 0.4572)
		(drill 0.2032)
		(layers "F.Cu" "B.Cu")
		(net "DRIVE_21_ACT")
	)
	(via
		(at 82.964528 -31.075122)
		(size 0.6604)
		(drill 0.3302)
		(layers "F.Cu" "B.Cu")
		(net "DRIVE_21_ACT")
	)
	(via
		(at 81.621122 -31.075122)
		(size 0.508)
		(drill 0.254)
		(layers "F.Cu" "B.Cu")
		(net "DRIVE_21_ACT")
	)
	(segment
		(start 107.00004 -64.000126)
		(end 106.393742 -64.606424)
		(width 0.127)
		(layer "In5.Cu")
		(net "DRIVE_21_ACT")
	)
	(segment
		(start 82.1055 -38.569138)
		(end 82.1055 -33.827212)
		(width 0.127)
		(layer "In5.Cu")
		(net "DRIVE_21_ACT")
	)
	(segment
		(start 93.772736 -67.410076)
		(end 92.66301 -67.410076)
		(width 0.127)
		(layer "In5.Cu")
		(net "DRIVE_21_ACT")
	)
	(segment
		(start 82.1055 -33.827212)
		(end 81.621122 -33.342834)
		(width 0.127)
		(layer "In5.Cu")
		(net "DRIVE_21_ACT")
	)
	(segment
		(start 81.621122 -33.342834)
		(end 81.621122 -31.075122)
		(width 0.127)
		(layer "In5.Cu")
		(net "DRIVE_21_ACT")
	)
	(segment
		(start 106.393742 -66.163444)
		(end 105.147364 -67.409822)
		(width 0.127)
		(layer "In5.Cu")
		(net "DRIVE_21_ACT")
	)
	(segment
		(start 93.77299 -67.409822)
		(end 93.772736 -67.410076)
		(width 0.127)
		(layer "In5.Cu")
		(net "DRIVE_21_ACT")
	)
	(segment
		(start 106.393742 -64.606424)
		(end 106.393742 -66.163444)
		(width 0.127)
		(layer "In5.Cu")
		(net "DRIVE_21_ACT")
	)
	(segment
		(start 105.147364 -67.409822)
		(end 93.77299 -67.409822)
		(width 0.127)
		(layer "In5.Cu")
		(net "DRIVE_21_ACT")
	)
	(segment
		(start 92.66301 -67.410076)
		(end 82.890868 -57.637934)
		(width 0.127)
		(layer "In5.Cu")
		(net "DRIVE_21_ACT")
	)
	(segment
		(start 82.890868 -39.354506)
		(end 82.1055 -38.569138)
		(width 0.127)
		(layer "In5.Cu")
		(net "DRIVE_21_ACT")
	)
	(segment
		(start 82.890868 -57.637934)
		(end 82.890868 -39.354506)
		(width 0.127)
		(layer "In5.Cu")
		(net "DRIVE_21_ACT")
	)
	(segment
		(start 100.102924 -62.103)
		(end 100.499926 -62.500002)
		(width 0.127)
		(layer "F.Cu")
		(net "DRIVE_20_ACT")
	)
	(segment
		(start 92.39758 -62.4332)
		(end 92.72778 -62.103)
		(width 0.127)
		(layer "F.Cu")
		(net "DRIVE_20_ACT")
	)
	(segment
		(start 91.8972 -62.4332)
		(end 92.39758 -62.4332)
		(width 0.127)
		(layer "F.Cu")
		(net "DRIVE_20_ACT")
	)
	(segment
		(start 120.075198 -29.990034)
		(end 129.832608 -20.232624)
		(width 0.127)
		(layer "F.Cu")
		(net "DRIVE_20_ACT")
	)
	(segment
		(start 84.387944 -30.425644)
		(end 84.823554 -29.990034)
		(width 0.127)
		(layer "F.Cu")
		(net "DRIVE_20_ACT")
	)
	(segment
		(start 80.734154 -58.763154)
		(end 80.734154 -34.667444)
		(width 0.127)
		(layer "F.Cu")
		(net "DRIVE_20_ACT")
	)
	(segment
		(start 84.823554 -29.990034)
		(end 120.075198 -29.990034)
		(width 0.127)
		(layer "F.Cu")
		(net "DRIVE_20_ACT")
	)
	(segment
		(start 80.734154 -34.667444)
		(end 80.530954 -34.464244)
		(width 0.127)
		(layer "F.Cu")
		(net "DRIVE_20_ACT")
	)
	(segment
		(start 92.72778 -62.103)
		(end 100.102924 -62.103)
		(width 0.127)
		(layer "F.Cu")
		(net "DRIVE_20_ACT")
	)
	(segment
		(start 80.530954 -31.105094)
		(end 81.210404 -30.425644)
		(width 0.127)
		(layer "F.Cu")
		(net "DRIVE_20_ACT")
	)
	(segment
		(start 82.499708 -60.528708)
		(end 80.734154 -58.763154)
		(width 0.127)
		(layer "F.Cu")
		(net "DRIVE_20_ACT")
	)
	(segment
		(start 88.8238 -62.4332)
		(end 86.919308 -60.528708)
		(width 0.127)
		(layer "F.Cu")
		(net "DRIVE_20_ACT")
	)
	(segment
		(start 129.832608 -7.367524)
		(end 130.999992 -6.20014)
		(width 0.127)
		(layer "F.Cu")
		(net "DRIVE_20_ACT")
	)
	(segment
		(start 86.919308 -60.528708)
		(end 82.499708 -60.528708)
		(width 0.127)
		(layer "F.Cu")
		(net "DRIVE_20_ACT")
	)
	(segment
		(start 91.8972 -62.4332)
		(end 88.8238 -62.4332)
		(width 0.127)
		(layer "F.Cu")
		(net "DRIVE_20_ACT")
	)
	(segment
		(start 129.832608 -20.232624)
		(end 129.832608 -7.367524)
		(width 0.127)
		(layer "F.Cu")
		(net "DRIVE_20_ACT")
	)
	(segment
		(start 80.530954 -34.464244)
		(end 80.530954 -31.105094)
		(width 0.127)
		(layer "F.Cu")
		(net "DRIVE_20_ACT")
	)
	(segment
		(start 81.210404 -30.425644)
		(end 84.387944 -30.425644)
		(width 0.127)
		(layer "F.Cu")
		(net "DRIVE_20_ACT")
	)
	(via
		(at 91.8972 -62.4332)
		(size 0.6604)
		(drill 0.3302)
		(layers "F.Cu" "B.Cu")
		(net "DRIVE_20_ACT")
	)
	(segment
		(start 74.01179 -25.457658)
		(end 74.594466 -24.874982)
		(width 0.127)
		(layer "F.Cu")
		(net "DRIVE_2_ACT")
	)
	(segment
		(start 77.280262 -24.874982)
		(end 76.242672 -24.874982)
		(width 0.127)
		(layer "F.Cu")
		(net "DRIVE_2_ACT")
	)
	(segment
		(start 117.24894 -20.964398)
		(end 116.242338 -21.971)
		(width 0.127)
		(layer "F.Cu")
		(net "DRIVE_2_ACT")
	)
	(segment
		(start 74.594466 -24.874982)
		(end 76.242672 -24.874982)
		(width 0.127)
		(layer "F.Cu")
		(net "DRIVE_2_ACT")
	)
	(segment
		(start 117.24894 -8.551164)
		(end 117.24894 -20.964398)
		(width 0.127)
		(layer "F.Cu")
		(net "DRIVE_2_ACT")
	)
	(segment
		(start 107.499912 -80.50022)
		(end 107.00004 -81.000092)
		(width 0.127)
		(layer "F.Cu")
		(net "DRIVE_2_ACT")
	)
	(segment
		(start 116.242338 -21.971)
		(end 80.184244 -21.971)
		(width 0.127)
		(layer "F.Cu")
		(net "DRIVE_2_ACT")
	)
	(segment
		(start 118.400068 -7.400036)
		(end 117.24894 -8.551164)
		(width 0.127)
		(layer "F.Cu")
		(net "DRIVE_2_ACT")
	)
	(segment
		(start 80.184244 -21.971)
		(end 77.280262 -24.874982)
		(width 0.127)
		(layer "F.Cu")
		(net "DRIVE_2_ACT")
	)
	(via
		(at 107.00004 -81.000092)
		(size 0.4572)
		(drill 0.2032)
		(layers "F.Cu" "B.Cu")
		(net "DRIVE_2_ACT")
	)
	(via
		(at 76.242672 -24.874982)
		(size 0.6604)
		(drill 0.3302)
		(layers "F.Cu" "B.Cu")
		(net "DRIVE_2_ACT")
	)
	(via
		(at 74.01179 -25.457658)
		(size 0.508)
		(drill 0.254)
		(layers "F.Cu" "B.Cu")
		(net "DRIVE_2_ACT")
	)
	(segment
		(start 79.832454 -60.30722)
		(end 81.719674 -62.19444)
		(width 0.127)
		(layer "In5.Cu")
		(net "DRIVE_2_ACT")
	)
	(segment
		(start 98.672142 -82.39379)
		(end 104.34701 -82.39379)
		(width 0.127)
		(layer "In5.Cu")
		(net "DRIVE_2_ACT")
	)
	(segment
		(start 78.379066 -30.990032)
		(end 78.93812 -31.549086)
		(width 0.127)
		(layer "In5.Cu")
		(net "DRIVE_2_ACT")
	)
	(segment
		(start 106.698796 -81.000092)
		(end 107.00004 -81.000092)
		(width 0.127)
		(layer "In5.Cu")
		(net "DRIVE_2_ACT")
	)
	(segment
		(start 97.024952 -80.7466)
		(end 98.672142 -82.39379)
		(width 0.127)
		(layer "In5.Cu")
		(net "DRIVE_2_ACT")
	)
	(segment
		(start 79.832454 -40.607488)
		(end 79.832454 -60.30722)
		(width 0.127)
		(layer "In5.Cu")
		(net "DRIVE_2_ACT")
	)
	(segment
		(start 78.93812 -31.549086)
		(end 78.93812 -39.713154)
		(width 0.127)
		(layer "In5.Cu")
		(net "DRIVE_2_ACT")
	)
	(segment
		(start 74.67981 -26.125678)
		(end 75.598528 -26.125678)
		(width 0.127)
		(layer "In5.Cu")
		(net "DRIVE_2_ACT")
	)
	(segment
		(start 106.216704 -81.482184)
		(end 106.698796 -81.000092)
		(width 0.127)
		(layer "In5.Cu")
		(net "DRIVE_2_ACT")
	)
	(segment
		(start 74.01179 -25.457658)
		(end 74.67981 -26.125678)
		(width 0.127)
		(layer "In5.Cu")
		(net "DRIVE_2_ACT")
	)
	(segment
		(start 81.719674 -67.051174)
		(end 84.133944 -69.465444)
		(width 0.127)
		(layer "In5.Cu")
		(net "DRIVE_2_ACT")
	)
	(segment
		(start 89.154 -79.811118)
		(end 90.089482 -80.7466)
		(width 0.127)
		(layer "In5.Cu")
		(net "DRIVE_2_ACT")
	)
	(segment
		(start 77.046836 -27.573986)
		(end 77.046836 -28.432506)
		(width 0.127)
		(layer "In5.Cu")
		(net "DRIVE_2_ACT")
	)
	(segment
		(start 86.792562 -69.465444)
		(end 89.154 -71.826882)
		(width 0.127)
		(layer "In5.Cu")
		(net "DRIVE_2_ACT")
	)
	(segment
		(start 75.598528 -26.125678)
		(end 77.046836 -27.573986)
		(width 0.127)
		(layer "In5.Cu")
		(net "DRIVE_2_ACT")
	)
	(segment
		(start 104.34701 -82.39379)
		(end 105.258616 -81.482184)
		(width 0.127)
		(layer "In5.Cu")
		(net "DRIVE_2_ACT")
	)
	(segment
		(start 89.154 -71.826882)
		(end 89.154 -79.811118)
		(width 0.127)
		(layer "In5.Cu")
		(net "DRIVE_2_ACT")
	)
	(segment
		(start 78.93812 -39.713154)
		(end 79.832454 -40.607488)
		(width 0.127)
		(layer "In5.Cu")
		(net "DRIVE_2_ACT")
	)
	(segment
		(start 105.258616 -81.482184)
		(end 106.216704 -81.482184)
		(width 0.127)
		(layer "In5.Cu")
		(net "DRIVE_2_ACT")
	)
	(segment
		(start 84.133944 -69.465444)
		(end 86.792562 -69.465444)
		(width 0.127)
		(layer "In5.Cu")
		(net "DRIVE_2_ACT")
	)
	(segment
		(start 77.046836 -28.432506)
		(end 78.379066 -29.764736)
		(width 0.127)
		(layer "In5.Cu")
		(net "DRIVE_2_ACT")
	)
	(segment
		(start 90.089482 -80.7466)
		(end 97.024952 -80.7466)
		(width 0.127)
		(layer "In5.Cu")
		(net "DRIVE_2_ACT")
	)
	(segment
		(start 78.379066 -29.764736)
		(end 78.379066 -30.990032)
		(width 0.127)
		(layer "In5.Cu")
		(net "DRIVE_2_ACT")
	)
	(segment
		(start 81.719674 -62.19444)
		(end 81.719674 -67.051174)
		(width 0.127)
		(layer "In5.Cu")
		(net "DRIVE_2_ACT")
	)
	(segment
		(start 119.864632 -29.482034)
		(end 128.541018 -20.805648)
		(width 0.127)
		(layer "F.Cu")
		(net "DRIVE_19_ACT")
	)
	(segment
		(start 99.499928 -62.500002)
		(end 98.662998 -62.500002)
		(width 0.127)
		(layer "F.Cu")
		(net "DRIVE_19_ACT")
	)
	(segment
		(start 86.449408 -61.074808)
		(end 81.923128 -61.074808)
		(width 0.127)
		(layer "F.Cu")
		(net "DRIVE_19_ACT")
	)
	(segment
		(start 80.953356 -29.917644)
		(end 84.177378 -29.917644)
		(width 0.127)
		(layer "F.Cu")
		(net "DRIVE_19_ACT")
	)
	(segment
		(start 88.5952 -63.2206)
		(end 86.449408 -61.074808)
		(width 0.127)
		(layer "F.Cu")
		(net "DRIVE_19_ACT")
	)
	(segment
		(start 84.612988 -29.482034)
		(end 119.864632 -29.482034)
		(width 0.127)
		(layer "F.Cu")
		(net "DRIVE_19_ACT")
	)
	(segment
		(start 98.662998 -62.500002)
		(end 97.9424 -63.2206)
		(width 0.127)
		(layer "F.Cu")
		(net "DRIVE_19_ACT")
	)
	(segment
		(start 81.439512 -60.591192)
		(end 80.226154 -59.377834)
		(width 0.127)
		(layer "F.Cu")
		(net "DRIVE_19_ACT")
	)
	(segment
		(start 80.226154 -59.377834)
		(end 80.226154 -34.87801)
		(width 0.127)
		(layer "F.Cu")
		(net "DRIVE_19_ACT")
	)
	(segment
		(start 80.022954 -34.67481)
		(end 80.022954 -30.848046)
		(width 0.127)
		(layer "F.Cu")
		(net "DRIVE_19_ACT")
	)
	(segment
		(start 128.541018 -20.805648)
		(end 128.541018 -9.459214)
		(width 0.127)
		(layer "F.Cu")
		(net "DRIVE_19_ACT")
	)
	(segment
		(start 81.923128 -61.074808)
		(end 81.439512 -60.591192)
		(width 0.127)
		(layer "F.Cu")
		(net "DRIVE_19_ACT")
	)
	(segment
		(start 80.022954 -30.848046)
		(end 80.953356 -29.917644)
		(width 0.127)
		(layer "F.Cu")
		(net "DRIVE_19_ACT")
	)
	(segment
		(start 97.9424 -63.2206)
		(end 88.5952 -63.2206)
		(width 0.127)
		(layer "F.Cu")
		(net "DRIVE_19_ACT")
	)
	(segment
		(start 80.226154 -34.87801)
		(end 80.022954 -34.67481)
		(width 0.127)
		(layer "F.Cu")
		(net "DRIVE_19_ACT")
	)
	(segment
		(start 128.541018 -9.459214)
		(end 129.200148 -8.800084)
		(width 0.127)
		(layer "F.Cu")
		(net "DRIVE_19_ACT")
	)
	(segment
		(start 84.177378 -29.917644)
		(end 84.612988 -29.482034)
		(width 0.127)
		(layer "F.Cu")
		(net "DRIVE_19_ACT")
	)
	(via
		(at 81.439512 -60.591192)
		(size 0.6604)
		(drill 0.3302)
		(layers "F.Cu" "B.Cu")
		(net "DRIVE_19_ACT")
	)
	(segment
		(start 119.59971 -28.974034)
		(end 121.77649 -26.797254)
		(width 0.127)
		(layer "F.Cu")
		(net "DRIVE_18_ACT")
	)
	(segment
		(start 83.4644 -29.0576)
		(end 83.547966 -28.974034)
		(width 0.127)
		(layer "F.Cu")
		(net "DRIVE_18_ACT")
	)
	(segment
		(start 83.547966 -28.974034)
		(end 119.59971 -28.974034)
		(width 0.127)
		(layer "F.Cu")
		(net "DRIVE_18_ACT")
	)
	(segment
		(start 103.49992 -63.5)
		(end 103.000048 -63.000128)
		(width 0.127)
		(layer "F.Cu")
		(net "DRIVE_18_ACT")
	)
	(segment
		(start 128.032764 -20.54098)
		(end 128.032764 -8.56742)
		(width 0.127)
		(layer "F.Cu")
		(net "DRIVE_18_ACT")
	)
	(segment
		(start 121.77649 -26.797254)
		(end 128.032764 -20.54098)
		(width 0.127)
		(layer "F.Cu")
		(net "DRIVE_18_ACT")
	)
	(segment
		(start 128.032764 -8.56742)
		(end 129.200148 -7.400036)
		(width 0.127)
		(layer "F.Cu")
		(net "DRIVE_18_ACT")
	)
	(via
		(at 121.77649 -26.797254)
		(size 0.6604)
		(drill 0.3302)
		(layers "F.Cu" "B.Cu")
		(net "DRIVE_18_ACT")
	)
	(via
		(at 83.4644 -29.0576)
		(size 0.508)
		(drill 0.254)
		(layers "F.Cu" "B.Cu")
		(net "DRIVE_18_ACT")
	)
	(via
		(at 103.000048 -63.000128)
		(size 0.4572)
		(drill 0.2032)
		(layers "F.Cu" "B.Cu")
		(net "DRIVE_18_ACT")
	)
	(segment
		(start 83.653122 -32.50057)
		(end 84.1375 -32.984948)
		(width 0.127)
		(layer "In5.Cu")
		(net "DRIVE_18_ACT")
	)
	(segment
		(start 103.000048 -64.39154)
		(end 103.000048 -63.000128)
		(width 0.127)
		(layer "In5.Cu")
		(net "DRIVE_18_ACT")
	)
	(segment
		(start 102.51948 -65.1764)
		(end 102.51948 -64.872108)
		(width 0.127)
		(layer "In5.Cu")
		(net "DRIVE_18_ACT")
	)
	(segment
		(start 84.1375 -32.984948)
		(end 84.1375 -37.726874)
		(width 0.127)
		(layer "In5.Cu")
		(net "DRIVE_18_ACT")
	)
	(segment
		(start 83.4644 -29.0576)
		(end 83.653122 -29.246322)
		(width 0.127)
		(layer "In5.Cu")
		(net "DRIVE_18_ACT")
	)
	(segment
		(start 83.653122 -29.246322)
		(end 83.653122 -32.50057)
		(width 0.127)
		(layer "In5.Cu")
		(net "DRIVE_18_ACT")
	)
	(segment
		(start 85.036914 -38.626288)
		(end 85.036914 -49.054004)
		(width 0.127)
		(layer "In5.Cu")
		(net "DRIVE_18_ACT")
	)
	(segment
		(start 88.536272 -59.172348)
		(end 92.838524 -63.4746)
		(width 0.127)
		(layer "In5.Cu")
		(net "DRIVE_18_ACT")
	)
	(segment
		(start 85.036914 -49.054004)
		(end 88.536272 -52.553362)
		(width 0.127)
		(layer "In5.Cu")
		(net "DRIVE_18_ACT")
	)
	(segment
		(start 84.1375 -37.726874)
		(end 85.036914 -38.626288)
		(width 0.127)
		(layer "In5.Cu")
		(net "DRIVE_18_ACT")
	)
	(segment
		(start 102.51948 -64.872108)
		(end 103.000048 -64.39154)
		(width 0.127)
		(layer "In5.Cu")
		(net "DRIVE_18_ACT")
	)
	(segment
		(start 102.17658 -65.5193)
		(end 102.51948 -65.1764)
		(width 0.127)
		(layer "In5.Cu")
		(net "DRIVE_18_ACT")
	)
	(segment
		(start 96.1644 -63.4746)
		(end 98.2091 -65.5193)
		(width 0.127)
		(layer "In5.Cu")
		(net "DRIVE_18_ACT")
	)
	(segment
		(start 92.838524 -63.4746)
		(end 96.1644 -63.4746)
		(width 0.127)
		(layer "In5.Cu")
		(net "DRIVE_18_ACT")
	)
	(segment
		(start 88.536272 -52.553362)
		(end 88.536272 -59.172348)
		(width 0.127)
		(layer "In5.Cu")
		(net "DRIVE_18_ACT")
	)
	(segment
		(start 98.2091 -65.5193)
		(end 102.17658 -65.5193)
		(width 0.127)
		(layer "In5.Cu")
		(net "DRIVE_18_ACT")
	)
	(segment
		(start 83.284314 -28.466034)
		(end 119.334788 -28.466034)
		(width 0.127)
		(layer "F.Cu")
		(net "DRIVE_17_ACT")
	)
	(segment
		(start 119.334788 -28.466034)
		(end 119.658384 -28.142438)
		(width 0.127)
		(layer "F.Cu")
		(net "DRIVE_17_ACT")
	)
	(segment
		(start 126.740666 -8.259572)
		(end 127.40005 -7.600188)
		(width 0.127)
		(layer "F.Cu")
		(net "DRIVE_17_ACT")
	)
	(segment
		(start 105.499916 -63.5)
		(end 105.000044 -63.000128)
		(width 0.127)
		(layer "F.Cu")
		(net "DRIVE_17_ACT")
	)
	(segment
		(start 119.658384 -28.142438)
		(end 126.740666 -21.060156)
		(width 0.127)
		(layer "F.Cu")
		(net "DRIVE_17_ACT")
	)
	(segment
		(start 82.302604 -29.447744)
		(end 83.284314 -28.466034)
		(width 0.127)
		(layer "F.Cu")
		(net "DRIVE_17_ACT")
	)
	(segment
		(start 126.740666 -21.060156)
		(end 126.740666 -8.259572)
		(width 0.127)
		(layer "F.Cu")
		(net "DRIVE_17_ACT")
	)
	(via
		(at 119.658384 -28.142438)
		(size 0.6604)
		(drill 0.3302)
		(layers "F.Cu" "B.Cu")
		(net "DRIVE_17_ACT")
	)
	(via
		(at 82.302604 -29.447744)
		(size 0.508)
		(drill 0.254)
		(layers "F.Cu" "B.Cu")
		(net "DRIVE_17_ACT")
	)
	(via
		(at 105.000044 -63.000128)
		(size 0.4572)
		(drill 0.2032)
		(layers "F.Cu" "B.Cu")
		(net "DRIVE_17_ACT")
	)
	(segment
		(start 83.145122 -32.711136)
		(end 83.6295 -33.195514)
		(width 0.127)
		(layer "In5.Cu")
		(net "DRIVE_17_ACT")
	)
	(segment
		(start 103.58882 -65.968372)
		(end 103.58882 -64.411352)
		(width 0.127)
		(layer "In5.Cu")
		(net "DRIVE_17_ACT")
	)
	(segment
		(start 102.90937 -66.647822)
		(end 103.58882 -65.968372)
		(width 0.127)
		(layer "In5.Cu")
		(net "DRIVE_17_ACT")
	)
	(segment
		(start 88.028272 -53.32095)
		(end 88.028272 -59.382914)
		(width 0.127)
		(layer "In5.Cu")
		(net "DRIVE_17_ACT")
	)
	(segment
		(start 84.521802 -38.829742)
		(end 84.521802 -49.81448)
		(width 0.127)
		(layer "In5.Cu")
		(net "DRIVE_17_ACT")
	)
	(segment
		(start 96.157034 -64.1858)
		(end 98.619056 -66.647822)
		(width 0.127)
		(layer "In5.Cu")
		(net "DRIVE_17_ACT")
	)
	(segment
		(start 88.028272 -59.382914)
		(end 92.831158 -64.1858)
		(width 0.127)
		(layer "In5.Cu")
		(net "DRIVE_17_ACT")
	)
	(segment
		(start 82.302604 -29.600906)
		(end 83.145122 -30.443424)
		(width 0.127)
		(layer "In5.Cu")
		(net "DRIVE_17_ACT")
	)
	(segment
		(start 82.302604 -29.447744)
		(end 82.302604 -29.600906)
		(width 0.127)
		(layer "In5.Cu")
		(net "DRIVE_17_ACT")
	)
	(segment
		(start 84.521802 -49.81448)
		(end 88.028272 -53.32095)
		(width 0.127)
		(layer "In5.Cu")
		(net "DRIVE_17_ACT")
	)
	(segment
		(start 83.145122 -30.443424)
		(end 83.145122 -32.711136)
		(width 0.127)
		(layer "In5.Cu")
		(net "DRIVE_17_ACT")
	)
	(segment
		(start 83.6295 -37.93744)
		(end 84.521802 -38.829742)
		(width 0.127)
		(layer "In5.Cu")
		(net "DRIVE_17_ACT")
	)
	(segment
		(start 92.831158 -64.1858)
		(end 96.157034 -64.1858)
		(width 0.127)
		(layer "In5.Cu")
		(net "DRIVE_17_ACT")
	)
	(segment
		(start 98.619056 -66.647822)
		(end 102.90937 -66.647822)
		(width 0.127)
		(layer "In5.Cu")
		(net "DRIVE_17_ACT")
	)
	(segment
		(start 103.58882 -64.411352)
		(end 105.000044 -63.000128)
		(width 0.127)
		(layer "In5.Cu")
		(net "DRIVE_17_ACT")
	)
	(segment
		(start 83.6295 -33.195514)
		(end 83.6295 -37.93744)
		(width 0.127)
		(layer "In5.Cu")
		(net "DRIVE_17_ACT")
	)
	(segment
		(start 81.90738 -28.282138)
		(end 81.161636 -29.027882)
		(width 0.127)
		(layer "F.Cu")
		(net "DRIVE_16_ACT")
	)
	(segment
		(start 127.40005 -6.20014)
		(end 126.232666 -7.367524)
		(width 0.127)
		(layer "F.Cu")
		(net "DRIVE_16_ACT")
	)
	(segment
		(start 106.499914 -64.499998)
		(end 106.000042 -64.000126)
		(width 0.127)
		(layer "F.Cu")
		(net "DRIVE_16_ACT")
	)
	(segment
		(start 81.161636 -29.027882)
		(end 81.161382 -29.027882)
		(width 0.127)
		(layer "F.Cu")
		(net "DRIVE_16_ACT")
	)
	(segment
		(start 82.231484 -27.958034)
		(end 81.90738 -28.282138)
		(width 0.127)
		(layer "F.Cu")
		(net "DRIVE_16_ACT")
	)
	(segment
		(start 126.232666 -20.795742)
		(end 119.070374 -27.958034)
		(width 0.127)
		(layer "F.Cu")
		(net "DRIVE_16_ACT")
	)
	(segment
		(start 126.232666 -7.367524)
		(end 126.232666 -20.795742)
		(width 0.127)
		(layer "F.Cu")
		(net "DRIVE_16_ACT")
	)
	(segment
		(start 119.070374 -27.958034)
		(end 82.231484 -27.958034)
		(width 0.127)
		(layer "F.Cu")
		(net "DRIVE_16_ACT")
	)
	(via
		(at 106.000042 -64.000126)
		(size 0.4572)
		(drill 0.2032)
		(layers "F.Cu" "B.Cu")
		(net "DRIVE_16_ACT")
	)
	(via
		(at 81.90738 -28.282138)
		(size 0.6604)
		(drill 0.3302)
		(layers "F.Cu" "B.Cu")
		(net "DRIVE_16_ACT")
	)
	(via
		(at 81.161382 -29.027882)
		(size 0.508)
		(drill 0.254)
		(layers "F.Cu" "B.Cu")
		(net "DRIVE_16_ACT")
	)
	(segment
		(start 104.401366 -67.155822)
		(end 96.984566 -67.155822)
		(width 0.127)
		(layer "In5.Cu")
		(net "DRIVE_16_ACT")
	)
	(segment
		(start 105.441496 -66.115692)
		(end 104.401366 -67.155822)
		(width 0.127)
		(layer "In5.Cu")
		(net "DRIVE_16_ACT")
	)
	(segment
		(start 106.000042 -64.000126)
		(end 105.441496 -64.558672)
		(width 0.127)
		(layer "In5.Cu")
		(net "DRIVE_16_ACT")
	)
	(segment
		(start 105.441496 -64.558672)
		(end 105.441496 -66.115692)
		(width 0.127)
		(layer "In5.Cu")
		(net "DRIVE_16_ACT")
	)
	(segment
		(start 83.398868 -57.427368)
		(end 83.398868 -39.14394)
		(width 0.127)
		(layer "In5.Cu")
		(net "DRIVE_16_ACT")
	)
	(segment
		(start 82.6135 -33.616646)
		(end 82.129122 -33.132268)
		(width 0.127)
		(layer "In5.Cu")
		(net "DRIVE_16_ACT")
	)
	(segment
		(start 82.129122 -30.864556)
		(end 81.161382 -29.896816)
		(width 0.127)
		(layer "In5.Cu")
		(net "DRIVE_16_ACT")
	)
	(segment
		(start 96.984566 -67.155822)
		(end 96.730566 -66.901822)
		(width 0.127)
		(layer "In5.Cu")
		(net "DRIVE_16_ACT")
	)
	(segment
		(start 82.129122 -33.132268)
		(end 82.129122 -30.864556)
		(width 0.127)
		(layer "In5.Cu")
		(net "DRIVE_16_ACT")
	)
	(segment
		(start 83.398868 -39.14394)
		(end 82.6135 -38.358572)
		(width 0.127)
		(layer "In5.Cu")
		(net "DRIVE_16_ACT")
	)
	(segment
		(start 92.873322 -66.901822)
		(end 83.398868 -57.427368)
		(width 0.127)
		(layer "In5.Cu")
		(net "DRIVE_16_ACT")
	)
	(segment
		(start 81.161382 -29.896816)
		(end 81.161382 -29.027882)
		(width 0.127)
		(layer "In5.Cu")
		(net "DRIVE_16_ACT")
	)
	(segment
		(start 82.6135 -38.358572)
		(end 82.6135 -33.616646)
		(width 0.127)
		(layer "In5.Cu")
		(net "DRIVE_16_ACT")
	)
	(segment
		(start 96.730566 -66.901822)
		(end 92.873322 -66.901822)
		(width 0.127)
		(layer "In5.Cu")
		(net "DRIVE_16_ACT")
	)
	(segment
		(start 72.99579 -25.102312)
		(end 73.507092 -24.59101)
		(width 0.127)
		(layer "F.Cu")
		(net "DRIVE_1_ACT")
	)
	(segment
		(start 77.184758 -24.25192)
		(end 79.973678 -21.463)
		(width 0.127)
		(layer "F.Cu")
		(net "DRIVE_1_ACT")
	)
	(segment
		(start 115.94084 -8.259318)
		(end 116.59997 -7.600188)
		(width 0.127)
		(layer "F.Cu")
		(net "DRIVE_1_ACT")
	)
	(segment
		(start 72.99579 -25.457658)
		(end 72.99579 -25.102312)
		(width 0.127)
		(layer "F.Cu")
		(net "DRIVE_1_ACT")
	)
	(segment
		(start 79.973678 -21.463)
		(end 115.4176 -21.463)
		(width 0.127)
		(layer "F.Cu")
		(net "DRIVE_1_ACT")
	)
	(segment
		(start 106.499914 -81.500218)
		(end 106.999786 -82.00009)
		(width 0.127)
		(layer "F.Cu")
		(net "DRIVE_1_ACT")
	)
	(segment
		(start 73.507092 -24.59101)
		(end 73.846182 -24.25192)
		(width 0.127)
		(layer "F.Cu")
		(net "DRIVE_1_ACT")
	)
	(segment
		(start 115.4176 -21.463)
		(end 115.94084 -20.93976)
		(width 0.127)
		(layer "F.Cu")
		(net "DRIVE_1_ACT")
	)
	(segment
		(start 73.846182 -24.25192)
		(end 77.184758 -24.25192)
		(width 0.127)
		(layer "F.Cu")
		(net "DRIVE_1_ACT")
	)
	(segment
		(start 115.94084 -20.93976)
		(end 115.94084 -8.259318)
		(width 0.127)
		(layer "F.Cu")
		(net "DRIVE_1_ACT")
	)
	(via
		(at 72.99579 -25.457658)
		(size 0.508)
		(drill 0.254)
		(layers "F.Cu" "B.Cu")
		(net "DRIVE_1_ACT")
	)
	(via
		(at 106.999786 -82.00009)
		(size 0.4572)
		(drill 0.2032)
		(layers "F.Cu" "B.Cu")
		(net "DRIVE_1_ACT")
	)
	(via
		(at 73.507092 -24.59101)
		(size 0.6604)
		(drill 0.3302)
		(layers "F.Cu" "B.Cu")
		(net "DRIVE_1_ACT")
	)
	(segment
		(start 77.35697 -62.137036)
		(end 78.814422 -63.594488)
		(width 0.127)
		(layer "In5.Cu")
		(net "DRIVE_1_ACT")
	)
	(segment
		(start 84.336128 -78.727046)
		(end 84.336128 -79.799434)
		(width 0.127)
		(layer "In5.Cu")
		(net "DRIVE_1_ACT")
	)
	(segment
		(start 78.814168 -64.638682)
		(end 78.814168 -65.100708)
		(width 0.127)
		(layer "In5.Cu")
		(net "DRIVE_1_ACT")
	)
	(segment
		(start 78.814676 -64.638174)
		(end 78.814168 -64.638682)
		(width 0.127)
		(layer "In5.Cu")
		(net "DRIVE_1_ACT")
	)
	(segment
		(start 82.735166 -77.126084)
		(end 84.336128 -78.727046)
		(width 0.127)
		(layer "In5.Cu")
		(net "DRIVE_1_ACT")
	)
	(segment
		(start 97.560638 -83.93938)
		(end 105.617772 -83.93938)
		(width 0.127)
		(layer "In5.Cu")
		(net "DRIVE_1_ACT")
	)
	(segment
		(start 87.167466 -83.1469)
		(end 96.768158 -83.1469)
		(width 0.127)
		(layer "In5.Cu")
		(net "DRIVE_1_ACT")
	)
	(segment
		(start 77.35697 -32.340296)
		(end 77.35697 -62.137036)
		(width 0.127)
		(layer "In5.Cu")
		(net "DRIVE_1_ACT")
	)
	(segment
		(start 78.814676 -64.21755)
		(end 78.814676 -64.638174)
		(width 0.127)
		(layer "In5.Cu")
		(net "DRIVE_1_ACT")
	)
	(segment
		(start 82.735166 -70.418198)
		(end 82.735166 -77.126084)
		(width 0.127)
		(layer "In5.Cu")
		(net "DRIVE_1_ACT")
	)
	(segment
		(start 106.999786 -82.416396)
		(end 106.999786 -82.00009)
		(width 0.127)
		(layer "In5.Cu")
		(net "DRIVE_1_ACT")
	)
	(segment
		(start 72.99579 -27.979116)
		(end 77.35697 -32.340296)
		(width 0.127)
		(layer "In5.Cu")
		(net "DRIVE_1_ACT")
	)
	(segment
		(start 96.768158 -83.1469)
		(end 97.560638 -83.93938)
		(width 0.127)
		(layer "In5.Cu")
		(net "DRIVE_1_ACT")
	)
	(segment
		(start 106.396282 -83.16087)
		(end 106.396282 -83.0199)
		(width 0.127)
		(layer "In5.Cu")
		(net "DRIVE_1_ACT")
	)
	(segment
		(start 105.617772 -83.93938)
		(end 106.396282 -83.16087)
		(width 0.127)
		(layer "In5.Cu")
		(net "DRIVE_1_ACT")
	)
	(segment
		(start 84.336128 -79.799434)
		(end 84.636356 -80.099662)
		(width 0.127)
		(layer "In5.Cu")
		(net "DRIVE_1_ACT")
	)
	(segment
		(start 78.814422 -64.217296)
		(end 78.814676 -64.21755)
		(width 0.127)
		(layer "In5.Cu")
		(net "DRIVE_1_ACT")
	)
	(segment
		(start 78.814422 -63.594488)
		(end 78.814422 -64.217296)
		(width 0.127)
		(layer "In5.Cu")
		(net "DRIVE_1_ACT")
	)
	(segment
		(start 78.8035 -66.486532)
		(end 82.735166 -70.418198)
		(width 0.127)
		(layer "In5.Cu")
		(net "DRIVE_1_ACT")
	)
	(segment
		(start 84.636356 -80.099662)
		(end 84.636356 -80.61579)
		(width 0.127)
		(layer "In5.Cu")
		(net "DRIVE_1_ACT")
	)
	(segment
		(start 78.8035 -65.111376)
		(end 78.8035 -66.486532)
		(width 0.127)
		(layer "In5.Cu")
		(net "DRIVE_1_ACT")
	)
	(segment
		(start 78.814168 -65.100708)
		(end 78.8035 -65.111376)
		(width 0.127)
		(layer "In5.Cu")
		(net "DRIVE_1_ACT")
	)
	(segment
		(start 72.99579 -25.457658)
		(end 72.99579 -27.979116)
		(width 0.127)
		(layer "In5.Cu")
		(net "DRIVE_1_ACT")
	)
	(segment
		(start 106.396282 -83.0199)
		(end 106.999786 -82.416396)
		(width 0.127)
		(layer "In5.Cu")
		(net "DRIVE_1_ACT")
	)
	(segment
		(start 84.636356 -80.61579)
		(end 87.167466 -83.1469)
		(width 0.127)
		(layer "In5.Cu")
		(net "DRIVE_1_ACT")
	)
	(segment
		(start 115.426998 -20.717002)
		(end 115.189 -20.955)
		(width 0.127)
		(layer "F.Cu")
		(net "DRIVE_0_ACT")
	)
	(segment
		(start 115.426998 -7.373112)
		(end 115.426998 -20.717002)
		(width 0.127)
		(layer "F.Cu")
		(net "DRIVE_0_ACT")
	)
	(segment
		(start 76.98105 -23.682706)
		(end 75.207368 -23.682706)
		(width 0.127)
		(layer "F.Cu")
		(net "DRIVE_0_ACT")
	)
	(segment
		(start 71.97979 -25.149556)
		(end 71.97979 -25.457658)
		(width 0.127)
		(layer "F.Cu")
		(net "DRIVE_0_ACT")
	)
	(segment
		(start 73.44664 -23.682706)
		(end 71.97979 -25.149556)
		(width 0.127)
		(layer "F.Cu")
		(net "DRIVE_0_ACT")
	)
	(segment
		(start 115.189 -20.955)
		(end 79.708756 -20.955)
		(width 0.127)
		(layer "F.Cu")
		(net "DRIVE_0_ACT")
	)
	(segment
		(start 116.59997 -6.20014)
		(end 115.426998 -7.373112)
		(width 0.127)
		(layer "F.Cu")
		(net "DRIVE_0_ACT")
	)
	(segment
		(start 79.708756 -20.955)
		(end 76.98105 -23.682706)
		(width 0.127)
		(layer "F.Cu")
		(net "DRIVE_0_ACT")
	)
	(segment
		(start 75.207368 -23.682706)
		(end 73.44664 -23.682706)
		(width 0.127)
		(layer "F.Cu")
		(net "DRIVE_0_ACT")
	)
	(segment
		(start 107.499912 -82.500216)
		(end 107.00004 -83.000088)
		(width 0.127)
		(layer "F.Cu")
		(net "DRIVE_0_ACT")
	)
	(via
		(at 75.207368 -23.682706)
		(size 0.6604)
		(drill 0.3302)
		(layers "F.Cu" "B.Cu")
		(net "DRIVE_0_ACT")
	)
	(via
		(at 107.00004 -83.000088)
		(size 0.4572)
		(drill 0.2032)
		(layers "F.Cu" "B.Cu")
		(net "DRIVE_0_ACT")
	)
	(via
		(at 71.97979 -25.457658)
		(size 0.508)
		(drill 0.254)
		(layers "F.Cu" "B.Cu")
		(net "DRIVE_0_ACT")
	)
	(segment
		(start 78.2955 -64.90081)
		(end 78.2955 -66.697098)
		(width 0.127)
		(layer "In5.Cu")
		(net "DRIVE_0_ACT")
	)
	(segment
		(start 78.306168 -64.890142)
		(end 78.2955 -64.90081)
		(width 0.127)
		(layer "In5.Cu")
		(net "DRIVE_0_ACT")
	)
	(segment
		(start 71.97979 -25.457658)
		(end 71.97979 -27.681682)
		(width 0.127)
		(layer "In5.Cu")
		(net "DRIVE_0_ACT")
	)
	(segment
		(start 78.306168 -64.428116)
		(end 78.306168 -64.890142)
		(width 0.127)
		(layer "In5.Cu")
		(net "DRIVE_0_ACT")
	)
	(segment
		(start 81.88198 -70.283578)
		(end 81.88198 -76.991464)
		(width 0.127)
		(layer "In5.Cu")
		(net "DRIVE_0_ACT")
	)
	(segment
		(start 78.2955 -66.697098)
		(end 81.88198 -70.283578)
		(width 0.127)
		(layer "In5.Cu")
		(net "DRIVE_0_ACT")
	)
	(segment
		(start 86.9569 -83.6549)
		(end 96.730566 -83.6549)
		(width 0.127)
		(layer "In5.Cu")
		(net "DRIVE_0_ACT")
	)
	(segment
		(start 105.806748 -84.19338)
		(end 107.00004 -83.000088)
		(width 0.127)
		(layer "In5.Cu")
		(net "DRIVE_0_ACT")
	)
	(segment
		(start 76.84897 -62.347602)
		(end 78.306422 -63.805054)
		(width 0.127)
		(layer "In5.Cu")
		(net "DRIVE_0_ACT")
	)
	(segment
		(start 81.88198 -76.991464)
		(end 83.828128 -78.937612)
		(width 0.127)
		(layer "In5.Cu")
		(net "DRIVE_0_ACT")
	)
	(segment
		(start 76.84897 -32.550862)
		(end 76.84897 -62.347602)
		(width 0.127)
		(layer "In5.Cu")
		(net "DRIVE_0_ACT")
	)
	(segment
		(start 96.730566 -83.6549)
		(end 97.269046 -84.19338)
		(width 0.127)
		(layer "In5.Cu")
		(net "DRIVE_0_ACT")
	)
	(segment
		(start 84.128356 -80.826356)
		(end 86.9569 -83.6549)
		(width 0.127)
		(layer "In5.Cu")
		(net "DRIVE_0_ACT")
	)
	(segment
		(start 83.828128 -80.01)
		(end 84.128356 -80.310228)
		(width 0.127)
		(layer "In5.Cu")
		(net "DRIVE_0_ACT")
	)
	(segment
		(start 78.306422 -64.427862)
		(end 78.306168 -64.428116)
		(width 0.127)
		(layer "In5.Cu")
		(net "DRIVE_0_ACT")
	)
	(segment
		(start 83.828128 -78.937612)
		(end 83.828128 -80.01)
		(width 0.127)
		(layer "In5.Cu")
		(net "DRIVE_0_ACT")
	)
	(segment
		(start 78.306422 -63.805054)
		(end 78.306422 -64.427862)
		(width 0.127)
		(layer "In5.Cu")
		(net "DRIVE_0_ACT")
	)
	(segment
		(start 71.97979 -27.681682)
		(end 76.84897 -32.550862)
		(width 0.127)
		(layer "In5.Cu")
		(net "DRIVE_0_ACT")
	)
	(segment
		(start 97.269046 -84.19338)
		(end 105.806748 -84.19338)
		(width 0.127)
		(layer "In5.Cu")
		(net "DRIVE_0_ACT")
	)
	(segment
		(start 84.128356 -80.310228)
		(end 84.128356 -80.826356)
		(width 0.127)
		(layer "In5.Cu")
		(net "DRIVE_0_ACT")
	)
	(segment
		(start 160.782 -4.572)
		(end 161.192718 -4.572)
		(width 0.127)
		(layer "F.Cu")
		(net "COMP_SPARE_0_LS")
	)
	(segment
		(start 161.192718 -4.572)
		(end 162.291014 -5.670296)
		(width 0.127)
		(layer "F.Cu")
		(net "COMP_SPARE_0_LS")
	)
	(segment
		(start 160.782 -4.572)
		(end 159.725106 -4.572)
		(width 0.127)
		(layer "F.Cu")
		(net "COMP_SPARE_0_LS")
	)
	(segment
		(start 159.725106 -4.572)
		(end 159.385 -4.912106)
		(width 0.127)
		(layer "F.Cu")
		(net "COMP_SPARE_0_LS")
	)
	(segment
		(start 162.291014 -5.670296)
		(end 162.291014 -6.418072)
		(width 0.127)
		(layer "F.Cu")
		(net "COMP_SPARE_0_LS")
	)
	(via
		(at 160.782 -4.572)
		(size 0.6604)
		(drill 0.3302)
		(layers "F.Cu" "B.Cu")
		(net "COMP_SPARE_0_LS")
	)
	(via
		(at 118.999 -88.265)
		(size 0.508)
		(drill 0.254)
		(layers "F.Cu" "B.Cu")
		(net "COMP_SPARE_0_LS")
	)
	(via
		(at 159.385 -4.912106)
		(size 0.508)
		(drill 0.254)
		(layers "F.Cu" "B.Cu")
		(net "COMP_SPARE_0_LS")
	)
	(segment
		(start 118.999 -88.519)
		(end 118.8466 -88.6714)
		(width 0.127)
		(layer "B.Cu")
		(net "COMP_SPARE_0_LS")
	)
	(segment
		(start 119.7483 -89.2302)
		(end 119.888 -89.0905)
		(width 0.127)
		(layer "B.Cu")
		(net "COMP_SPARE_0_LS")
	)
	(segment
		(start 119.888 -88.904826)
		(end 119.824246 -88.841072)
		(width 0.127)
		(layer "B.Cu")
		(net "COMP_SPARE_0_LS")
	)
	(segment
		(start 118.999 -88.265)
		(end 118.999 -88.519)
		(width 0.127)
		(layer "B.Cu")
		(net "COMP_SPARE_0_LS")
	)
	(segment
		(start 119.888 -89.0905)
		(end 119.888 -88.904826)
		(width 0.127)
		(layer "B.Cu")
		(net "COMP_SPARE_0_LS")
	)
	(segment
		(start 118.9863 -89.2302)
		(end 119.7483 -89.2302)
		(width 0.127)
		(layer "B.Cu")
		(net "COMP_SPARE_0_LS")
	)
	(segment
		(start 119.133874 -87.4395)
		(end 118.872 -87.4395)
		(width 0.127)
		(layer "B.Cu")
		(net "COMP_SPARE_0_LS")
	)
	(segment
		(start 119.824246 -88.129872)
		(end 119.133874 -87.4395)
		(width 0.127)
		(layer "B.Cu")
		(net "COMP_SPARE_0_LS")
	)
	(segment
		(start 118.8466 -88.6714)
		(end 118.8466 -89.0905)
		(width 0.127)
		(layer "B.Cu")
		(net "COMP_SPARE_0_LS")
	)
	(segment
		(start 119.824246 -88.841072)
		(end 119.824246 -88.129872)
		(width 0.127)
		(layer "B.Cu")
		(net "COMP_SPARE_0_LS")
	)
	(segment
		(start 118.8466 -89.0905)
		(end 118.9863 -89.2302)
		(width 0.127)
		(layer "B.Cu")
		(net "COMP_SPARE_0_LS")
	)
	(segment
		(start 123.780804 -83.647788)
		(end 128.909318 -83.647788)
		(width 0.127)
		(layer "In5.Cu")
		(net "COMP_SPARE_0_LS")
	)
	(segment
		(start 141.625828 -75.37069)
		(end 153.962862 -63.033656)
		(width 0.127)
		(layer "In5.Cu")
		(net "COMP_SPARE_0_LS")
	)
	(segment
		(start 155.491942 -33.939226)
		(end 157.536388 -31.89478)
		(width 0.127)
		(layer "In5.Cu")
		(net "COMP_SPARE_0_LS")
	)
	(segment
		(start 157.536388 -6.760718)
		(end 159.385 -4.912106)
		(width 0.127)
		(layer "In5.Cu")
		(net "COMP_SPARE_0_LS")
	)
	(segment
		(start 153.962862 -42.24528)
		(end 155.491942 -40.7162)
		(width 0.127)
		(layer "In5.Cu")
		(net "COMP_SPARE_0_LS")
	)
	(segment
		(start 155.491942 -40.7162)
		(end 155.491942 -33.939226)
		(width 0.127)
		(layer "In5.Cu")
		(net "COMP_SPARE_0_LS")
	)
	(segment
		(start 135.699754 -75.37069)
		(end 141.625828 -75.37069)
		(width 0.127)
		(layer "In5.Cu")
		(net "COMP_SPARE_0_LS")
	)
	(segment
		(start 122.002296 -85.426296)
		(end 123.780804 -83.647788)
		(width 0.127)
		(layer "In5.Cu")
		(net "COMP_SPARE_0_LS")
	)
	(segment
		(start 128.909318 -83.647788)
		(end 131.832858 -80.724248)
		(width 0.127)
		(layer "In5.Cu")
		(net "COMP_SPARE_0_LS")
	)
	(segment
		(start 157.536388 -31.89478)
		(end 157.536388 -6.760718)
		(width 0.127)
		(layer "In5.Cu")
		(net "COMP_SPARE_0_LS")
	)
	(segment
		(start 118.999 -88.265)
		(end 118.999 -87.924132)
		(width 0.127)
		(layer "In5.Cu")
		(net "COMP_SPARE_0_LS")
	)
	(segment
		(start 153.962862 -63.033656)
		(end 153.962862 -42.24528)
		(width 0.127)
		(layer "In5.Cu")
		(net "COMP_SPARE_0_LS")
	)
	(segment
		(start 121.496836 -85.426296)
		(end 122.002296 -85.426296)
		(width 0.127)
		(layer "In5.Cu")
		(net "COMP_SPARE_0_LS")
	)
	(segment
		(start 131.832858 -79.237586)
		(end 135.699754 -75.37069)
		(width 0.127)
		(layer "In5.Cu")
		(net "COMP_SPARE_0_LS")
	)
	(segment
		(start 131.832858 -80.724248)
		(end 131.832858 -79.237586)
		(width 0.127)
		(layer "In5.Cu")
		(net "COMP_SPARE_0_LS")
	)
	(segment
		(start 118.999 -87.924132)
		(end 121.496836 -85.426296)
		(width 0.127)
		(layer "In5.Cu")
		(net "COMP_SPARE_0_LS")
	)
	(segment
		(start 162.532822 -13.253974)
		(end 162.532822 -13.576046)
		(width 0.127)
		(layer "F.Cu")
		(net "COMP_SPARE_0")
	)
	(segment
		(start 162.691064 -12.056872)
		(end 162.691064 -13.095732)
		(width 0.127)
		(layer "F.Cu")
		(net "COMP_SPARE_0")
	)
	(segment
		(start 161.9758 -14.133068)
		(end 160.615122 -14.133068)
		(width 0.127)
		(layer "F.Cu")
		(net "COMP_SPARE_0")
	)
	(segment
		(start 162.532822 -13.576046)
		(end 161.9758 -14.133068)
		(width 0.127)
		(layer "F.Cu")
		(net "COMP_SPARE_0")
	)
	(segment
		(start 159.740854 -14.133068)
		(end 160.615122 -14.133068)
		(width 0.127)
		(layer "F.Cu")
		(net "COMP_SPARE_0")
	)
	(segment
		(start 159.411162 -11.054842)
		(end 159.411162 -13.803376)
		(width 0.127)
		(layer "F.Cu")
		(net "COMP_SPARE_0")
	)
	(segment
		(start 162.691064 -13.095732)
		(end 162.532822 -13.253974)
		(width 0.127)
		(layer "F.Cu")
		(net "COMP_SPARE_0")
	)
	(segment
		(start 159.411162 -13.803376)
		(end 159.740854 -14.133068)
		(width 0.127)
		(layer "F.Cu")
		(net "COMP_SPARE_0")
	)
	(via
		(at 159.411162 -11.054842)
		(size 0.508)
		(drill 0.254)
		(layers "F.Cu" "B.Cu")
		(net "COMP_SPARE_0")
	)
	(via
		(at 160.615122 -14.133068)
		(size 0.6604)
		(drill 0.3302)
		(layers "F.Cu" "B.Cu")
		(net "COMP_SPARE_0")
	)
	(segment
		(start 184.58053 -13.327634)
		(end 182.820564 -15.0876)
		(width 0.127)
		(layer "In2.Cu")
		(net "COMP_SPARE_0")
	)
	(segment
		(start 184.58053 -7.097268)
		(end 184.58053 -13.327634)
		(width 0.127)
		(layer "In2.Cu")
		(net "COMP_SPARE_0")
	)
	(segment
		(start 160.810194 -9.65581)
		(end 159.411162 -11.054842)
		(width 0.127)
		(layer "In2.Cu")
		(net "COMP_SPARE_0")
	)
	(segment
		(start 185.399934 -6.277864)
		(end 184.58053 -7.097268)
		(width 0.127)
		(layer "In2.Cu")
		(net "COMP_SPARE_0")
	)
	(segment
		(start 164.916612 -9.65581)
		(end 160.810194 -9.65581)
		(width 0.127)
		(layer "In2.Cu")
		(net "COMP_SPARE_0")
	)
	(segment
		(start 165.895782 -8.67664)
		(end 164.916612 -9.65581)
		(width 0.127)
		(layer "In2.Cu")
		(net "COMP_SPARE_0")
	)
	(segment
		(start 178.507644 -15.0876)
		(end 172.096684 -8.67664)
		(width 0.127)
		(layer "In2.Cu")
		(net "COMP_SPARE_0")
	)
	(segment
		(start 182.820564 -15.0876)
		(end 178.507644 -15.0876)
		(width 0.127)
		(layer "In2.Cu")
		(net "COMP_SPARE_0")
	)
	(segment
		(start 172.096684 -8.67664)
		(end 165.895782 -8.67664)
		(width 0.127)
		(layer "In2.Cu")
		(net "COMP_SPARE_0")
	)
	(segment
		(start 185.399934 -6.20014)
		(end 185.399934 -6.277864)
		(width 0.127)
		(layer "In2.Cu")
		(net "COMP_SPARE_0")
	)
	(segment
		(start 121.4755 -92.0496)
		(end 121.487692 -92.037408)
		(width 0.127)
		(layer "F.Cu")
		(net "BMC_SPARE_1_LS")
	)
	(segment
		(start 121.487692 -92.037408)
		(end 121.487692 -91.009216)
		(width 0.127)
		(layer "F.Cu")
		(net "BMC_SPARE_1_LS")
	)
	(segment
		(start 64.8462 -18.4404)
		(end 65.35801 -17.92859)
		(width 0.127)
		(layer "F.Cu")
		(net "BMC_SPARE_1_LS")
	)
	(segment
		(start 76.146914 -89.439242)
		(end 72.913494 -86.205822)
		(width 0.127)
		(layer "F.Cu")
		(net "BMC_SPARE_1_LS")
	)
	(segment
		(start 80.56753 -93.859858)
		(end 120.782842 -93.859858)
		(width 0.127)
		(layer "F.Cu")
		(net "BMC_SPARE_1_LS")
	)
	(segment
		(start 70.35038 -86.205822)
		(end 67.006216 -82.861658)
		(width 0.127)
		(layer "F.Cu")
		(net "BMC_SPARE_1_LS")
	)
	(segment
		(start 67.006216 -82.861658)
		(end 64.301116 -82.861658)
		(width 0.127)
		(layer "F.Cu")
		(net "BMC_SPARE_1_LS")
	)
	(segment
		(start 120.782842 -93.859858)
		(end 121.4755 -93.1672)
		(width 0.127)
		(layer "F.Cu")
		(net "BMC_SPARE_1_LS")
	)
	(segment
		(start 72.913494 -86.205822)
		(end 70.35038 -86.205822)
		(width 0.127)
		(layer "F.Cu")
		(net "BMC_SPARE_1_LS")
	)
	(segment
		(start 76.146914 -89.439242)
		(end 80.56753 -93.859858)
		(width 0.127)
		(layer "F.Cu")
		(net "BMC_SPARE_1_LS")
	)
	(segment
		(start 65.35801 -17.92859)
		(end 66.319908 -17.92859)
		(width 0.127)
		(layer "F.Cu")
		(net "BMC_SPARE_1_LS")
	)
	(segment
		(start 121.4755 -93.1672)
		(end 121.4755 -92.0496)
		(width 0.127)
		(layer "F.Cu")
		(net "BMC_SPARE_1_LS")
	)
	(via
		(at 64.8462 -18.4404)
		(size 0.508)
		(drill 0.254)
		(layers "F.Cu" "B.Cu")
		(net "BMC_SPARE_1_LS")
	)
	(via
		(at 86.868 -35.9664)
		(size 0.508)
		(drill 0.254)
		(layers "F.Cu" "B.Cu")
		(net "BMC_SPARE_1_LS")
	)
	(via
		(at 76.146914 -89.439242)
		(size 0.6604)
		(drill 0.3302)
		(layers "F.Cu" "B.Cu")
		(net "BMC_SPARE_1_LS")
	)
	(via
		(at 64.301116 -82.861658)
		(size 0.508)
		(drill 0.254)
		(layers "F.Cu" "B.Cu")
		(net "BMC_SPARE_1_LS")
	)
	(segment
		(start 64.897 -82.265774)
		(end 64.897 -77.404722)
		(width 0.127)
		(layer "In2.Cu")
		(net "BMC_SPARE_1_LS")
	)
	(segment
		(start 78.66507 -65.0367)
		(end 82.589878 -61.111892)
		(width 0.127)
		(layer "In2.Cu")
		(net "BMC_SPARE_1_LS")
	)
	(segment
		(start 82.589878 -61.111892)
		(end 82.589878 -51.703478)
		(width 0.127)
		(layer "In2.Cu")
		(net "BMC_SPARE_1_LS")
	)
	(segment
		(start 78.66507 -65.539112)
		(end 78.66507 -65.0367)
		(width 0.127)
		(layer "In2.Cu")
		(net "BMC_SPARE_1_LS")
	)
	(segment
		(start 73.86193 -68.439792)
		(end 75.76439 -68.439792)
		(width 0.127)
		(layer "In2.Cu")
		(net "BMC_SPARE_1_LS")
	)
	(segment
		(start 64.301116 -82.861658)
		(end 64.897 -82.265774)
		(width 0.127)
		(layer "In2.Cu")
		(net "BMC_SPARE_1_LS")
	)
	(segment
		(start 82.589878 -51.703478)
		(end 85.32876 -48.964596)
		(width 0.127)
		(layer "In2.Cu")
		(net "BMC_SPARE_1_LS")
	)
	(segment
		(start 64.897 -77.404722)
		(end 73.86193 -68.439792)
		(width 0.127)
		(layer "In2.Cu")
		(net "BMC_SPARE_1_LS")
	)
	(segment
		(start 85.32876 -48.964596)
		(end 85.32876 -37.50564)
		(width 0.127)
		(layer "In2.Cu")
		(net "BMC_SPARE_1_LS")
	)
	(segment
		(start 75.76439 -68.439792)
		(end 78.66507 -65.539112)
		(width 0.127)
		(layer "In2.Cu")
		(net "BMC_SPARE_1_LS")
	)
	(segment
		(start 85.32876 -37.50564)
		(end 86.868 -35.9664)
		(width 0.127)
		(layer "In2.Cu")
		(net "BMC_SPARE_1_LS")
	)
	(segment
		(start 68.905882 -18.4404)
		(end 64.8462 -18.4404)
		(width 0.127)
		(layer "In5.Cu")
		(net "BMC_SPARE_1_LS")
	)
	(segment
		(start 79.016098 -22.2504)
		(end 72.715882 -22.2504)
		(width 0.127)
		(layer "In5.Cu")
		(net "BMC_SPARE_1_LS")
	)
	(segment
		(start 86.868 -35.9664)
		(end 86.7664 -35.8648)
		(width 0.127)
		(layer "In5.Cu")
		(net "BMC_SPARE_1_LS")
	)
	(segment
		(start 72.715882 -22.2504)
		(end 68.905882 -18.4404)
		(width 0.127)
		(layer "In5.Cu")
		(net "BMC_SPARE_1_LS")
	)
	(segment
		(start 86.7664 -30.000702)
		(end 79.016098 -22.2504)
		(width 0.127)
		(layer "In5.Cu")
		(net "BMC_SPARE_1_LS")
	)
	(segment
		(start 86.7664 -35.8648)
		(end 86.7664 -30.000702)
		(width 0.127)
		(layer "In5.Cu")
		(net "BMC_SPARE_1_LS")
	)
	(segment
		(start 70.2818 -16.9418)
		(end 70.86854 -17.52854)
		(width 0.127)
		(layer "F.Cu")
		(net "BMC_SPARE_1")
	)
	(segment
		(start 70.86854 -17.52854)
		(end 71.958708 -17.52854)
		(width 0.127)
		(layer "F.Cu")
		(net "BMC_SPARE_1")
	)
	(via
		(at 90.297 -36.703)
		(size 0.508)
		(drill 0.254)
		(layers "F.Cu" "B.Cu")
		(net "BMC_SPARE_1")
	)
	(via
		(at 70.2818 -16.9418)
		(size 0.508)
		(drill 0.254)
		(layers "F.Cu" "B.Cu")
		(net "BMC_SPARE_1")
	)
	(segment
		(start 178.125882 -16.212566)
		(end 171.605956 -9.69264)
		(width 0.127)
		(layer "In2.Cu")
		(net "BMC_SPARE_1")
	)
	(segment
		(start 137.950956 -20.545044)
		(end 122.174 -36.322)
		(width 0.127)
		(layer "In2.Cu")
		(net "BMC_SPARE_1")
	)
	(segment
		(start 158.397702 -11.557)
		(end 149.409658 -20.545044)
		(width 0.127)
		(layer "In2.Cu")
		(net "BMC_SPARE_1")
	)
	(segment
		(start 90.678 -36.322)
		(end 90.297 -36.703)
		(width 0.127)
		(layer "In2.Cu")
		(net "BMC_SPARE_1")
	)
	(segment
		(start 122.174 -36.322)
		(end 90.678 -36.322)
		(width 0.127)
		(layer "In2.Cu")
		(net "BMC_SPARE_1")
	)
	(segment
		(start 168.404032 -9.69264)
		(end 166.539672 -11.557)
		(width 0.127)
		(layer "In2.Cu")
		(net "BMC_SPARE_1")
	)
	(segment
		(start 149.409658 -20.545044)
		(end 137.950956 -20.545044)
		(width 0.127)
		(layer "In2.Cu")
		(net "BMC_SPARE_1")
	)
	(segment
		(start 166.539672 -11.557)
		(end 158.397702 -11.557)
		(width 0.127)
		(layer "In2.Cu")
		(net "BMC_SPARE_1")
	)
	(segment
		(start 186.014106 -16.212566)
		(end 178.125882 -16.212566)
		(width 0.127)
		(layer "In2.Cu")
		(net "BMC_SPARE_1")
	)
	(segment
		(start 188.354208 -13.872464)
		(end 186.014106 -16.212566)
		(width 0.127)
		(layer "In2.Cu")
		(net "BMC_SPARE_1")
	)
	(segment
		(start 188.354208 -8.245856)
		(end 188.354208 -13.872464)
		(width 0.127)
		(layer "In2.Cu")
		(net "BMC_SPARE_1")
	)
	(segment
		(start 171.605956 -9.69264)
		(end 168.404032 -9.69264)
		(width 0.127)
		(layer "In2.Cu")
		(net "BMC_SPARE_1")
	)
	(segment
		(start 188.999876 -7.600188)
		(end 188.354208 -8.245856)
		(width 0.127)
		(layer "In2.Cu")
		(net "BMC_SPARE_1")
	)
	(segment
		(start 89.385394 -34.737802)
		(end 90.297 -35.649408)
		(width 0.127)
		(layer "In5.Cu")
		(net "BMC_SPARE_1")
	)
	(segment
		(start 80.2386 -19.7612)
		(end 89.385394 -28.907994)
		(width 0.127)
		(layer "In5.Cu")
		(net "BMC_SPARE_1")
	)
	(segment
		(start 90.297 -35.649408)
		(end 90.297 -36.703)
		(width 0.127)
		(layer "In5.Cu")
		(net "BMC_SPARE_1")
	)
	(segment
		(start 89.385394 -28.907994)
		(end 89.385394 -34.737802)
		(width 0.127)
		(layer "In5.Cu")
		(net "BMC_SPARE_1")
	)
	(segment
		(start 75.694286 -14.399514)
		(end 79.271114 -14.399514)
		(width 0.127)
		(layer "In5.Cu")
		(net "BMC_SPARE_1")
	)
	(segment
		(start 73.152 -16.9418)
		(end 75.694286 -14.399514)
		(width 0.127)
		(layer "In5.Cu")
		(net "BMC_SPARE_1")
	)
	(segment
		(start 70.2818 -16.9418)
		(end 73.152 -16.9418)
		(width 0.127)
		(layer "In5.Cu")
		(net "BMC_SPARE_1")
	)
	(segment
		(start 79.271114 -14.399514)
		(end 80.2386 -15.367)
		(width 0.127)
		(layer "In5.Cu")
		(net "BMC_SPARE_1")
	)
	(segment
		(start 80.2386 -15.367)
		(end 80.2386 -19.7612)
		(width 0.127)
		(layer "In5.Cu")
		(net "BMC_SPARE_1")
	)
	(segment
		(start 161.490914 -7.427214)
		(end 161.490914 -6.418072)
		(width 0.127)
		(layer "F.Cu")
		(net "BMC_SPARE_0_LS")
	)
	(segment
		(start 124.3584 -93.271086)
		(end 122.60707 -95.022416)
		(width 0.127)
		(layer "F.Cu")
		(net "BMC_SPARE_0_LS")
	)
	(segment
		(start 66.936874 -83.743292)
		(end 64.32423 -83.743292)
		(width 0.127)
		(layer "F.Cu")
		(net "BMC_SPARE_0_LS")
	)
	(segment
		(start 72.629522 -86.713822)
		(end 69.907404 -86.713822)
		(width 0.127)
		(layer "F.Cu")
		(net "BMC_SPARE_0_LS")
	)
	(segment
		(start 160.633664 -8.028686)
		(end 160.889442 -8.028686)
		(width 0.127)
		(layer "F.Cu")
		(net "BMC_SPARE_0_LS")
	)
	(segment
		(start 80.938116 -95.022416)
		(end 72.629522 -86.713822)
		(width 0.127)
		(layer "F.Cu")
		(net "BMC_SPARE_0_LS")
	)
	(segment
		(start 160.889442 -8.028686)
		(end 161.490914 -7.427214)
		(width 0.127)
		(layer "F.Cu")
		(net "BMC_SPARE_0_LS")
	)
	(segment
		(start 69.907404 -86.713822)
		(end 66.936874 -83.743292)
		(width 0.127)
		(layer "F.Cu")
		(net "BMC_SPARE_0_LS")
	)
	(segment
		(start 122.60707 -95.022416)
		(end 80.938116 -95.022416)
		(width 0.127)
		(layer "F.Cu")
		(net "BMC_SPARE_0_LS")
	)
	(via
		(at 64.32423 -83.743292)
		(size 0.508)
		(drill 0.254)
		(layers "F.Cu" "B.Cu")
		(net "BMC_SPARE_0_LS")
	)
	(via
		(at 124.3584 -93.271086)
		(size 0.508)
		(drill 0.254)
		(layers "F.Cu" "B.Cu")
		(net "BMC_SPARE_0_LS")
	)
	(via
		(at 160.633664 -8.028686)
		(size 0.508)
		(drill 0.254)
		(layers "F.Cu" "B.Cu")
		(net "BMC_SPARE_0_LS")
	)
	(via
		(at 122.391424 -89.574624)
		(size 0.6096)
		(drill 0.3048)
		(layers "F.Cu" "B.Cu")
		(net "BMC_SPARE_0_LS")
	)
	(segment
		(start 123.594876 -90.137742)
		(end 123.594876 -91.23553)
		(width 0.127)
		(layer "B.Cu")
		(net "BMC_SPARE_0_LS")
	)
	(segment
		(start 122.391424 -89.574624)
		(end 122.391424 -89.22893)
		(width 0.127)
		(layer "B.Cu")
		(net "BMC_SPARE_0_LS")
	)
	(segment
		(start 122.391424 -89.888314)
		(end 122.640852 -90.137742)
		(width 0.127)
		(layer "B.Cu")
		(net "BMC_SPARE_0_LS")
	)
	(segment
		(start 123.7615 -92.66936)
		(end 123.7615 -91.506294)
		(width 0.127)
		(layer "B.Cu")
		(net "BMC_SPARE_0_LS")
	)
	(segment
		(start 122.61723 -89.003124)
		(end 123.665742 -89.003124)
		(width 0.127)
		(layer "B.Cu")
		(net "BMC_SPARE_0_LS")
	)
	(segment
		(start 123.7615 -91.506294)
		(end 123.594876 -91.33967)
		(width 0.127)
		(layer "B.Cu")
		(net "BMC_SPARE_0_LS")
	)
	(segment
		(start 122.391424 -89.574624)
		(end 122.391424 -89.888314)
		(width 0.127)
		(layer "B.Cu")
		(net "BMC_SPARE_0_LS")
	)
	(segment
		(start 122.640852 -90.137742)
		(end 123.594876 -90.137742)
		(width 0.127)
		(layer "B.Cu")
		(net "BMC_SPARE_0_LS")
	)
	(segment
		(start 124.3584 -93.26626)
		(end 123.7615 -92.66936)
		(width 0.127)
		(layer "B.Cu")
		(net "BMC_SPARE_0_LS")
	)
	(segment
		(start 123.594876 -91.33967)
		(end 123.594876 -91.23553)
		(width 0.127)
		(layer "B.Cu")
		(net "BMC_SPARE_0_LS")
	)
	(segment
		(start 124.3584 -93.271086)
		(end 124.3584 -93.26626)
		(width 0.127)
		(layer "B.Cu")
		(net "BMC_SPARE_0_LS")
	)
	(segment
		(start 122.391424 -89.22893)
		(end 122.61723 -89.003124)
		(width 0.127)
		(layer "B.Cu")
		(net "BMC_SPARE_0_LS")
	)
	(segment
		(start 83.097878 -61.322458)
		(end 79.19085 -65.229486)
		(width 0.127)
		(layer "In2.Cu")
		(net "BMC_SPARE_0_LS")
	)
	(segment
		(start 85.83676 -38.6842)
		(end 85.83676 -49.175162)
		(width 0.127)
		(layer "In2.Cu")
		(net "BMC_SPARE_0_LS")
	)
	(segment
		(start 79.19085 -65.731898)
		(end 75.946508 -68.97624)
		(width 0.127)
		(layer "In2.Cu")
		(net "BMC_SPARE_0_LS")
	)
	(segment
		(start 88.68029 -34.278062)
		(end 87.761572 -35.19678)
		(width 0.127)
		(layer "In2.Cu")
		(net "BMC_SPARE_0_LS")
	)
	(segment
		(start 137.108692 -18.513044)
		(end 121.343674 -34.278062)
		(width 0.127)
		(layer "In2.Cu")
		(net "BMC_SPARE_0_LS")
	)
	(segment
		(start 65.405 -77.615288)
		(end 65.405 -82.662522)
		(width 0.127)
		(layer "In2.Cu")
		(net "BMC_SPARE_0_LS")
	)
	(segment
		(start 83.097878 -51.914044)
		(end 83.097878 -61.322458)
		(width 0.127)
		(layer "In2.Cu")
		(net "BMC_SPARE_0_LS")
	)
	(segment
		(start 160.144968 -8.028686)
		(end 159.57804 -7.461758)
		(width 0.127)
		(layer "In2.Cu")
		(net "BMC_SPARE_0_LS")
	)
	(segment
		(start 65.405 -82.662522)
		(end 64.32423 -83.743292)
		(width 0.127)
		(layer "In2.Cu")
		(net "BMC_SPARE_0_LS")
	)
	(segment
		(start 75.946508 -68.97624)
		(end 74.044302 -68.97624)
		(width 0.127)
		(layer "In2.Cu")
		(net "BMC_SPARE_0_LS")
	)
	(segment
		(start 160.633664 -8.028686)
		(end 160.144968 -8.028686)
		(width 0.127)
		(layer "In2.Cu")
		(net "BMC_SPARE_0_LS")
	)
	(segment
		(start 87.761572 -36.759388)
		(end 85.83676 -38.6842)
		(width 0.127)
		(layer "In2.Cu")
		(net "BMC_SPARE_0_LS")
	)
	(segment
		(start 158.954978 -7.461758)
		(end 147.903692 -18.513044)
		(width 0.127)
		(layer "In2.Cu")
		(net "BMC_SPARE_0_LS")
	)
	(segment
		(start 79.19085 -65.229486)
		(end 79.19085 -65.731898)
		(width 0.127)
		(layer "In2.Cu")
		(net "BMC_SPARE_0_LS")
	)
	(segment
		(start 121.343674 -34.278062)
		(end 88.68029 -34.278062)
		(width 0.127)
		(layer "In2.Cu")
		(net "BMC_SPARE_0_LS")
	)
	(segment
		(start 85.83676 -49.175162)
		(end 83.097878 -51.914044)
		(width 0.127)
		(layer "In2.Cu")
		(net "BMC_SPARE_0_LS")
	)
	(segment
		(start 159.57804 -7.461758)
		(end 158.954978 -7.461758)
		(width 0.127)
		(layer "In2.Cu")
		(net "BMC_SPARE_0_LS")
	)
	(segment
		(start 87.761572 -35.19678)
		(end 87.761572 -36.759388)
		(width 0.127)
		(layer "In2.Cu")
		(net "BMC_SPARE_0_LS")
	)
	(segment
		(start 74.044302 -68.97624)
		(end 65.405 -77.615288)
		(width 0.127)
		(layer "In2.Cu")
		(net "BMC_SPARE_0_LS")
	)
	(segment
		(start 147.903692 -18.513044)
		(end 137.108692 -18.513044)
		(width 0.127)
		(layer "In2.Cu")
		(net "BMC_SPARE_0_LS")
	)
	(segment
		(start 161.890964 -11.111738)
		(end 161.890964 -12.056872)
		(width 0.127)
		(layer "F.Cu")
		(net "BMC_SPARE_0")
	)
	(segment
		(start 162.596576 -10.406126)
		(end 161.890964 -11.111738)
		(width 0.127)
		(layer "F.Cu")
		(net "BMC_SPARE_0")
	)
	(via
		(at 162.596576 -10.406126)
		(size 0.508)
		(drill 0.254)
		(layers "F.Cu" "B.Cu")
		(net "BMC_SPARE_0")
	)
	(segment
		(start 185.80354 -15.704566)
		(end 187.846208 -13.661898)
		(width 0.127)
		(layer "In2.Cu")
		(net "BMC_SPARE_0")
	)
	(segment
		(start 187.846208 -7.595108)
		(end 188.999876 -6.44144)
		(width 0.127)
		(layer "In2.Cu")
		(net "BMC_SPARE_0")
	)
	(segment
		(start 171.886118 -9.18464)
		(end 178.406044 -15.704566)
		(width 0.127)
		(layer "In2.Cu")
		(net "BMC_SPARE_0")
	)
	(segment
		(start 187.846208 -13.661898)
		(end 187.846208 -7.595108)
		(width 0.127)
		(layer "In2.Cu")
		(net "BMC_SPARE_0")
	)
	(segment
		(start 178.406044 -15.704566)
		(end 185.80354 -15.704566)
		(width 0.127)
		(layer "In2.Cu")
		(net "BMC_SPARE_0")
	)
	(segment
		(start 188.999876 -6.44144)
		(end 188.999876 -6.20014)
		(width 0.127)
		(layer "In2.Cu")
		(net "BMC_SPARE_0")
	)
	(segment
		(start 162.838892 -10.16381)
		(end 165.127178 -10.16381)
		(width 0.127)
		(layer "In2.Cu")
		(net "BMC_SPARE_0")
	)
	(segment
		(start 165.127178 -10.16381)
		(end 166.106348 -9.18464)
		(width 0.127)
		(layer "In2.Cu")
		(net "BMC_SPARE_0")
	)
	(segment
		(start 166.106348 -9.18464)
		(end 171.886118 -9.18464)
		(width 0.127)
		(layer "In2.Cu")
		(net "BMC_SPARE_0")
	)
	(segment
		(start 162.596576 -10.406126)
		(end 162.838892 -10.16381)
		(width 0.127)
		(layer "In2.Cu")
		(net "BMC_SPARE_0")
	)
	(segment
		(start 95.0595 -87.503)
		(end 95.0595 -88.2904)
		(width 0.127)
		(layer "F.Cu")
		(net "BMC_RMT_HEARTBEAT_LS")
	)
	(segment
		(start 163.889944 -7.290816)
		(end 163.529264 -7.651496)
		(width 0.127)
		(layer "F.Cu")
		(net "BMC_RMT_HEARTBEAT_LS")
	)
	(segment
		(start 163.529264 -7.651496)
		(end 163.529264 -8.019542)
		(width 0.127)
		(layer "F.Cu")
		(net "BMC_RMT_HEARTBEAT_LS")
	)
	(segment
		(start 117.500146 -77.500226)
		(end 118.000018 -77.000354)
		(width 0.127)
		(layer "F.Cu")
		(net "BMC_RMT_HEARTBEAT_LS")
	)
	(segment
		(start 97.536 -87.503)
		(end 95.0595 -87.503)
		(width 0.127)
		(layer "F.Cu")
		(net "BMC_RMT_HEARTBEAT_LS")
	)
	(segment
		(start 163.889944 -6.418072)
		(end 163.889944 -7.290816)
		(width 0.127)
		(layer "F.Cu")
		(net "BMC_RMT_HEARTBEAT_LS")
	)
	(via
		(at 118.000018 -77.000354)
		(size 0.4572)
		(drill 0.2032)
		(layers "F.Cu" "B.Cu")
		(net "BMC_RMT_HEARTBEAT_LS")
	)
	(via
		(at 163.529264 -8.019542)
		(size 0.508)
		(drill 0.254)
		(layers "F.Cu" "B.Cu")
		(net "BMC_RMT_HEARTBEAT_LS")
	)
	(via
		(at 76.774548 -66.711068)
		(size 0.508)
		(drill 0.254)
		(layers "F.Cu" "B.Cu")
		(net "BMC_RMT_HEARTBEAT_LS")
	)
	(via
		(at 95.0595 -88.2904)
		(size 0.508)
		(drill 0.254)
		(layers "F.Cu" "B.Cu")
		(net "BMC_RMT_HEARTBEAT_LS")
	)
	(segment
		(start 136.81456 -18.005044)
		(end 147.403566 -18.005044)
		(width 0.127)
		(layer "In2.Cu")
		(net "BMC_RMT_HEARTBEAT_LS")
	)
	(segment
		(start 77.72908 -65.086484)
		(end 82.081878 -60.733686)
		(width 0.127)
		(layer "In2.Cu")
		(net "BMC_RMT_HEARTBEAT_LS")
	)
	(segment
		(start 76.774548 -66.711068)
		(end 77.72908 -65.756536)
		(width 0.127)
		(layer "In2.Cu")
		(net "BMC_RMT_HEARTBEAT_LS")
	)
	(segment
		(start 121.240804 -33.5788)
		(end 136.81456 -18.005044)
		(width 0.127)
		(layer "In2.Cu")
		(net "BMC_RMT_HEARTBEAT_LS")
	)
	(segment
		(start 159.518604 -5.890006)
		(end 161.399728 -5.890006)
		(width 0.127)
		(layer "In2.Cu")
		(net "BMC_RMT_HEARTBEAT_LS")
	)
	(segment
		(start 147.403566 -18.005044)
		(end 159.518604 -5.890006)
		(width 0.127)
		(layer "In2.Cu")
		(net "BMC_RMT_HEARTBEAT_LS")
	)
	(segment
		(start 84.82076 -37.295074)
		(end 88.537034 -33.5788)
		(width 0.127)
		(layer "In2.Cu")
		(net "BMC_RMT_HEARTBEAT_LS")
	)
	(segment
		(start 161.399728 -5.890006)
		(end 163.529264 -8.019542)
		(width 0.127)
		(layer "In2.Cu")
		(net "BMC_RMT_HEARTBEAT_LS")
	)
	(segment
		(start 88.537034 -33.5788)
		(end 121.240804 -33.5788)
		(width 0.127)
		(layer "In2.Cu")
		(net "BMC_RMT_HEARTBEAT_LS")
	)
	(segment
		(start 82.081878 -51.492658)
		(end 84.82076 -48.753776)
		(width 0.127)
		(layer "In2.Cu")
		(net "BMC_RMT_HEARTBEAT_LS")
	)
	(segment
		(start 84.82076 -48.753776)
		(end 84.82076 -37.295074)
		(width 0.127)
		(layer "In2.Cu")
		(net "BMC_RMT_HEARTBEAT_LS")
	)
	(segment
		(start 77.72908 -65.756536)
		(end 77.72908 -65.086484)
		(width 0.127)
		(layer "In2.Cu")
		(net "BMC_RMT_HEARTBEAT_LS")
	)
	(segment
		(start 82.081878 -60.733686)
		(end 82.081878 -51.492658)
		(width 0.127)
		(layer "In2.Cu")
		(net "BMC_RMT_HEARTBEAT_LS")
	)
	(segment
		(start 116.000022 -79.557118)
		(end 116.60632 -78.95082)
		(width 0.127)
		(layer "In5.Cu")
		(net "BMC_RMT_HEARTBEAT_LS")
	)
	(segment
		(start 83.278218 -83.1215)
		(end 87.240618 -87.0839)
		(width 0.127)
		(layer "In5.Cu")
		(net "BMC_RMT_HEARTBEAT_LS")
	)
	(segment
		(start 80.3021 -79.824072)
		(end 82.2071 -81.729072)
		(width 0.127)
		(layer "In5.Cu")
		(net "BMC_RMT_HEARTBEAT_LS")
	)
	(segment
		(start 117.606318 -77.846682)
		(end 117.606318 -77.83703)
		(width 0.127)
		(layer "In5.Cu")
		(net "BMC_RMT_HEARTBEAT_LS")
	)
	(segment
		(start 117.1702 -78.47838)
		(end 117.5766 -78.07198)
		(width 0.127)
		(layer "In5.Cu")
		(net "BMC_RMT_HEARTBEAT_LS")
	)
	(segment
		(start 80.3021 -76.087986)
		(end 80.3021 -79.824072)
		(width 0.127)
		(layer "In5.Cu")
		(net "BMC_RMT_HEARTBEAT_LS")
	)
	(segment
		(start 76.754736 -68.458588)
		(end 80.12557 -71.829422)
		(width 0.127)
		(layer "In5.Cu")
		(net "BMC_RMT_HEARTBEAT_LS")
	)
	(segment
		(start 115.885976 -79.557118)
		(end 116.000022 -79.557118)
		(width 0.127)
		(layer "In5.Cu")
		(net "BMC_RMT_HEARTBEAT_LS")
	)
	(segment
		(start 82.2071 -81.729072)
		(end 82.2071 -82.846418)
		(width 0.127)
		(layer "In5.Cu")
		(net "BMC_RMT_HEARTBEAT_LS")
	)
	(segment
		(start 80.12557 -75.911456)
		(end 80.3021 -76.087986)
		(width 0.127)
		(layer "In5.Cu")
		(net "BMC_RMT_HEARTBEAT_LS")
	)
	(segment
		(start 95.0595 -88.2904)
		(end 96.440752 -88.2904)
		(width 0.127)
		(layer "In5.Cu")
		(net "BMC_RMT_HEARTBEAT_LS")
	)
	(segment
		(start 114.773964 -80.66913)
		(end 115.885976 -79.557118)
		(width 0.127)
		(layer "In5.Cu")
		(net "BMC_RMT_HEARTBEAT_LS")
	)
	(segment
		(start 103.2383 -85.2297)
		(end 106.7435 -85.2297)
		(width 0.127)
		(layer "In5.Cu")
		(net "BMC_RMT_HEARTBEAT_LS")
	)
	(segment
		(start 87.240618 -87.0839)
		(end 93.853 -87.0839)
		(width 0.127)
		(layer "In5.Cu")
		(net "BMC_RMT_HEARTBEAT_LS")
	)
	(segment
		(start 116.60632 -78.95082)
		(end 116.60632 -78.836774)
		(width 0.127)
		(layer "In5.Cu")
		(net "BMC_RMT_HEARTBEAT_LS")
	)
	(segment
		(start 118.000018 -77.44333)
		(end 118.000018 -77.000354)
		(width 0.127)
		(layer "In5.Cu")
		(net "BMC_RMT_HEARTBEAT_LS")
	)
	(segment
		(start 96.440752 -88.2904)
		(end 97.94748 -86.783672)
		(width 0.127)
		(layer "In5.Cu")
		(net "BMC_RMT_HEARTBEAT_LS")
	)
	(segment
		(start 114.773964 -80.783176)
		(end 114.773964 -80.66913)
		(width 0.127)
		(layer "In5.Cu")
		(net "BMC_RMT_HEARTBEAT_LS")
	)
	(segment
		(start 117.5766 -78.07198)
		(end 117.5766 -77.8764)
		(width 0.127)
		(layer "In5.Cu")
		(net "BMC_RMT_HEARTBEAT_LS")
	)
	(segment
		(start 76.774548 -66.711068)
		(end 76.754736 -66.73088)
		(width 0.127)
		(layer "In5.Cu")
		(net "BMC_RMT_HEARTBEAT_LS")
	)
	(segment
		(start 117.606318 -77.83703)
		(end 118.000018 -77.44333)
		(width 0.127)
		(layer "In5.Cu")
		(net "BMC_RMT_HEARTBEAT_LS")
	)
	(segment
		(start 82.482182 -83.1215)
		(end 83.278218 -83.1215)
		(width 0.127)
		(layer "In5.Cu")
		(net "BMC_RMT_HEARTBEAT_LS")
	)
	(segment
		(start 116.60632 -78.836774)
		(end 116.964714 -78.47838)
		(width 0.127)
		(layer "In5.Cu")
		(net "BMC_RMT_HEARTBEAT_LS")
	)
	(segment
		(start 116.964714 -78.47838)
		(end 117.1702 -78.47838)
		(width 0.127)
		(layer "In5.Cu")
		(net "BMC_RMT_HEARTBEAT_LS")
	)
	(segment
		(start 117.5766 -77.8764)
		(end 117.606318 -77.846682)
		(width 0.127)
		(layer "In5.Cu")
		(net "BMC_RMT_HEARTBEAT_LS")
	)
	(segment
		(start 101.684328 -86.783672)
		(end 103.2383 -85.2297)
		(width 0.127)
		(layer "In5.Cu")
		(net "BMC_RMT_HEARTBEAT_LS")
	)
	(segment
		(start 93.853 -87.0839)
		(end 95.0595 -88.2904)
		(width 0.127)
		(layer "In5.Cu")
		(net "BMC_RMT_HEARTBEAT_LS")
	)
	(segment
		(start 113.16335 -82.39379)
		(end 114.773964 -80.783176)
		(width 0.127)
		(layer "In5.Cu")
		(net "BMC_RMT_HEARTBEAT_LS")
	)
	(segment
		(start 76.754736 -66.73088)
		(end 76.754736 -68.458588)
		(width 0.127)
		(layer "In5.Cu")
		(net "BMC_RMT_HEARTBEAT_LS")
	)
	(segment
		(start 82.2071 -82.846418)
		(end 82.482182 -83.1215)
		(width 0.127)
		(layer "In5.Cu")
		(net "BMC_RMT_HEARTBEAT_LS")
	)
	(segment
		(start 106.7435 -85.2297)
		(end 109.57941 -82.39379)
		(width 0.127)
		(layer "In5.Cu")
		(net "BMC_RMT_HEARTBEAT_LS")
	)
	(segment
		(start 80.12557 -71.829422)
		(end 80.12557 -75.911456)
		(width 0.127)
		(layer "In5.Cu")
		(net "BMC_RMT_HEARTBEAT_LS")
	)
	(segment
		(start 97.94748 -86.783672)
		(end 101.684328 -86.783672)
		(width 0.127)
		(layer "In5.Cu")
		(net "BMC_RMT_HEARTBEAT_LS")
	)
	(segment
		(start 109.57941 -82.39379)
		(end 113.16335 -82.39379)
		(width 0.127)
		(layer "In5.Cu")
		(net "BMC_RMT_HEARTBEAT_LS")
	)
	(segment
		(start 169.231056 -10.778744)
		(end 167.815768 -10.778744)
		(width 0.127)
		(layer "F.Cu")
		(net "BMC_RMT_HEARTBEAT")
	)
	(segment
		(start 164.735256 -10.778744)
		(end 164.289994 -11.224006)
		(width 0.127)
		(layer "F.Cu")
		(net "BMC_RMT_HEARTBEAT")
	)
	(segment
		(start 167.815768 -10.778744)
		(end 164.735256 -10.778744)
		(width 0.127)
		(layer "F.Cu")
		(net "BMC_RMT_HEARTBEAT")
	)
	(segment
		(start 164.289994 -11.224006)
		(end 164.289994 -12.056872)
		(width 0.127)
		(layer "F.Cu")
		(net "BMC_RMT_HEARTBEAT")
	)
	(segment
		(start 169.6466 -10.3632)
		(end 169.231056 -10.778744)
		(width 0.127)
		(layer "F.Cu")
		(net "BMC_RMT_HEARTBEAT")
	)
	(via
		(at 169.6466 -10.3632)
		(size 0.508)
		(drill 0.254)
		(layers "F.Cu" "B.Cu")
		(net "BMC_RMT_HEARTBEAT")
	)
	(via
		(at 167.815768 -10.778744)
		(size 0.6604)
		(drill 0.3302)
		(layers "F.Cu" "B.Cu")
		(net "BMC_RMT_HEARTBEAT")
	)
	(segment
		(start 190.799974 -8.800084)
		(end 190.619126 -8.800084)
		(width 0.127)
		(layer "In2.Cu")
		(net "BMC_RMT_HEARTBEAT")
	)
	(segment
		(start 189.902338 -14.282674)
		(end 187.367672 -16.81734)
		(width 0.127)
		(layer "In2.Cu")
		(net "BMC_RMT_HEARTBEAT")
	)
	(segment
		(start 189.902338 -9.516872)
		(end 189.902338 -14.282674)
		(width 0.127)
		(layer "In2.Cu")
		(net "BMC_RMT_HEARTBEAT")
	)
	(segment
		(start 171.55795 -10.3632)
		(end 169.6466 -10.3632)
		(width 0.127)
		(layer "In2.Cu")
		(net "BMC_RMT_HEARTBEAT")
	)
	(segment
		(start 190.619126 -8.800084)
		(end 189.902338 -9.516872)
		(width 0.127)
		(layer "In2.Cu")
		(net "BMC_RMT_HEARTBEAT")
	)
	(segment
		(start 187.367672 -16.81734)
		(end 178.01209 -16.81734)
		(width 0.127)
		(layer "In2.Cu")
		(net "BMC_RMT_HEARTBEAT")
	)
	(segment
		(start 178.01209 -16.81734)
		(end 171.55795 -10.3632)
		(width 0.127)
		(layer "In2.Cu")
		(net "BMC_RMT_HEARTBEAT")
	)
	(segment
		(start 164.289994 -7.510526)
		(end 164.289994 -6.418072)
		(width 0.127)
		(layer "F.Cu")
		(net "BMC_LOC_HEARTBEAT_LS")
	)
	(segment
		(start 116.500148 -76.500228)
		(end 117.00002 -77.0001)
		(width 0.127)
		(layer "F.Cu")
		(net "BMC_LOC_HEARTBEAT_LS")
	)
	(segment
		(start 164.392864 -8.026654)
		(end 164.392864 -7.613396)
		(width 0.127)
		(layer "F.Cu")
		(net "BMC_LOC_HEARTBEAT_LS")
	)
	(segment
		(start 91.8845 -86.487)
		(end 91.8845 -86.233)
		(width 0.127)
		(layer "F.Cu")
		(net "BMC_LOC_HEARTBEAT_LS")
	)
	(segment
		(start 91.8845 -86.233)
		(end 92.4687 -85.6488)
		(width 0.127)
		(layer "F.Cu")
		(net "BMC_LOC_HEARTBEAT_LS")
	)
	(segment
		(start 164.392864 -7.613396)
		(end 164.289994 -7.510526)
		(width 0.127)
		(layer "F.Cu")
		(net "BMC_LOC_HEARTBEAT_LS")
	)
	(segment
		(start 91.8845 -86.487)
		(end 94.1705 -86.487)
		(width 0.127)
		(layer "F.Cu")
		(net "BMC_LOC_HEARTBEAT_LS")
	)
	(via
		(at 117.00002 -77.0001)
		(size 0.4572)
		(drill 0.2032)
		(layers "F.Cu" "B.Cu")
		(net "BMC_LOC_HEARTBEAT_LS")
	)
	(via
		(at 92.4687 -85.6488)
		(size 0.508)
		(drill 0.254)
		(layers "F.Cu" "B.Cu")
		(net "BMC_LOC_HEARTBEAT_LS")
	)
	(via
		(at 77.798168 -64.21755)
		(size 0.508)
		(drill 0.254)
		(layers "F.Cu" "B.Cu")
		(net "BMC_LOC_HEARTBEAT_LS")
	)
	(via
		(at 164.392864 -8.026654)
		(size 0.508)
		(drill 0.254)
		(layers "F.Cu" "B.Cu")
		(net "BMC_LOC_HEARTBEAT_LS")
	)
	(segment
		(start 81.573878 -60.44184)
		(end 81.573878 -51.282092)
		(width 0.127)
		(layer "In2.Cu")
		(net "BMC_LOC_HEARTBEAT_LS")
	)
	(segment
		(start 84.31276 -37.084508)
		(end 88.428068 -32.9692)
		(width 0.127)
		(layer "In2.Cu")
		(net "BMC_LOC_HEARTBEAT_LS")
	)
	(segment
		(start 121.131838 -32.9692)
		(end 136.603994 -17.497044)
		(width 0.127)
		(layer "In2.Cu")
		(net "BMC_LOC_HEARTBEAT_LS")
	)
	(segment
		(start 81.573878 -51.282092)
		(end 84.31276 -48.54321)
		(width 0.127)
		(layer "In2.Cu")
		(net "BMC_LOC_HEARTBEAT_LS")
	)
	(segment
		(start 88.428068 -32.9692)
		(end 121.131838 -32.9692)
		(width 0.127)
		(layer "In2.Cu")
		(net "BMC_LOC_HEARTBEAT_LS")
	)
	(segment
		(start 136.603994 -17.497044)
		(end 147.193 -17.497044)
		(width 0.127)
		(layer "In2.Cu")
		(net "BMC_LOC_HEARTBEAT_LS")
	)
	(segment
		(start 147.193 -17.497044)
		(end 159.308038 -5.382006)
		(width 0.127)
		(layer "In2.Cu")
		(net "BMC_LOC_HEARTBEAT_LS")
	)
	(segment
		(start 77.798168 -64.21755)
		(end 81.573878 -60.44184)
		(width 0.127)
		(layer "In2.Cu")
		(net "BMC_LOC_HEARTBEAT_LS")
	)
	(segment
		(start 159.308038 -5.382006)
		(end 161.748216 -5.382006)
		(width 0.127)
		(layer "In2.Cu")
		(net "BMC_LOC_HEARTBEAT_LS")
	)
	(segment
		(start 161.748216 -5.382006)
		(end 164.392864 -8.026654)
		(width 0.127)
		(layer "In2.Cu")
		(net "BMC_LOC_HEARTBEAT_LS")
	)
	(segment
		(start 84.31276 -48.54321)
		(end 84.31276 -37.084508)
		(width 0.127)
		(layer "In2.Cu")
		(net "BMC_LOC_HEARTBEAT_LS")
	)
	(segment
		(start 117.00002 -77.0001)
		(end 116.557044 -77.0001)
		(width 0.127)
		(layer "In5.Cu")
		(net "BMC_LOC_HEARTBEAT_LS")
	)
	(segment
		(start 101.219 -86.233)
		(end 93.0529 -86.233)
		(width 0.127)
		(layer "In5.Cu")
		(net "BMC_LOC_HEARTBEAT_LS")
	)
	(segment
		(start 109.462062 -80.926686)
		(end 109.462062 -81.792318)
		(width 0.127)
		(layer "In5.Cu")
		(net "BMC_LOC_HEARTBEAT_LS")
	)
	(segment
		(start 113.393728 -80.04937)
		(end 113.393728 -80.163416)
		(width 0.127)
		(layer "In5.Cu")
		(net "BMC_LOC_HEARTBEAT_LS")
	)
	(segment
		(start 77.798168 -64.21755)
		(end 77.282548 -64.73317)
		(width 0.127)
		(layer "In5.Cu")
		(net "BMC_LOC_HEARTBEAT_LS")
	)
	(segment
		(start 102.2223 -84.7217)
		(end 101.473 -85.471)
		(width 0.127)
		(layer "In5.Cu")
		(net "BMC_LOC_HEARTBEAT_LS")
	)
	(segment
		(start 86.707726 -84.9376)
		(end 91.7575 -84.9376)
		(width 0.127)
		(layer "In5.Cu")
		(net "BMC_LOC_HEARTBEAT_LS")
	)
	(segment
		(start 77.282548 -68.267834)
		(end 80.63357 -71.618856)
		(width 0.127)
		(layer "In5.Cu")
		(net "BMC_LOC_HEARTBEAT_LS")
	)
	(segment
		(start 101.473 -85.979)
		(end 101.219 -86.233)
		(width 0.127)
		(layer "In5.Cu")
		(net "BMC_LOC_HEARTBEAT_LS")
	)
	(segment
		(start 109.813598 -80.57515)
		(end 109.462062 -80.926686)
		(width 0.127)
		(layer "In5.Cu")
		(net "BMC_LOC_HEARTBEAT_LS")
	)
	(segment
		(start 77.282548 -64.73317)
		(end 77.282548 -68.267834)
		(width 0.127)
		(layer "In5.Cu")
		(net "BMC_LOC_HEARTBEAT_LS")
	)
	(segment
		(start 81.317846 -78.606396)
		(end 82.680556 -79.969106)
		(width 0.127)
		(layer "In5.Cu")
		(net "BMC_LOC_HEARTBEAT_LS")
	)
	(segment
		(start 113.393728 -80.163416)
		(end 113.16335 -80.393794)
		(width 0.127)
		(layer "In5.Cu")
		(net "BMC_LOC_HEARTBEAT_LS")
	)
	(segment
		(start 115.117626 -78.484222)
		(end 114.958876 -78.484222)
		(width 0.127)
		(layer "In5.Cu")
		(net "BMC_LOC_HEARTBEAT_LS")
	)
	(segment
		(start 82.680556 -80.91043)
		(end 86.707726 -84.9376)
		(width 0.127)
		(layer "In5.Cu")
		(net "BMC_LOC_HEARTBEAT_LS")
	)
	(segment
		(start 80.63357 -71.618856)
		(end 80.63357 -75.70089)
		(width 0.127)
		(layer "In5.Cu")
		(net "BMC_LOC_HEARTBEAT_LS")
	)
	(segment
		(start 112.867948 -80.57515)
		(end 109.813598 -80.57515)
		(width 0.127)
		(layer "In5.Cu")
		(net "BMC_LOC_HEARTBEAT_LS")
	)
	(segment
		(start 113.049304 -80.393794)
		(end 112.867948 -80.57515)
		(width 0.127)
		(layer "In5.Cu")
		(net "BMC_LOC_HEARTBEAT_LS")
	)
	(segment
		(start 80.63357 -75.70089)
		(end 81.317846 -76.385166)
		(width 0.127)
		(layer "In5.Cu")
		(net "BMC_LOC_HEARTBEAT_LS")
	)
	(segment
		(start 81.317846 -76.385166)
		(end 81.317846 -78.606396)
		(width 0.127)
		(layer "In5.Cu")
		(net "BMC_LOC_HEARTBEAT_LS")
	)
	(segment
		(start 115.426998 -78.17485)
		(end 115.117626 -78.484222)
		(width 0.127)
		(layer "In5.Cu")
		(net "BMC_LOC_HEARTBEAT_LS")
	)
	(segment
		(start 91.7575 -84.9376)
		(end 92.4687 -85.6488)
		(width 0.127)
		(layer "In5.Cu")
		(net "BMC_LOC_HEARTBEAT_LS")
	)
	(segment
		(start 114.958876 -78.484222)
		(end 114.393726 -79.049372)
		(width 0.127)
		(layer "In5.Cu")
		(net "BMC_LOC_HEARTBEAT_LS")
	)
	(segment
		(start 115.426998 -78.0161)
		(end 115.426998 -78.17485)
		(width 0.127)
		(layer "In5.Cu")
		(net "BMC_LOC_HEARTBEAT_LS")
	)
	(segment
		(start 114.393726 -79.163418)
		(end 114.163348 -79.393796)
		(width 0.127)
		(layer "In5.Cu")
		(net "BMC_LOC_HEARTBEAT_LS")
	)
	(segment
		(start 93.0529 -86.233)
		(end 92.4687 -85.6488)
		(width 0.127)
		(layer "In5.Cu")
		(net "BMC_LOC_HEARTBEAT_LS")
	)
	(segment
		(start 116.163344 -77.3938)
		(end 116.049298 -77.3938)
		(width 0.127)
		(layer "In5.Cu")
		(net "BMC_LOC_HEARTBEAT_LS")
	)
	(segment
		(start 114.049302 -79.393796)
		(end 113.393728 -80.04937)
		(width 0.127)
		(layer "In5.Cu")
		(net "BMC_LOC_HEARTBEAT_LS")
	)
	(segment
		(start 114.393726 -79.049372)
		(end 114.393726 -79.163418)
		(width 0.127)
		(layer "In5.Cu")
		(net "BMC_LOC_HEARTBEAT_LS")
	)
	(segment
		(start 114.163348 -79.393796)
		(end 114.049302 -79.393796)
		(width 0.127)
		(layer "In5.Cu")
		(net "BMC_LOC_HEARTBEAT_LS")
	)
	(segment
		(start 82.680556 -79.969106)
		(end 82.680556 -80.91043)
		(width 0.127)
		(layer "In5.Cu")
		(net "BMC_LOC_HEARTBEAT_LS")
	)
	(segment
		(start 109.462062 -81.792318)
		(end 106.53268 -84.7217)
		(width 0.127)
		(layer "In5.Cu")
		(net "BMC_LOC_HEARTBEAT_LS")
	)
	(segment
		(start 101.473 -85.471)
		(end 101.473 -85.979)
		(width 0.127)
		(layer "In5.Cu")
		(net "BMC_LOC_HEARTBEAT_LS")
	)
	(segment
		(start 116.557044 -77.0001)
		(end 116.163344 -77.3938)
		(width 0.127)
		(layer "In5.Cu")
		(net "BMC_LOC_HEARTBEAT_LS")
	)
	(segment
		(start 113.16335 -80.393794)
		(end 113.049304 -80.393794)
		(width 0.127)
		(layer "In5.Cu")
		(net "BMC_LOC_HEARTBEAT_LS")
	)
	(segment
		(start 116.049298 -77.3938)
		(end 115.426998 -78.0161)
		(width 0.127)
		(layer "In5.Cu")
		(net "BMC_LOC_HEARTBEAT_LS")
	)
	(segment
		(start 106.53268 -84.7217)
		(end 102.2223 -84.7217)
		(width 0.127)
		(layer "In5.Cu")
		(net "BMC_LOC_HEARTBEAT_LS")
	)
	(segment
		(start 164.690044 -14.894814)
		(end 163.849812 -15.735046)
		(width 0.127)
		(layer "F.Cu")
		(net "BMC_LOC_HEARTBEAT")
	)
	(segment
		(start 163.849812 -15.735046)
		(end 162.814762 -16.770096)
		(width 0.127)
		(layer "F.Cu")
		(net "BMC_LOC_HEARTBEAT")
	)
	(segment
		(start 79.040228 -13.48994)
		(end 83.730084 -8.800084)
		(width 0.127)
		(layer "F.Cu")
		(net "BMC_LOC_HEARTBEAT")
	)
	(segment
		(start 162.814762 -16.770096)
		(end 162.814762 -17.477486)
		(width 0.127)
		(layer "F.Cu")
		(net "BMC_LOC_HEARTBEAT")
	)
	(segment
		(start 79.040228 -14.907768)
		(end 79.040228 -13.48994)
		(width 0.127)
		(layer "F.Cu")
		(net "BMC_LOC_HEARTBEAT")
	)
	(segment
		(start 83.730084 -8.800084)
		(end 86.000082 -8.800084)
		(width 0.127)
		(layer "F.Cu")
		(net "BMC_LOC_HEARTBEAT")
	)
	(segment
		(start 164.690044 -12.056872)
		(end 164.690044 -14.894814)
		(width 0.127)
		(layer "F.Cu")
		(net "BMC_LOC_HEARTBEAT")
	)
	(via
		(at 162.814762 -17.477486)
		(size 0.508)
		(drill 0.254)
		(layers "F.Cu" "B.Cu")
		(net "BMC_LOC_HEARTBEAT")
	)
	(via
		(at 95.581724 -46.40961)
		(size 0.508)
		(drill 0.254)
		(layers "F.Cu" "B.Cu")
		(net "BMC_LOC_HEARTBEAT")
	)
	(via
		(at 79.040228 -14.907768)
		(size 0.508)
		(drill 0.254)
		(layers "F.Cu" "B.Cu")
		(net "BMC_LOC_HEARTBEAT")
	)
	(via
		(at 163.849812 -15.735046)
		(size 0.6604)
		(drill 0.3302)
		(layers "F.Cu" "B.Cu")
		(net "BMC_LOC_HEARTBEAT")
	)
	(segment
		(start 162.131248 -18.161)
		(end 162.814762 -17.477486)
		(width 0.127)
		(layer "In2.Cu")
		(net "BMC_LOC_HEARTBEAT")
	)
	(segment
		(start 151.354028 -23.85568)
		(end 157.048708 -18.161)
		(width 0.127)
		(layer "In2.Cu")
		(net "BMC_LOC_HEARTBEAT")
	)
	(segment
		(start 102.953058 -46.40961)
		(end 108.849922 -40.512746)
		(width 0.127)
		(layer "In2.Cu")
		(net "BMC_LOC_HEARTBEAT")
	)
	(segment
		(start 139.178538 -23.85568)
		(end 151.354028 -23.85568)
		(width 0.127)
		(layer "In2.Cu")
		(net "BMC_LOC_HEARTBEAT")
	)
	(segment
		(start 157.048708 -18.161)
		(end 162.131248 -18.161)
		(width 0.127)
		(layer "In2.Cu")
		(net "BMC_LOC_HEARTBEAT")
	)
	(segment
		(start 95.581724 -46.40961)
		(end 102.953058 -46.40961)
		(width 0.127)
		(layer "In2.Cu")
		(net "BMC_LOC_HEARTBEAT")
	)
	(segment
		(start 108.849922 -40.512746)
		(end 122.521472 -40.512746)
		(width 0.127)
		(layer "In2.Cu")
		(net "BMC_LOC_HEARTBEAT")
	)
	(segment
		(start 122.521472 -40.512746)
		(end 139.178538 -23.85568)
		(width 0.127)
		(layer "In2.Cu")
		(net "BMC_LOC_HEARTBEAT")
	)
	(segment
		(start 95.581724 -46.002702)
		(end 94.42958 -44.850558)
		(width 0.127)
		(layer "In5.Cu")
		(net "BMC_LOC_HEARTBEAT")
	)
	(segment
		(start 88.369394 -29.447998)
		(end 79.696564 -20.775168)
		(width 0.127)
		(layer "In5.Cu")
		(net "BMC_LOC_HEARTBEAT")
	)
	(segment
		(start 89.88552 -37.30752)
		(end 88.369394 -35.791394)
		(width 0.127)
		(layer "In5.Cu")
		(net "BMC_LOC_HEARTBEAT")
	)
	(segment
		(start 95.581724 -46.40961)
		(end 95.581724 -46.002702)
		(width 0.127)
		(layer "In5.Cu")
		(net "BMC_LOC_HEARTBEAT")
	)
	(segment
		(start 88.369394 -35.791394)
		(end 88.369394 -29.447998)
		(width 0.127)
		(layer "In5.Cu")
		(net "BMC_LOC_HEARTBEAT")
	)
	(segment
		(start 94.42958 -44.850558)
		(end 93.254576 -44.850558)
		(width 0.127)
		(layer "In5.Cu")
		(net "BMC_LOC_HEARTBEAT")
	)
	(segment
		(start 79.696564 -15.564104)
		(end 79.040228 -14.907768)
		(width 0.127)
		(layer "In5.Cu")
		(net "BMC_LOC_HEARTBEAT")
	)
	(segment
		(start 93.254576 -44.850558)
		(end 89.88552 -41.481502)
		(width 0.127)
		(layer "In5.Cu")
		(net "BMC_LOC_HEARTBEAT")
	)
	(segment
		(start 89.88552 -41.481502)
		(end 89.88552 -37.30752)
		(width 0.127)
		(layer "In5.Cu")
		(net "BMC_LOC_HEARTBEAT")
	)
	(segment
		(start 79.696564 -20.775168)
		(end 79.696564 -15.564104)
		(width 0.127)
		(layer "In5.Cu")
		(net "BMC_LOC_HEARTBEAT")
	)
	(segment
		(start 12.8778 -94.356682)
		(end 11.9126 -94.356682)
		(width 0.127)
		(layer "F.Cu")
		(net "VREF3")
	)
	(segment
		(start 11.9126 -94.356682)
		(end 11.9126 -93.3831)
		(width 0.127)
		(layer "F.Cu")
		(net "VREF3")
	)
	(segment
		(start 13.21435 -92.08135)
		(end 12.823444 -92.472256)
		(width 0.127)
		(layer "F.Cu")
		(net "VREF3")
	)
	(segment
		(start 11.9126 -93.3831)
		(end 11.9761 -93.3196)
		(width 0.127)
		(layer "F.Cu")
		(net "VREF3")
	)
	(segment
		(start 13.21435 -90.628978)
		(end 13.21435 -92.08135)
		(width 0.127)
		(layer "F.Cu")
		(net "VREF3")
	)
	(segment
		(start 12.823444 -92.472256)
		(end 11.9761 -93.3196)
		(width 0.127)
		(layer "F.Cu")
		(net "VREF3")
	)
	(via
		(at 12.823444 -92.472256)
		(size 0.6604)
		(drill 0.3302)
		(layers "F.Cu" "B.Cu")
		(net "VREF3")
	)
	(segment
		(start 22.931374 -93.377004)
		(end 22.83333 -93.377004)
		(width 0.127)
		(layer "F.Cu")
		(net "VREF1")
	)
	(segment
		(start 22.83333 -94.405704)
		(end 23.79853 -94.405704)
		(width 0.127)
		(layer "F.Cu")
		(net "VREF1")
	)
	(segment
		(start 23.784814 -92.523564)
		(end 22.931374 -93.377004)
		(width 0.127)
		(layer "F.Cu")
		(net "VREF1")
	)
	(segment
		(start 22.83333 -93.377004)
		(end 22.83333 -94.405704)
		(width 0.127)
		(layer "F.Cu")
		(net "VREF1")
	)
	(segment
		(start 24.08428 -90.678)
		(end 24.08428 -92.224098)
		(width 0.127)
		(layer "F.Cu")
		(net "VREF1")
	)
	(segment
		(start 24.08428 -92.224098)
		(end 23.784814 -92.523564)
		(width 0.127)
		(layer "F.Cu")
		(net "VREF1")
	)
	(via
		(at 23.784814 -92.523564)
		(size 0.6604)
		(drill 0.3302)
		(layers "F.Cu" "B.Cu")
		(net "VREF1")
	)
	(segment
		(start 159.004 -76.708)
		(end 158.815786 -76.519786)
		(width 0.127)
		(layer "F.Cu")
		(net "VOL_SEN2_SDA")
	)
	(segment
		(start 158.815786 -76.519786)
		(end 157.81528 -76.519786)
		(width 0.127)
		(layer "F.Cu")
		(net "VOL_SEN2_SDA")
	)
	(segment
		(start 154.501342 -74.095102)
		(end 155.956 -75.54976)
		(width 0.127)
		(layer "F.Cu")
		(net "VOL_SEN2_SDA")
	)
	(segment
		(start 159.004 -77.47)
		(end 159.004 -76.708)
		(width 0.127)
		(layer "F.Cu")
		(net "VOL_SEN2_SDA")
	)
	(segment
		(start 154.501342 -73.319894)
		(end 154.501342 -74.095102)
		(width 0.127)
		(layer "F.Cu")
		(net "VOL_SEN2_SDA")
	)
	(segment
		(start 154.612594 -72.677274)
		(end 154.501342 -72.788526)
		(width 0.127)
		(layer "F.Cu")
		(net "VOL_SEN2_SDA")
	)
	(segment
		(start 154.612594 -72.04837)
		(end 154.612594 -72.677274)
		(width 0.127)
		(layer "F.Cu")
		(net "VOL_SEN2_SDA")
	)
	(segment
		(start 158.75 -77.724)
		(end 159.004 -77.47)
		(width 0.127)
		(layer "F.Cu")
		(net "VOL_SEN2_SDA")
	)
	(segment
		(start 154.501342 -72.788526)
		(end 154.501342 -73.319894)
		(width 0.127)
		(layer "F.Cu")
		(net "VOL_SEN2_SDA")
	)
	(segment
		(start 155.956 -76.8477)
		(end 156.8323 -77.724)
		(width 0.127)
		(layer "F.Cu")
		(net "VOL_SEN2_SDA")
	)
	(segment
		(start 156.8323 -77.724)
		(end 158.75 -77.724)
		(width 0.127)
		(layer "F.Cu")
		(net "VOL_SEN2_SDA")
	)
	(segment
		(start 155.956 -75.54976)
		(end 155.956 -76.8477)
		(width 0.127)
		(layer "F.Cu")
		(net "VOL_SEN2_SDA")
	)
	(via
		(at 154.501342 -73.319894)
		(size 0.6604)
		(drill 0.3302)
		(layers "F.Cu" "B.Cu")
		(net "VOL_SEN2_SDA")
	)
	(segment
		(start 156.025342 -72.796654)
		(end 156.025342 -73.319894)
		(width 0.127)
		(layer "F.Cu")
		(net "VOL_SEN2_SCL")
	)
	(segment
		(start 156.591 -75.348084)
		(end 156.025342 -74.782426)
		(width 0.127)
		(layer "F.Cu")
		(net "VOL_SEN2_SCL")
	)
	(segment
		(start 155.755594 -72.04837)
		(end 155.755594 -72.526906)
		(width 0.127)
		(layer "F.Cu")
		(net "VOL_SEN2_SCL")
	)
	(segment
		(start 156.851096 -77.018896)
		(end 156.591 -76.7588)
		(width 0.127)
		(layer "F.Cu")
		(net "VOL_SEN2_SCL")
	)
	(segment
		(start 156.025342 -74.782426)
		(end 156.025342 -73.319894)
		(width 0.127)
		(layer "F.Cu")
		(net "VOL_SEN2_SCL")
	)
	(segment
		(start 157.81528 -77.018896)
		(end 156.851096 -77.018896)
		(width 0.127)
		(layer "F.Cu")
		(net "VOL_SEN2_SCL")
	)
	(segment
		(start 155.755594 -72.526906)
		(end 156.025342 -72.796654)
		(width 0.127)
		(layer "F.Cu")
		(net "VOL_SEN2_SCL")
	)
	(segment
		(start 156.591 -76.7588)
		(end 156.591 -75.348084)
		(width 0.127)
		(layer "F.Cu")
		(net "VOL_SEN2_SCL")
	)
	(via
		(at 156.025342 -73.319894)
		(size 0.6604)
		(drill 0.3302)
		(layers "F.Cu" "B.Cu")
		(net "VOL_SEN2_SCL")
	)
	(segment
		(start 155.7274 -78.0034)
		(end 155.7274 -77.4954)
		(width 0.127)
		(layer "F.Cu")
		(net "VOL_SEN2_ALERT")
	)
	(segment
		(start 156.4386 -78.7146)
		(end 155.7274 -78.0034)
		(width 0.127)
		(layer "F.Cu")
		(net "VOL_SEN2_ALERT")
	)
	(segment
		(start 155.7274 -77.4954)
		(end 154.751786 -76.519786)
		(width 0.127)
		(layer "F.Cu")
		(net "VOL_SEN2_ALERT")
	)
	(segment
		(start 156.4386 -78.7146)
		(end 156.588714 -78.864714)
		(width 0.127)
		(layer "F.Cu")
		(net "VOL_SEN2_ALERT")
	)
	(segment
		(start 154.751786 -76.519786)
		(end 153.67508 -76.519786)
		(width 0.127)
		(layer "F.Cu")
		(net "VOL_SEN2_ALERT")
	)
	(segment
		(start 156.588714 -78.864714)
		(end 158.0642 -78.864714)
		(width 0.127)
		(layer "F.Cu")
		(net "VOL_SEN2_ALERT")
	)
	(via
		(at 156.4386 -78.7146)
		(size 0.6604)
		(drill 0.3302)
		(layers "F.Cu" "B.Cu")
		(net "VOL_SEN2_ALERT")
	)
	(segment
		(start 152.983692 -78.782672)
		(end 154.471878 -78.782672)
		(width 0.127)
		(layer "F.Cu")
		(net "VOL_SEN2_ADDR")
	)
	(segment
		(start 153.67508 -77.018896)
		(end 152.682702 -77.018896)
		(width 0.127)
		(layer "F.Cu")
		(net "VOL_SEN2_ADDR")
	)
	(segment
		(start 155.061158 -78.782672)
		(end 154.471878 -78.782672)
		(width 0.127)
		(layer "F.Cu")
		(net "VOL_SEN2_ADDR")
	)
	(segment
		(start 152.550876 -77.150722)
		(end 152.550876 -78.349856)
		(width 0.127)
		(layer "F.Cu")
		(net "VOL_SEN2_ADDR")
	)
	(segment
		(start 152.682702 -77.018896)
		(end 152.550876 -77.150722)
		(width 0.127)
		(layer "F.Cu")
		(net "VOL_SEN2_ADDR")
	)
	(segment
		(start 156.2862 -80.007714)
		(end 155.061158 -78.782672)
		(width 0.127)
		(layer "F.Cu")
		(net "VOL_SEN2_ADDR")
	)
	(segment
		(start 152.550876 -78.349856)
		(end 152.983692 -78.782672)
		(width 0.127)
		(layer "F.Cu")
		(net "VOL_SEN2_ADDR")
	)
	(segment
		(start 157.4292 -80.007714)
		(end 156.2862 -80.007714)
		(width 0.127)
		(layer "F.Cu")
		(net "VOL_SEN2_ADDR")
	)
	(via
		(at 154.471878 -78.782672)
		(size 0.6604)
		(drill 0.3302)
		(layers "F.Cu" "B.Cu")
		(net "VOL_SEN2_ADDR")
	)
	(segment
		(start 193.234564 -65.43167)
		(end 193.567558 -65.43167)
		(width 0.127)
		(layer "F.Cu")
		(net "UART_IOC_TX")
	)
	(segment
		(start 198.50608 -88.952324)
		(end 198.505572 -88.951816)
		(width 0.127)
		(layer "F.Cu")
		(net "UART_IOC_TX")
	)
	(segment
		(start 194.002152 -64.997076)
		(end 194.002152 -64.736472)
		(width 0.127)
		(layer "F.Cu")
		(net "UART_IOC_TX")
	)
	(segment
		(start 202.514708 -20.60194)
		(end 202.514708 -32.85109)
		(width 0.127)
		(layer "F.Cu")
		(net "UART_IOC_TX")
	)
	(segment
		(start 192.060322 -66.892678)
		(end 192.951354 -66.892678)
		(width 0.127)
		(layer "F.Cu")
		(net "UART_IOC_TX")
	)
	(segment
		(start 187.199778 -7.400036)
		(end 187.199778 -7.695692)
		(width 0.127)
		(layer "F.Cu")
		(net "UART_IOC_TX")
	)
	(segment
		(start 202.9206 -33.256982)
		(end 202.9206 -35.636962)
		(width 0.127)
		(layer "F.Cu")
		(net "UART_IOC_TX")
	)
	(segment
		(start 202.25131 -47.059088)
		(end 204.245972 -49.05375)
		(width 0.127)
		(layer "F.Cu")
		(net "UART_IOC_TX")
	)
	(segment
		(start 186.265058 -8.630412)
		(end 186.265058 -17.608804)
		(width 0.127)
		(layer "F.Cu")
		(net "UART_IOC_TX")
	)
	(segment
		(start 187.199778 -7.695692)
		(end 186.265058 -8.630412)
		(width 0.127)
		(layer "F.Cu")
		(net "UART_IOC_TX")
	)
	(segment
		(start 194.002152 -64.736472)
		(end 194.986402 -63.752222)
		(width 0.127)
		(layer "F.Cu")
		(net "UART_IOC_TX")
	)
	(segment
		(start 192.951354 -65.71488)
		(end 193.234564 -65.43167)
		(width 0.127)
		(layer "F.Cu")
		(net "UART_IOC_TX")
	)
	(segment
		(start 192.951354 -66.892678)
		(end 192.951354 -65.71488)
		(width 0.127)
		(layer "F.Cu")
		(net "UART_IOC_TX")
	)
	(segment
		(start 191.40424 -69.54012)
		(end 191.40424 -67.54876)
		(width 0.127)
		(layer "F.Cu")
		(net "UART_IOC_TX")
	)
	(segment
		(start 204.245972 -54.492652)
		(end 194.986402 -63.752222)
		(width 0.127)
		(layer "F.Cu")
		(net "UART_IOC_TX")
	)
	(segment
		(start 193.567558 -65.43167)
		(end 194.002152 -64.997076)
		(width 0.127)
		(layer "F.Cu")
		(net "UART_IOC_TX")
	)
	(segment
		(start 204.245972 -49.05375)
		(end 204.245972 -54.492652)
		(width 0.127)
		(layer "F.Cu")
		(net "UART_IOC_TX")
	)
	(segment
		(start 200.235312 -18.322544)
		(end 202.514708 -20.60194)
		(width 0.127)
		(layer "F.Cu")
		(net "UART_IOC_TX")
	)
	(segment
		(start 202.514708 -32.85109)
		(end 202.9206 -33.256982)
		(width 0.127)
		(layer "F.Cu")
		(net "UART_IOC_TX")
	)
	(segment
		(start 186.265058 -17.608804)
		(end 186.978798 -18.322544)
		(width 0.127)
		(layer "F.Cu")
		(net "UART_IOC_TX")
	)
	(segment
		(start 202.25131 -36.306252)
		(end 202.25131 -47.059088)
		(width 0.127)
		(layer "F.Cu")
		(net "UART_IOC_TX")
	)
	(segment
		(start 198.505572 -88.951816)
		(end 197.020688 -88.951816)
		(width 0.127)
		(layer "F.Cu")
		(net "UART_IOC_TX")
	)
	(segment
		(start 186.978798 -18.322544)
		(end 200.235312 -18.322544)
		(width 0.127)
		(layer "F.Cu")
		(net "UART_IOC_TX")
	)
	(segment
		(start 191.40424 -67.54876)
		(end 192.060322 -66.892678)
		(width 0.127)
		(layer "F.Cu")
		(net "UART_IOC_TX")
	)
	(segment
		(start 202.9206 -35.636962)
		(end 202.25131 -36.306252)
		(width 0.127)
		(layer "F.Cu")
		(net "UART_IOC_TX")
	)
	(via
		(at 194.986402 -63.752222)
		(size 0.6604)
		(drill 0.3302)
		(layers "F.Cu" "B.Cu")
		(net "UART_IOC_TX")
	)
	(via
		(at 197.020688 -88.951816)
		(size 0.508)
		(drill 0.254)
		(layers "F.Cu" "B.Cu")
		(net "UART_IOC_TX")
	)
	(via
		(at 191.40424 -69.54012)
		(size 0.508)
		(drill 0.254)
		(layers "F.Cu" "B.Cu")
		(net "UART_IOC_TX")
	)
	(segment
		(start 191.40424 -69.54012)
		(end 195.863464 -73.999344)
		(width 0.127)
		(layer "In2.Cu")
		(net "UART_IOC_TX")
	)
	(segment
		(start 195.863464 -87.794592)
		(end 197.020688 -88.951816)
		(width 0.127)
		(layer "In2.Cu")
		(net "UART_IOC_TX")
	)
	(segment
		(start 195.863464 -73.999344)
		(end 195.863464 -87.794592)
		(width 0.127)
		(layer "In2.Cu")
		(net "UART_IOC_TX")
	)
	(segment
		(start 188.763402 -17.674336)
		(end 200.761854 -17.674336)
		(width 0.127)
		(layer "F.Cu")
		(net "UART_IOC_RX")
	)
	(segment
		(start 187.199778 -8.800084)
		(end 187.199778 -8.967978)
		(width 0.127)
		(layer "F.Cu")
		(net "UART_IOC_RX")
	)
	(segment
		(start 195.04406 -69.43852)
		(end 195.04406 -67.89674)
		(width 0.127)
		(layer "F.Cu")
		(net "UART_IOC_RX")
	)
	(segment
		(start 198.557642 -61.74486)
		(end 198.09714 -61.74486)
		(width 0.127)
		(layer "F.Cu")
		(net "UART_IOC_RX")
	)
	(segment
		(start 197.235572 -62.606428)
		(end 195.817744 -64.024256)
		(width 0.127)
		(layer "F.Cu")
		(net "UART_IOC_RX")
	)
	(segment
		(start 198.09714 -61.74486)
		(end 197.235572 -62.606428)
		(width 0.127)
		(layer "F.Cu")
		(net "UART_IOC_RX")
	)
	(segment
		(start 194.01536 -66.443352)
		(end 194.01536 -66.86804)
		(width 0.127)
		(layer "F.Cu")
		(net "UART_IOC_RX")
	)
	(segment
		(start 188.200284 -9.968484)
		(end 188.200284 -17.111218)
		(width 0.127)
		(layer "F.Cu")
		(net "UART_IOC_RX")
	)
	(segment
		(start 188.200284 -17.111218)
		(end 188.763402 -17.674336)
		(width 0.127)
		(layer "F.Cu")
		(net "UART_IOC_RX")
	)
	(segment
		(start 195.817744 -64.024256)
		(end 195.817744 -64.640968)
		(width 0.127)
		(layer "F.Cu")
		(net "UART_IOC_RX")
	)
	(segment
		(start 195.966588 -85.951568)
		(end 197.230238 -85.951568)
		(width 0.127)
		(layer "F.Cu")
		(net "UART_IOC_RX")
	)
	(segment
		(start 195.96608 -85.952076)
		(end 195.966588 -85.951568)
		(width 0.127)
		(layer "F.Cu")
		(net "UART_IOC_RX")
	)
	(segment
		(start 200.761854 -17.674336)
		(end 203.592684 -20.505166)
		(width 0.127)
		(layer "F.Cu")
		(net "UART_IOC_RX")
	)
	(segment
		(start 195.04406 -67.89674)
		(end 194.01536 -66.86804)
		(width 0.127)
		(layer "F.Cu")
		(net "UART_IOC_RX")
	)
	(segment
		(start 187.199778 -8.967978)
		(end 188.200284 -9.968484)
		(width 0.127)
		(layer "F.Cu")
		(net "UART_IOC_RX")
	)
	(segment
		(start 204.880972 -55.42153)
		(end 198.557642 -61.74486)
		(width 0.127)
		(layer "F.Cu")
		(net "UART_IOC_RX")
	)
	(segment
		(start 203.592684 -20.505166)
		(end 203.592684 -44.86656)
		(width 0.127)
		(layer "F.Cu")
		(net "UART_IOC_RX")
	)
	(segment
		(start 204.880972 -46.154848)
		(end 204.880972 -55.42153)
		(width 0.127)
		(layer "F.Cu")
		(net "UART_IOC_RX")
	)
	(segment
		(start 195.817744 -64.640968)
		(end 194.01536 -66.443352)
		(width 0.127)
		(layer "F.Cu")
		(net "UART_IOC_RX")
	)
	(segment
		(start 203.592684 -44.86656)
		(end 204.880972 -46.154848)
		(width 0.127)
		(layer "F.Cu")
		(net "UART_IOC_RX")
	)
	(via
		(at 197.230238 -85.951568)
		(size 0.508)
		(drill 0.254)
		(layers "F.Cu" "B.Cu")
		(net "UART_IOC_RX")
	)
	(via
		(at 195.04406 -69.43852)
		(size 0.508)
		(drill 0.254)
		(layers "F.Cu" "B.Cu")
		(net "UART_IOC_RX")
	)
	(via
		(at 197.235572 -62.606428)
		(size 0.6604)
		(drill 0.3302)
		(layers "F.Cu" "B.Cu")
		(net "UART_IOC_RX")
	)
	(segment
		(start 196.498464 -73.7362)
		(end 196.498464 -85.219794)
		(width 0.127)
		(layer "In2.Cu")
		(net "UART_IOC_RX")
	)
	(segment
		(start 196.498464 -85.219794)
		(end 197.230238 -85.951568)
		(width 0.127)
		(layer "In2.Cu")
		(net "UART_IOC_RX")
	)
	(segment
		(start 195.04406 -72.281796)
		(end 196.498464 -73.7362)
		(width 0.127)
		(layer "In2.Cu")
		(net "UART_IOC_RX")
	)
	(segment
		(start 195.04406 -69.43852)
		(end 195.04406 -72.281796)
		(width 0.127)
		(layer "In2.Cu")
		(net "UART_IOC_RX")
	)
	(segment
		(start 160.30956 -95.8596)
		(end 159.918908 -95.468948)
		(width 0.127)
		(layer "F.Cu")
		(net "UART_EXP_TX")
	)
	(segment
		(start 159.673036 -95.223076)
		(end 159.918908 -95.468948)
		(width 0.127)
		(layer "F.Cu")
		(net "UART_EXP_TX")
	)
	(segment
		(start 157.611318 -95.223076)
		(end 159.673036 -95.223076)
		(width 0.127)
		(layer "F.Cu")
		(net "UART_EXP_TX")
	)
	(segment
		(start 160.30956 -96.863662)
		(end 160.30956 -95.8596)
		(width 0.127)
		(layer "F.Cu")
		(net "UART_EXP_TX")
	)
	(via
		(at 160.30956 -96.863662)
		(size 0.508)
		(drill 0.254)
		(layers "F.Cu" "B.Cu")
		(net "UART_EXP_TX")
	)
	(via
		(at 159.918908 -95.468948)
		(size 0.6604)
		(drill 0.3302)
		(layers "F.Cu" "B.Cu")
		(net "UART_EXP_TX")
	)
	(segment
		(start 76.805028 -44.849542)
		(end 74.422254 -47.232316)
		(width 0.127)
		(layer "In2.Cu")
		(net "UART_EXP_TX")
	)
	(segment
		(start 143.178276 -100.041202)
		(end 143.19377 -100.025708)
		(width 0.127)
		(layer "In2.Cu")
		(net "UART_EXP_TX")
	)
	(segment
		(start 108.775246 -12.856464)
		(end 108.859828 -12.941046)
		(width 0.127)
		(layer "In2.Cu")
		(net "UART_EXP_TX")
	)
	(segment
		(start 68.123562 -65.620392)
		(end 66.290698 -65.620392)
		(width 0.127)
		(layer "In2.Cu")
		(net "UART_EXP_TX")
	)
	(segment
		(start 71.209662 -96.3676)
		(end 72.718676 -96.3676)
		(width 0.127)
		(layer "In2.Cu")
		(net "UART_EXP_TX")
	)
	(segment
		(start 60.582302 -91.677236)
		(end 67.576954 -91.677236)
		(width 0.127)
		(layer "In2.Cu")
		(net "UART_EXP_TX")
	)
	(segment
		(start 108.775246 -8.575294)
		(end 108.775246 -11.199622)
		(width 0.127)
		(layer "In2.Cu")
		(net "UART_EXP_TX")
	)
	(segment
		(start 150.34133 -97.29597)
		(end 151.43988 -96.197674)
		(width 0.127)
		(layer "In2.Cu")
		(net "UART_EXP_TX")
	)
	(segment
		(start 148.2598 -100.025708)
		(end 150.34133 -97.944178)
		(width 0.127)
		(layer "In2.Cu")
		(net "UART_EXP_TX")
	)
	(segment
		(start 150.34133 -97.944178)
		(end 150.34133 -97.29597)
		(width 0.127)
		(layer "In2.Cu")
		(net "UART_EXP_TX")
	)
	(segment
		(start 72.360536 -52.956206)
		(end 72.360536 -61.383418)
		(width 0.127)
		(layer "In2.Cu")
		(net "UART_EXP_TX")
	)
	(segment
		(start 108.09986 -14.706854)
		(end 108.099606 -14.706854)
		(width 0.127)
		(layer "In2.Cu")
		(net "UART_EXP_TX")
	)
	(segment
		(start 107.599988 -7.400036)
		(end 108.775246 -8.575294)
		(width 0.127)
		(layer "In2.Cu")
		(net "UART_EXP_TX")
	)
	(segment
		(start 78.35646 -32.602678)
		(end 78.35646 -35.630358)
		(width 0.127)
		(layer "In2.Cu")
		(net "UART_EXP_TX")
	)
	(segment
		(start 83.433158 -26.84018)
		(end 82.346038 -27.9273)
		(width 0.127)
		(layer "In2.Cu")
		(net "UART_EXP_TX")
	)
	(segment
		(start 108.099606 -14.706854)
		(end 95.966026 -26.840434)
		(width 0.127)
		(layer "In2.Cu")
		(net "UART_EXP_TX")
	)
	(segment
		(start 95.440246 -26.840434)
		(end 95.439992 -26.84018)
		(width 0.127)
		(layer "In2.Cu")
		(net "UART_EXP_TX")
	)
	(segment
		(start 108.775246 -11.199622)
		(end 108.774738 -11.258804)
		(width 0.127)
		(layer "In2.Cu")
		(net "UART_EXP_TX")
	)
	(segment
		(start 56.22417 -68.189602)
		(end 54.076346 -70.337426)
		(width 0.127)
		(layer "In2.Cu")
		(net "UART_EXP_TX")
	)
	(segment
		(start 108.775246 -11.261598)
		(end 108.775246 -12.856464)
		(width 0.127)
		(layer "In2.Cu")
		(net "UART_EXP_TX")
	)
	(segment
		(start 82.346038 -27.9273)
		(end 82.346038 -28.6131)
		(width 0.127)
		(layer "In2.Cu")
		(net "UART_EXP_TX")
	)
	(segment
		(start 72.360536 -61.383418)
		(end 68.123562 -65.620392)
		(width 0.127)
		(layer "In2.Cu")
		(net "UART_EXP_TX")
	)
	(segment
		(start 52.361592 -78.914498)
		(end 52.361592 -83.456526)
		(width 0.127)
		(layer "In2.Cu")
		(net "UART_EXP_TX")
	)
	(segment
		(start 74.422254 -50.894488)
		(end 72.360536 -52.956206)
		(width 0.127)
		(layer "In2.Cu")
		(net "UART_EXP_TX")
	)
	(segment
		(start 68.7832 -92.883482)
		(end 68.7832 -93.941138)
		(width 0.127)
		(layer "In2.Cu")
		(net "UART_EXP_TX")
	)
	(segment
		(start 54.076346 -70.337426)
		(end 54.076346 -77.199744)
		(width 0.127)
		(layer "In2.Cu")
		(net "UART_EXP_TX")
	)
	(segment
		(start 95.966026 -26.840434)
		(end 95.440246 -26.840434)
		(width 0.127)
		(layer "In2.Cu")
		(net "UART_EXP_TX")
	)
	(segment
		(start 52.361592 -83.456526)
		(end 60.582302 -91.677236)
		(width 0.127)
		(layer "In2.Cu")
		(net "UART_EXP_TX")
	)
	(segment
		(start 159.643572 -96.197674)
		(end 160.30956 -96.863662)
		(width 0.127)
		(layer "In2.Cu")
		(net "UART_EXP_TX")
	)
	(segment
		(start 63.721488 -68.189602)
		(end 56.22417 -68.189602)
		(width 0.127)
		(layer "In2.Cu")
		(net "UART_EXP_TX")
	)
	(segment
		(start 143.19377 -100.025708)
		(end 148.2598 -100.025708)
		(width 0.127)
		(layer "In2.Cu")
		(net "UART_EXP_TX")
	)
	(segment
		(start 67.576954 -91.677236)
		(end 68.7832 -92.883482)
		(width 0.127)
		(layer "In2.Cu")
		(net "UART_EXP_TX")
	)
	(segment
		(start 95.439992 -26.84018)
		(end 83.433158 -26.84018)
		(width 0.127)
		(layer "In2.Cu")
		(net "UART_EXP_TX")
	)
	(segment
		(start 151.43988 -96.197674)
		(end 159.643572 -96.197674)
		(width 0.127)
		(layer "In2.Cu")
		(net "UART_EXP_TX")
	)
	(segment
		(start 108.859828 -12.941046)
		(end 108.859828 -13.946886)
		(width 0.127)
		(layer "In2.Cu")
		(net "UART_EXP_TX")
	)
	(segment
		(start 66.290698 -65.620392)
		(end 63.721488 -68.189602)
		(width 0.127)
		(layer "In2.Cu")
		(net "UART_EXP_TX")
	)
	(segment
		(start 68.7832 -93.941138)
		(end 71.209662 -96.3676)
		(width 0.127)
		(layer "In2.Cu")
		(net "UART_EXP_TX")
	)
	(segment
		(start 74.422254 -47.232316)
		(end 74.422254 -50.894488)
		(width 0.127)
		(layer "In2.Cu")
		(net "UART_EXP_TX")
	)
	(segment
		(start 82.346038 -28.6131)
		(end 78.35646 -32.602678)
		(width 0.127)
		(layer "In2.Cu")
		(net "UART_EXP_TX")
	)
	(segment
		(start 76.805028 -37.18179)
		(end 76.805028 -44.849542)
		(width 0.127)
		(layer "In2.Cu")
		(net "UART_EXP_TX")
	)
	(segment
		(start 54.076346 -77.199744)
		(end 52.361592 -78.914498)
		(width 0.127)
		(layer "In2.Cu")
		(net "UART_EXP_TX")
	)
	(segment
		(start 108.774738 -11.258804)
		(end 108.775246 -11.261598)
		(width 0.127)
		(layer "In2.Cu")
		(net "UART_EXP_TX")
	)
	(segment
		(start 78.35646 -35.630358)
		(end 76.805028 -37.18179)
		(width 0.127)
		(layer "In2.Cu")
		(net "UART_EXP_TX")
	)
	(segment
		(start 76.392278 -100.041202)
		(end 143.178276 -100.041202)
		(width 0.127)
		(layer "In2.Cu")
		(net "UART_EXP_TX")
	)
	(segment
		(start 108.859828 -13.946886)
		(end 108.09986 -14.706854)
		(width 0.127)
		(layer "In2.Cu")
		(net "UART_EXP_TX")
	)
	(segment
		(start 72.718676 -96.3676)
		(end 76.392278 -100.041202)
		(width 0.127)
		(layer "In2.Cu")
		(net "UART_EXP_TX")
	)
	(segment
		(start 157.611318 -96.239076)
		(end 158.274004 -96.239076)
		(width 0.127)
		(layer "F.Cu")
		(net "UART_EXP_RX")
	)
	(segment
		(start 158.44774 -96.06534)
		(end 158.797498 -96.06534)
		(width 0.127)
		(layer "F.Cu")
		(net "UART_EXP_RX")
	)
	(segment
		(start 159.035242 -96.06534)
		(end 158.797498 -96.06534)
		(width 0.127)
		(layer "F.Cu")
		(net "UART_EXP_RX")
	)
	(segment
		(start 159.29356 -96.863662)
		(end 159.29356 -96.323658)
		(width 0.127)
		(layer "F.Cu")
		(net "UART_EXP_RX")
	)
	(segment
		(start 159.29356 -96.323658)
		(end 159.035242 -96.06534)
		(width 0.127)
		(layer "F.Cu")
		(net "UART_EXP_RX")
	)
	(segment
		(start 158.274004 -96.239076)
		(end 158.44774 -96.06534)
		(width 0.127)
		(layer "F.Cu")
		(net "UART_EXP_RX")
	)
	(via
		(at 158.797498 -96.06534)
		(size 0.6604)
		(drill 0.3302)
		(layers "F.Cu" "B.Cu")
		(net "UART_EXP_RX")
	)
	(via
		(at 159.29356 -96.863662)
		(size 0.508)
		(drill 0.254)
		(layers "F.Cu" "B.Cu")
		(net "UART_EXP_RX")
	)
	(segment
		(start 148.522944 -100.660708)
		(end 150.97633 -98.207322)
		(width 0.127)
		(layer "In2.Cu")
		(net "UART_EXP_RX")
	)
	(segment
		(start 107.836716 -14.0716)
		(end 95.703136 -26.20518)
		(width 0.127)
		(layer "In2.Cu")
		(net "UART_EXP_RX")
	)
	(segment
		(start 67.860418 -64.985392)
		(end 66.027554 -64.985392)
		(width 0.127)
		(layer "In2.Cu")
		(net "UART_EXP_RX")
	)
	(segment
		(start 143.44142 -100.676202)
		(end 143.456914 -100.660708)
		(width 0.127)
		(layer "In2.Cu")
		(net "UART_EXP_RX")
	)
	(segment
		(start 73.787 -46.969426)
		(end 73.787 -50.631598)
		(width 0.127)
		(layer "In2.Cu")
		(net "UART_EXP_RX")
	)
	(segment
		(start 108.224828 -13.683742)
		(end 107.83697 -14.0716)
		(width 0.127)
		(layer "In2.Cu")
		(net "UART_EXP_RX")
	)
	(segment
		(start 51.726592 -78.6511)
		(end 51.726592 -83.71967)
		(width 0.127)
		(layer "In2.Cu")
		(net "UART_EXP_RX")
	)
	(segment
		(start 107.83697 -14.0716)
		(end 107.836716 -14.0716)
		(width 0.127)
		(layer "In2.Cu")
		(net "UART_EXP_RX")
	)
	(segment
		(start 71.725282 -61.120528)
		(end 67.860418 -64.985392)
		(width 0.127)
		(layer "In2.Cu")
		(net "UART_EXP_RX")
	)
	(segment
		(start 81.530952 -27.844242)
		(end 81.530952 -27.993594)
		(width 0.127)
		(layer "In2.Cu")
		(net "UART_EXP_RX")
	)
	(segment
		(start 143.456914 -100.660708)
		(end 148.522944 -100.660708)
		(width 0.127)
		(layer "In2.Cu")
		(net "UART_EXP_RX")
	)
	(segment
		(start 81.530952 -27.993594)
		(end 77.72146 -31.803086)
		(width 0.127)
		(layer "In2.Cu")
		(net "UART_EXP_RX")
	)
	(segment
		(start 51.726592 -83.71967)
		(end 60.319158 -92.312236)
		(width 0.127)
		(layer "In2.Cu")
		(net "UART_EXP_RX")
	)
	(segment
		(start 70.946518 -97.0026)
		(end 72.455532 -97.0026)
		(width 0.127)
		(layer "In2.Cu")
		(net "UART_EXP_RX")
	)
	(segment
		(start 63.458598 -67.554348)
		(end 55.96128 -67.554348)
		(width 0.127)
		(layer "In2.Cu")
		(net "UART_EXP_RX")
	)
	(segment
		(start 108.224828 -9.424924)
		(end 108.224828 -13.683742)
		(width 0.127)
		(layer "In2.Cu")
		(net "UART_EXP_RX")
	)
	(segment
		(start 60.319158 -92.312236)
		(end 66.645536 -92.312236)
		(width 0.127)
		(layer "In2.Cu")
		(net "UART_EXP_RX")
	)
	(segment
		(start 77.72146 -31.803086)
		(end 77.72146 -35.122612)
		(width 0.127)
		(layer "In2.Cu")
		(net "UART_EXP_RX")
	)
	(segment
		(start 53.441346 -70.074282)
		(end 53.441346 -76.936346)
		(width 0.127)
		(layer "In2.Cu")
		(net "UART_EXP_RX")
	)
	(segment
		(start 150.97633 -97.559368)
		(end 151.525732 -97.009966)
		(width 0.127)
		(layer "In2.Cu")
		(net "UART_EXP_RX")
	)
	(segment
		(start 150.97633 -98.207322)
		(end 150.97633 -97.559368)
		(width 0.127)
		(layer "In2.Cu")
		(net "UART_EXP_RX")
	)
	(segment
		(start 107.599988 -8.800084)
		(end 108.224828 -9.424924)
		(width 0.127)
		(layer "In2.Cu")
		(net "UART_EXP_RX")
	)
	(segment
		(start 55.96128 -67.554348)
		(end 53.441346 -70.074282)
		(width 0.127)
		(layer "In2.Cu")
		(net "UART_EXP_RX")
	)
	(segment
		(start 71.725282 -52.693316)
		(end 71.725282 -61.120528)
		(width 0.127)
		(layer "In2.Cu")
		(net "UART_EXP_RX")
	)
	(segment
		(start 76.170028 -36.674044)
		(end 76.170028 -44.586398)
		(width 0.127)
		(layer "In2.Cu")
		(net "UART_EXP_RX")
	)
	(segment
		(start 66.645536 -92.312236)
		(end 67.31635 -92.98305)
		(width 0.127)
		(layer "In2.Cu")
		(net "UART_EXP_RX")
	)
	(segment
		(start 67.31635 -93.372432)
		(end 70.946518 -97.0026)
		(width 0.127)
		(layer "In2.Cu")
		(net "UART_EXP_RX")
	)
	(segment
		(start 83.170014 -26.20518)
		(end 81.530952 -27.844242)
		(width 0.127)
		(layer "In2.Cu")
		(net "UART_EXP_RX")
	)
	(segment
		(start 154.898852 -96.863662)
		(end 159.29356 -96.863662)
		(width 0.127)
		(layer "In2.Cu")
		(net "UART_EXP_RX")
	)
	(segment
		(start 72.455532 -97.0026)
		(end 75.741784 -100.288852)
		(width 0.127)
		(layer "In2.Cu")
		(net "UART_EXP_RX")
	)
	(segment
		(start 154.867864 -96.832674)
		(end 154.898852 -96.863662)
		(width 0.127)
		(layer "In2.Cu")
		(net "UART_EXP_RX")
	)
	(segment
		(start 75.741784 -100.288852)
		(end 75.741784 -100.289106)
		(width 0.127)
		(layer "In2.Cu")
		(net "UART_EXP_RX")
	)
	(segment
		(start 67.31635 -92.98305)
		(end 67.31635 -93.372432)
		(width 0.127)
		(layer "In2.Cu")
		(net "UART_EXP_RX")
	)
	(segment
		(start 75.741784 -100.289106)
		(end 76.12888 -100.676202)
		(width 0.127)
		(layer "In2.Cu")
		(net "UART_EXP_RX")
	)
	(segment
		(start 151.525732 -97.009966)
		(end 151.703278 -96.832674)
		(width 0.127)
		(layer "In2.Cu")
		(net "UART_EXP_RX")
	)
	(segment
		(start 76.170028 -44.586398)
		(end 73.787 -46.969426)
		(width 0.127)
		(layer "In2.Cu")
		(net "UART_EXP_RX")
	)
	(segment
		(start 76.12888 -100.676202)
		(end 143.44142 -100.676202)
		(width 0.127)
		(layer "In2.Cu")
		(net "UART_EXP_RX")
	)
	(segment
		(start 151.703278 -96.832674)
		(end 154.867864 -96.832674)
		(width 0.127)
		(layer "In2.Cu")
		(net "UART_EXP_RX")
	)
	(segment
		(start 77.72146 -35.122612)
		(end 76.170028 -36.674044)
		(width 0.127)
		(layer "In2.Cu")
		(net "UART_EXP_RX")
	)
	(segment
		(start 73.787 -50.631598)
		(end 71.725282 -52.693316)
		(width 0.127)
		(layer "In2.Cu")
		(net "UART_EXP_RX")
	)
	(segment
		(start 66.027554 -64.985392)
		(end 63.458598 -67.554348)
		(width 0.127)
		(layer "In2.Cu")
		(net "UART_EXP_RX")
	)
	(segment
		(start 53.441346 -76.936346)
		(end 51.726592 -78.6511)
		(width 0.127)
		(layer "In2.Cu")
		(net "UART_EXP_RX")
	)
	(segment
		(start 95.703136 -26.20518)
		(end 83.170014 -26.20518)
		(width 0.127)
		(layer "In2.Cu")
		(net "UART_EXP_RX")
	)
	(segment
		(start 200.573132 -76.482194)
		(end 201.13879 -76.482194)
		(width 0.127)
		(layer "F.Cu")
		(net "TEMP2_SDA")
	)
	(segment
		(start 198.424292 -76.482194)
		(end 200.573132 -76.482194)
		(width 0.127)
		(layer "F.Cu")
		(net "TEMP2_SDA")
	)
	(segment
		(start 201.13879 -76.482194)
		(end 201.522076 -76.86548)
		(width 0.127)
		(layer "F.Cu")
		(net "TEMP2_SDA")
	)
	(segment
		(start 201.522076 -76.86548)
		(end 201.85888 -76.86548)
		(width 0.127)
		(layer "F.Cu")
		(net "TEMP2_SDA")
	)
	(via
		(at 200.573132 -76.482194)
		(size 0.6604)
		(drill 0.3302)
		(layers "F.Cu" "B.Cu")
		(net "TEMP2_SDA")
	)
	(segment
		(start 201.85888 -78.00848)
		(end 201.489818 -78.00848)
		(width 0.127)
		(layer "F.Cu")
		(net "TEMP2_SCL")
	)
	(segment
		(start 198.424292 -77.132434)
		(end 199.225154 -77.132434)
		(width 0.127)
		(layer "F.Cu")
		(net "TEMP2_SCL")
	)
	(segment
		(start 199.90181 -77.80909)
		(end 200.557638 -77.80909)
		(width 0.127)
		(layer "F.Cu")
		(net "TEMP2_SCL")
	)
	(segment
		(start 201.290428 -77.80909)
		(end 200.557638 -77.80909)
		(width 0.127)
		(layer "F.Cu")
		(net "TEMP2_SCL")
	)
	(segment
		(start 201.489818 -78.00848)
		(end 201.290428 -77.80909)
		(width 0.127)
		(layer "F.Cu")
		(net "TEMP2_SCL")
	)
	(segment
		(start 199.225154 -77.132434)
		(end 199.90181 -77.80909)
		(width 0.127)
		(layer "F.Cu")
		(net "TEMP2_SCL")
	)
	(via
		(at 200.557638 -77.80909)
		(size 0.6604)
		(drill 0.3302)
		(layers "F.Cu" "B.Cu")
		(net "TEMP2_SCL")
	)
	(segment
		(start 196.342 -80.2132)
		(end 196.342 -78.8416)
		(width 0.127)
		(layer "F.Cu")
		(net "TEMP2_ALERT")
	)
	(segment
		(start 197.400926 -77.782674)
		(end 198.424292 -77.782674)
		(width 0.127)
		(layer "F.Cu")
		(net "TEMP2_ALERT")
	)
	(segment
		(start 196.342 -78.8416)
		(end 197.400926 -77.782674)
		(width 0.127)
		(layer "F.Cu")
		(net "TEMP2_ALERT")
	)
	(segment
		(start 193.631566 -80.564736)
		(end 192.438782 -80.564736)
		(width 0.127)
		(layer "F.Cu")
		(net "TEMP2_A2")
	)
	(segment
		(start 193.93027 -80.266032)
		(end 193.631566 -80.564736)
		(width 0.127)
		(layer "F.Cu")
		(net "TEMP2_A2")
	)
	(segment
		(start 192.438782 -81.707736)
		(end 192.438782 -80.564736)
		(width 0.127)
		(layer "F.Cu")
		(net "TEMP2_A2")
	)
	(segment
		(start 194.314572 -78.432914)
		(end 194.314572 -79.88173)
		(width 0.127)
		(layer "F.Cu")
		(net "TEMP2_A2")
	)
	(segment
		(start 194.314572 -79.88173)
		(end 193.93027 -80.266032)
		(width 0.127)
		(layer "F.Cu")
		(net "TEMP2_A2")
	)
	(via
		(at 193.93027 -80.266032)
		(size 0.6604)
		(drill 0.3302)
		(layers "F.Cu" "B.Cu")
		(net "TEMP2_A2")
	)
	(segment
		(start 189.73038 -78.04658)
		(end 190.87338 -78.04658)
		(width 0.127)
		(layer "F.Cu")
		(net "TEMP2_A1")
	)
	(segment
		(start 190.87338 -78.04658)
		(end 191.03848 -78.04658)
		(width 0.127)
		(layer "F.Cu")
		(net "TEMP2_A1")
	)
	(segment
		(start 192.400682 -78.974696)
		(end 193.005964 -78.974696)
		(width 0.127)
		(layer "F.Cu")
		(net "TEMP2_A1")
	)
	(segment
		(start 193.005964 -78.974696)
		(end 193.171572 -78.809088)
		(width 0.127)
		(layer "F.Cu")
		(net "TEMP2_A1")
	)
	(segment
		(start 193.171572 -78.809088)
		(end 193.171572 -78.203806)
		(width 0.127)
		(layer "F.Cu")
		(net "TEMP2_A1")
	)
	(segment
		(start 191.03848 -78.04658)
		(end 191.966596 -78.974696)
		(width 0.127)
		(layer "F.Cu")
		(net "TEMP2_A1")
	)
	(segment
		(start 191.966596 -78.974696)
		(end 192.400682 -78.974696)
		(width 0.127)
		(layer "F.Cu")
		(net "TEMP2_A1")
	)
	(segment
		(start 193.592704 -77.782674)
		(end 194.314572 -77.782674)
		(width 0.127)
		(layer "F.Cu")
		(net "TEMP2_A1")
	)
	(segment
		(start 193.171572 -78.203806)
		(end 193.592704 -77.782674)
		(width 0.127)
		(layer "F.Cu")
		(net "TEMP2_A1")
	)
	(via
		(at 192.400682 -78.974696)
		(size 0.6604)
		(drill 0.3302)
		(layers "F.Cu" "B.Cu")
		(net "TEMP2_A1")
	)
	(segment
		(start 191.915796 -77.653896)
		(end 191.57188 -77.30998)
		(width 0.127)
		(layer "F.Cu")
		(net "TEMP2_A0")
	)
	(segment
		(start 192.934844 -77.653896)
		(end 192.400682 -77.653896)
		(width 0.127)
		(layer "F.Cu")
		(net "TEMP2_A0")
	)
	(segment
		(start 193.456306 -77.132434)
		(end 192.934844 -77.653896)
		(width 0.127)
		(layer "F.Cu")
		(net "TEMP2_A0")
	)
	(segment
		(start 192.400682 -77.653896)
		(end 191.915796 -77.653896)
		(width 0.127)
		(layer "F.Cu")
		(net "TEMP2_A0")
	)
	(segment
		(start 190.49238 -77.30998)
		(end 189.79388 -76.61148)
		(width 0.127)
		(layer "F.Cu")
		(net "TEMP2_A0")
	)
	(segment
		(start 194.314572 -77.132434)
		(end 193.456306 -77.132434)
		(width 0.127)
		(layer "F.Cu")
		(net "TEMP2_A0")
	)
	(segment
		(start 191.57188 -77.30998)
		(end 190.49238 -77.30998)
		(width 0.127)
		(layer "F.Cu")
		(net "TEMP2_A0")
	)
	(segment
		(start 189.79388 -76.61148)
		(end 189.79388 -75.46848)
		(width 0.127)
		(layer "F.Cu")
		(net "TEMP2_A0")
	)
	(via
		(at 192.400682 -77.653896)
		(size 0.6604)
		(drill 0.3302)
		(layers "F.Cu" "B.Cu")
		(net "TEMP2_A0")
	)
	(segment
		(start 150.16861 -107.68838)
		(end 149.9616 -107.48137)
		(width 0.127)
		(layer "F.Cu")
		(net "SDB_CONN_PWR_2")
	)
	(segment
		(start 151.016716 -105.929684)
		(end 149.9616 -106.9848)
		(width 0.127)
		(layer "F.Cu")
		(net "SDB_CONN_PWR_2")
	)
	(segment
		(start 151.24176 -109.33176)
		(end 151.23668 -109.32668)
		(width 0.127)
		(layer "F.Cu")
		(net "SDB_CONN_PWR_2")
	)
	(segment
		(start 150.63724 -107.68838)
		(end 150.16861 -107.68838)
		(width 0.127)
		(layer "F.Cu")
		(net "SDB_CONN_PWR_2")
	)
	(segment
		(start 152.2476 -105.929684)
		(end 151.016716 -105.929684)
		(width 0.127)
		(layer "F.Cu")
		(net "SDB_CONN_PWR_2")
	)
	(segment
		(start 151.23668 -108.38688)
		(end 151.23668 -108.28782)
		(width 0.127)
		(layer "F.Cu")
		(net "SDB_CONN_PWR_2")
	)
	(segment
		(start 151.23668 -108.28782)
		(end 150.63724 -107.68838)
		(width 0.127)
		(layer "F.Cu")
		(net "SDB_CONN_PWR_2")
	)
	(segment
		(start 149.9616 -107.48137)
		(end 149.9616 -106.9848)
		(width 0.127)
		(layer "F.Cu")
		(net "SDB_CONN_PWR_2")
	)
	(segment
		(start 151.23668 -109.32668)
		(end 151.23668 -108.38688)
		(width 0.127)
		(layer "F.Cu")
		(net "SDB_CONN_PWR_2")
	)
	(via
		(at 149.9616 -106.9848)
		(size 0.6604)
		(drill 0.3302)
		(layers "F.Cu" "B.Cu")
		(net "SDB_CONN_PWR_2")
	)
	(segment
		(start 120.005602 -82.407506)
		(end 120.005602 -83.778598)
		(width 0.127)
		(layer "F.Cu")
		(net "SCC_TYPE_2_LS")
	)
	(segment
		(start 119.500142 -81.902046)
		(end 120.005602 -82.407506)
		(width 0.127)
		(layer "F.Cu")
		(net "SCC_TYPE_2_LS")
	)
	(segment
		(start 119.500142 -81.500218)
		(end 119.500142 -81.902046)
		(width 0.127)
		(layer "F.Cu")
		(net "SCC_TYPE_2_LS")
	)
	(via
		(at 120.861836 -84.115402)
		(size 0.6096)
		(drill 0.3048)
		(layers "F.Cu" "B.Cu")
		(net "SCC_TYPE_2_LS")
	)
	(via
		(at 120.005602 -83.778598)
		(size 0.508)
		(drill 0.254)
		(layers "F.Cu" "B.Cu")
		(net "SCC_TYPE_2_LS")
	)
	(segment
		(start 120.005602 -83.778598)
		(end 120.525032 -83.778598)
		(width 0.127)
		(layer "B.Cu")
		(net "SCC_TYPE_2_LS")
	)
	(segment
		(start 122.584972 -85.68182)
		(end 122.404124 -85.500972)
		(width 0.127)
		(layer "B.Cu")
		(net "SCC_TYPE_2_LS")
	)
	(segment
		(start 122.584972 -86.205568)
		(end 122.584972 -85.68182)
		(width 0.127)
		(layer "B.Cu")
		(net "SCC_TYPE_2_LS")
	)
	(segment
		(start 121.3866 -84.640166)
		(end 120.861836 -84.115402)
		(width 0.127)
		(layer "B.Cu")
		(net "SCC_TYPE_2_LS")
	)
	(segment
		(start 121.683018 -85.500972)
		(end 121.3866 -85.204554)
		(width 0.127)
		(layer "B.Cu")
		(net "SCC_TYPE_2_LS")
	)
	(segment
		(start 120.525032 -83.778598)
		(end 120.861836 -84.115402)
		(width 0.127)
		(layer "B.Cu")
		(net "SCC_TYPE_2_LS")
	)
	(segment
		(start 121.3866 -85.204554)
		(end 121.3866 -84.640166)
		(width 0.127)
		(layer "B.Cu")
		(net "SCC_TYPE_2_LS")
	)
	(segment
		(start 122.404124 -85.500972)
		(end 121.683018 -85.500972)
		(width 0.127)
		(layer "B.Cu")
		(net "SCC_TYPE_2_LS")
	)
	(segment
		(start 121.568972 -86.205568)
		(end 122.584972 -86.205568)
		(width 0.127)
		(layer "B.Cu")
		(net "SCC_TYPE_2_LS")
	)
	(segment
		(start 73.142602 -8.509)
		(end 73.88479 -8.509)
		(width 0.127)
		(layer "F.Cu")
		(net "SCC_TYPE_2")
	)
	(segment
		(start 73.88479 -8.509)
		(end 77.874114 -12.498324)
		(width 0.127)
		(layer "F.Cu")
		(net "SCC_TYPE_2")
	)
	(segment
		(start 77.874114 -18.052796)
		(end 78.382114 -18.560796)
		(width 0.127)
		(layer "F.Cu")
		(net "SCC_TYPE_2")
	)
	(segment
		(start 77.874114 -12.498324)
		(end 77.874114 -18.052796)
		(width 0.127)
		(layer "F.Cu")
		(net "SCC_TYPE_2")
	)
	(segment
		(start 70.5485 -8.509)
		(end 73.142602 -8.509)
		(width 0.127)
		(layer "F.Cu")
		(net "SCC_TYPE_2")
	)
	(via
		(at 78.382114 -18.560796)
		(size 0.508)
		(drill 0.254)
		(layers "F.Cu" "B.Cu")
		(net "SCC_TYPE_2")
	)
	(via
		(at 73.142602 -8.509)
		(size 0.6604)
		(drill 0.3302)
		(layers "F.Cu" "B.Cu")
		(net "SCC_TYPE_2")
	)
	(segment
		(start 93.83268 -14.58849)
		(end 89.860374 -18.560796)
		(width 0.127)
		(layer "In2.Cu")
		(net "SCC_TYPE_2")
	)
	(segment
		(start 93.83268 -7.367524)
		(end 93.83268 -14.58849)
		(width 0.127)
		(layer "In2.Cu")
		(net "SCC_TYPE_2")
	)
	(segment
		(start 89.860374 -18.560796)
		(end 78.382114 -18.560796)
		(width 0.127)
		(layer "In2.Cu")
		(net "SCC_TYPE_2")
	)
	(segment
		(start 95.000064 -6.20014)
		(end 93.83268 -7.367524)
		(width 0.127)
		(layer "In2.Cu")
		(net "SCC_TYPE_2")
	)
	(segment
		(start 116.500148 -74.500232)
		(end 116.000276 -75.000104)
		(width 0.127)
		(layer "F.Cu")
		(net "SCC_TYPE_1_LS")
	)
	(segment
		(start 99.939348 -87.6681)
		(end 99.669346 -87.398098)
		(width 0.127)
		(layer "F.Cu")
		(net "SCC_TYPE_1_LS")
	)
	(segment
		(start 99.669346 -86.503002)
		(end 99.669346 -85.765386)
		(width 0.127)
		(layer "F.Cu")
		(net "SCC_TYPE_1_LS")
	)
	(segment
		(start 100.483162 -87.6681)
		(end 99.939348 -87.6681)
		(width 0.127)
		(layer "F.Cu")
		(net "SCC_TYPE_1_LS")
	)
	(segment
		(start 99.669346 -87.398098)
		(end 99.669346 -86.503002)
		(width 0.127)
		(layer "F.Cu")
		(net "SCC_TYPE_1_LS")
	)
	(segment
		(start 101.6762 -87.6681)
		(end 100.483162 -87.6681)
		(width 0.127)
		(layer "F.Cu")
		(net "SCC_TYPE_1_LS")
	)
	(segment
		(start 99.669346 -85.765386)
		(end 99.811586 -85.623146)
		(width 0.127)
		(layer "F.Cu")
		(net "SCC_TYPE_1_LS")
	)
	(via
		(at 99.811586 -85.623146)
		(size 0.508)
		(drill 0.254)
		(layers "F.Cu" "B.Cu")
		(net "SCC_TYPE_1_LS")
	)
	(via
		(at 116.000276 -75.000104)
		(size 0.4572)
		(drill 0.2032)
		(layers "F.Cu" "B.Cu")
		(net "SCC_TYPE_1_LS")
	)
	(via
		(at 100.483162 -87.6681)
		(size 0.6604)
		(drill 0.3302)
		(layers "F.Cu" "B.Cu")
		(net "SCC_TYPE_1_LS")
	)
	(segment
		(start 106.08945 -84.4677)
		(end 100.967032 -84.4677)
		(width 0.127)
		(layer "In5.Cu")
		(net "SCC_TYPE_1_LS")
	)
	(segment
		(start 116.000276 -75.000104)
		(end 114.39398 -76.6064)
		(width 0.127)
		(layer "In5.Cu")
		(net "SCC_TYPE_1_LS")
	)
	(segment
		(start 109.393736 -80.163416)
		(end 108.95076 -80.606392)
		(width 0.127)
		(layer "In5.Cu")
		(net "SCC_TYPE_1_LS")
	)
	(segment
		(start 111.60633 -76.836778)
		(end 111.60633 -77.950822)
		(width 0.127)
		(layer "In5.Cu")
		(net "SCC_TYPE_1_LS")
	)
	(segment
		(start 111.836708 -76.6064)
		(end 111.60633 -76.836778)
		(width 0.127)
		(layer "In5.Cu")
		(net "SCC_TYPE_1_LS")
	)
	(segment
		(start 110.393734 -79.163418)
		(end 110.163356 -79.393796)
		(width 0.127)
		(layer "In5.Cu")
		(net "SCC_TYPE_1_LS")
	)
	(segment
		(start 109.393736 -80.04937)
		(end 109.393736 -80.163416)
		(width 0.127)
		(layer "In5.Cu")
		(net "SCC_TYPE_1_LS")
	)
	(segment
		(start 111.163354 -78.393798)
		(end 111.049308 -78.393798)
		(width 0.127)
		(layer "In5.Cu")
		(net "SCC_TYPE_1_LS")
	)
	(segment
		(start 100.967032 -84.4677)
		(end 99.811586 -85.623146)
		(width 0.127)
		(layer "In5.Cu")
		(net "SCC_TYPE_1_LS")
	)
	(segment
		(start 110.163356 -79.393796)
		(end 110.04931 -79.393796)
		(width 0.127)
		(layer "In5.Cu")
		(net "SCC_TYPE_1_LS")
	)
	(segment
		(start 110.393734 -79.049372)
		(end 110.393734 -79.163418)
		(width 0.127)
		(layer "In5.Cu")
		(net "SCC_TYPE_1_LS")
	)
	(segment
		(start 108.95076 -80.606392)
		(end 108.836714 -80.606392)
		(width 0.127)
		(layer "In5.Cu")
		(net "SCC_TYPE_1_LS")
	)
	(segment
		(start 114.39398 -76.6064)
		(end 111.836708 -76.6064)
		(width 0.127)
		(layer "In5.Cu")
		(net "SCC_TYPE_1_LS")
	)
	(segment
		(start 108.5088 -80.934306)
		(end 108.5088 -82.04835)
		(width 0.127)
		(layer "In5.Cu")
		(net "SCC_TYPE_1_LS")
	)
	(segment
		(start 110.04931 -79.393796)
		(end 109.393736 -80.04937)
		(width 0.127)
		(layer "In5.Cu")
		(net "SCC_TYPE_1_LS")
	)
	(segment
		(start 108.836714 -80.606392)
		(end 108.5088 -80.934306)
		(width 0.127)
		(layer "In5.Cu")
		(net "SCC_TYPE_1_LS")
	)
	(segment
		(start 111.60633 -77.950822)
		(end 111.163354 -78.393798)
		(width 0.127)
		(layer "In5.Cu")
		(net "SCC_TYPE_1_LS")
	)
	(segment
		(start 108.5088 -82.04835)
		(end 106.08945 -84.4677)
		(width 0.127)
		(layer "In5.Cu")
		(net "SCC_TYPE_1_LS")
	)
	(segment
		(start 111.049308 -78.393798)
		(end 110.393734 -79.049372)
		(width 0.127)
		(layer "In5.Cu")
		(net "SCC_TYPE_1_LS")
	)
	(segment
		(start 70.5485 -9.652)
		(end 71.925942 -9.652)
		(width 0.127)
		(layer "F.Cu")
		(net "SCC_TYPE_1")
	)
	(segment
		(start 77.366114 -13.373608)
		(end 77.366114 -17.507712)
		(width 0.127)
		(layer "F.Cu")
		(net "SCC_TYPE_1")
	)
	(segment
		(start 73.644506 -9.652)
		(end 77.366114 -13.373608)
		(width 0.127)
		(layer "F.Cu")
		(net "SCC_TYPE_1")
	)
	(segment
		(start 71.925942 -9.652)
		(end 73.644506 -9.652)
		(width 0.127)
		(layer "F.Cu")
		(net "SCC_TYPE_1")
	)
	(via
		(at 77.366114 -17.507712)
		(size 0.508)
		(drill 0.254)
		(layers "F.Cu" "B.Cu")
		(net "SCC_TYPE_1")
	)
	(via
		(at 71.925942 -9.652)
		(size 0.6604)
		(drill 0.3302)
		(layers "F.Cu" "B.Cu")
		(net "SCC_TYPE_1")
	)
	(segment
		(start 92.540836 -9.459214)
		(end 92.540836 -15.161768)
		(width 0.127)
		(layer "In2.Cu")
		(net "SCC_TYPE_1")
	)
	(segment
		(start 89.649808 -18.052796)
		(end 77.911198 -18.052796)
		(width 0.127)
		(layer "In2.Cu")
		(net "SCC_TYPE_1")
	)
	(segment
		(start 77.911198 -18.052796)
		(end 77.366114 -17.507712)
		(width 0.127)
		(layer "In2.Cu")
		(net "SCC_TYPE_1")
	)
	(segment
		(start 93.199966 -8.800084)
		(end 92.540836 -9.459214)
		(width 0.127)
		(layer "In2.Cu")
		(net "SCC_TYPE_1")
	)
	(segment
		(start 92.540836 -15.161768)
		(end 89.649808 -18.052796)
		(width 0.127)
		(layer "In2.Cu")
		(net "SCC_TYPE_1")
	)
	(segment
		(start 118.500144 -77.500226)
		(end 119.000016 -77.000354)
		(width 0.127)
		(layer "F.Cu")
		(net "SCC_TYPE_0_LS")
	)
	(via
		(at 119.000016 -77.000354)
		(size 0.4572)
		(drill 0.2032)
		(layers "F.Cu" "B.Cu")
		(net "SCC_TYPE_0_LS")
	)
	(via
		(at 102.0318 -85.6869)
		(size 0.508)
		(drill 0.254)
		(layers "F.Cu" "B.Cu")
		(net "SCC_TYPE_0_LS")
	)
	(via
		(at 102.0318 -86.6013)
		(size 0.6096)
		(drill 0.3048)
		(layers "F.Cu" "B.Cu")
		(net "SCC_TYPE_0_LS")
	)
	(segment
		(start 102.0318 -85.6869)
		(end 102.0318 -86.6013)
		(width 0.127)
		(layer "B.Cu")
		(net "SCC_TYPE_0_LS")
	)
	(segment
		(start 99.5426 -87.4141)
		(end 100.584 -87.4141)
		(width 0.127)
		(layer "B.Cu")
		(net "SCC_TYPE_0_LS")
	)
	(segment
		(start 101.795834 -87.4141)
		(end 100.584 -87.4141)
		(width 0.127)
		(layer "B.Cu")
		(net "SCC_TYPE_0_LS")
	)
	(segment
		(start 102.0318 -87.178134)
		(end 101.795834 -87.4141)
		(width 0.127)
		(layer "B.Cu")
		(net "SCC_TYPE_0_LS")
	)
	(segment
		(start 102.0318 -86.6013)
		(end 102.0318 -87.178134)
		(width 0.127)
		(layer "B.Cu")
		(net "SCC_TYPE_0_LS")
	)
	(segment
		(start 113.606326 -80.950816)
		(end 113.606326 -80.83677)
		(width 0.127)
		(layer "In5.Cu")
		(net "SCC_TYPE_0_LS")
	)
	(segment
		(start 115.606322 -78.836774)
		(end 115.8367 -78.606396)
		(width 0.127)
		(layer "In5.Cu")
		(net "SCC_TYPE_0_LS")
	)
	(segment
		(start 113.95075 -80.606392)
		(end 115.606322 -78.95082)
		(width 0.127)
		(layer "In5.Cu")
		(net "SCC_TYPE_0_LS")
	)
	(segment
		(start 102.7684 -84.9757)
		(end 106.63809 -84.9757)
		(width 0.127)
		(layer "In5.Cu")
		(net "SCC_TYPE_0_LS")
	)
	(segment
		(start 116.60632 -77.836776)
		(end 116.836698 -77.606398)
		(width 0.127)
		(layer "In5.Cu")
		(net "SCC_TYPE_0_LS")
	)
	(segment
		(start 110.186724 -81.427066)
		(end 113.130076 -81.427066)
		(width 0.127)
		(layer "In5.Cu")
		(net "SCC_TYPE_0_LS")
	)
	(segment
		(start 102.0318 -85.6869)
		(end 102.0572 -85.6869)
		(width 0.127)
		(layer "In5.Cu")
		(net "SCC_TYPE_0_LS")
	)
	(segment
		(start 113.606326 -80.83677)
		(end 113.836704 -80.606392)
		(width 0.127)
		(layer "In5.Cu")
		(net "SCC_TYPE_0_LS")
	)
	(segment
		(start 117.836696 -76.606654)
		(end 118.606316 -76.606654)
		(width 0.127)
		(layer "In5.Cu")
		(net "SCC_TYPE_0_LS")
	)
	(segment
		(start 115.950746 -78.606396)
		(end 116.60632 -77.950822)
		(width 0.127)
		(layer "In5.Cu")
		(net "SCC_TYPE_0_LS")
	)
	(segment
		(start 116.950744 -77.606398)
		(end 117.4242 -77.132942)
		(width 0.127)
		(layer "In5.Cu")
		(net "SCC_TYPE_0_LS")
	)
	(segment
		(start 115.8367 -78.606396)
		(end 115.950746 -78.606396)
		(width 0.127)
		(layer "In5.Cu")
		(net "SCC_TYPE_0_LS")
	)
	(segment
		(start 115.606322 -78.95082)
		(end 115.606322 -78.836774)
		(width 0.127)
		(layer "In5.Cu")
		(net "SCC_TYPE_0_LS")
	)
	(segment
		(start 118.606316 -76.606654)
		(end 119.000016 -77.000354)
		(width 0.127)
		(layer "In5.Cu")
		(net "SCC_TYPE_0_LS")
	)
	(segment
		(start 113.836704 -80.606392)
		(end 113.95075 -80.606392)
		(width 0.127)
		(layer "In5.Cu")
		(net "SCC_TYPE_0_LS")
	)
	(segment
		(start 117.4242 -77.01915)
		(end 117.836696 -76.606654)
		(width 0.127)
		(layer "In5.Cu")
		(net "SCC_TYPE_0_LS")
	)
	(segment
		(start 116.836698 -77.606398)
		(end 116.950744 -77.606398)
		(width 0.127)
		(layer "In5.Cu")
		(net "SCC_TYPE_0_LS")
	)
	(segment
		(start 113.130076 -81.427066)
		(end 113.606326 -80.950816)
		(width 0.127)
		(layer "In5.Cu")
		(net "SCC_TYPE_0_LS")
	)
	(segment
		(start 102.0572 -85.6869)
		(end 102.7684 -84.9757)
		(width 0.127)
		(layer "In5.Cu")
		(net "SCC_TYPE_0_LS")
	)
	(segment
		(start 116.60632 -77.950822)
		(end 116.60632 -77.836776)
		(width 0.127)
		(layer "In5.Cu")
		(net "SCC_TYPE_0_LS")
	)
	(segment
		(start 117.4242 -77.132942)
		(end 117.4242 -77.01915)
		(width 0.127)
		(layer "In5.Cu")
		(net "SCC_TYPE_0_LS")
	)
	(segment
		(start 106.63809 -84.9757)
		(end 110.186724 -81.427066)
		(width 0.127)
		(layer "In5.Cu")
		(net "SCC_TYPE_0_LS")
	)
	(segment
		(start 78.382114 -17.507712)
		(end 78.382114 -11.856212)
		(width 0.127)
		(layer "F.Cu")
		(net "SCC_TYPE_0")
	)
	(segment
		(start 71.938642 -7.366)
		(end 70.5485 -7.366)
		(width 0.127)
		(layer "F.Cu")
		(net "SCC_TYPE_0")
	)
	(segment
		(start 78.382114 -11.856212)
		(end 73.891902 -7.366)
		(width 0.127)
		(layer "F.Cu")
		(net "SCC_TYPE_0")
	)
	(segment
		(start 73.891902 -7.366)
		(end 71.938642 -7.366)
		(width 0.127)
		(layer "F.Cu")
		(net "SCC_TYPE_0")
	)
	(via
		(at 71.938642 -7.366)
		(size 0.6604)
		(drill 0.3302)
		(layers "F.Cu" "B.Cu")
		(net "SCC_TYPE_0")
	)
	(via
		(at 78.382114 -17.507712)
		(size 0.508)
		(drill 0.254)
		(layers "F.Cu" "B.Cu")
		(net "SCC_TYPE_0")
	)
	(segment
		(start 92.032582 -14.951456)
		(end 92.032582 -8.56742)
		(width 0.127)
		(layer "In2.Cu")
		(net "SCC_TYPE_0")
	)
	(segment
		(start 89.476326 -17.507712)
		(end 92.032582 -14.951456)
		(width 0.127)
		(layer "In2.Cu")
		(net "SCC_TYPE_0")
	)
	(segment
		(start 78.382114 -17.507712)
		(end 89.476326 -17.507712)
		(width 0.127)
		(layer "In2.Cu")
		(net "SCC_TYPE_0")
	)
	(segment
		(start 92.032582 -8.56742)
		(end 93.199966 -7.400036)
		(width 0.127)
		(layer "In2.Cu")
		(net "SCC_TYPE_0")
	)
	(segment
		(start 63.700914 -16.681958)
		(end 63.700914 -15.730982)
		(width 0.127)
		(layer "F.Cu")
		(net "LS_EN_U14")
	)
	(segment
		(start 63.902336 -15.52956)
		(end 64.417702 -15.52956)
		(width 0.127)
		(layer "F.Cu")
		(net "LS_EN_U14")
	)
	(segment
		(start 66.319908 -15.52956)
		(end 64.417702 -15.52956)
		(width 0.127)
		(layer "F.Cu")
		(net "LS_EN_U14")
	)
	(segment
		(start 63.700914 -15.730982)
		(end 63.902336 -15.52956)
		(width 0.127)
		(layer "F.Cu")
		(net "LS_EN_U14")
	)
	(via
		(at 64.417702 -15.52956)
		(size 0.6604)
		(drill 0.3302)
		(layers "F.Cu" "B.Cu")
		(net "LS_EN_U14")
	)
	(segment
		(start 165.469824 -8.087106)
		(end 166.983664 -8.087106)
		(width 0.127)
		(layer "F.Cu")
		(net "LS_EN_U12")
	)
	(segment
		(start 166.983664 -8.087106)
		(end 166.98976 -8.08101)
		(width 0.127)
		(layer "F.Cu")
		(net "LS_EN_U12")
	)
	(segment
		(start 168.732454 -8.08101)
		(end 166.98976 -8.08101)
		(width 0.127)
		(layer "F.Cu")
		(net "LS_EN_U12")
	)
	(segment
		(start 164.690044 -7.307326)
		(end 165.469824 -8.087106)
		(width 0.127)
		(layer "F.Cu")
		(net "LS_EN_U12")
	)
	(segment
		(start 164.690044 -6.418072)
		(end 164.690044 -7.307326)
		(width 0.127)
		(layer "F.Cu")
		(net "LS_EN_U12")
	)
	(via
		(at 166.98976 -8.08101)
		(size 0.6604)
		(drill 0.3302)
		(layers "F.Cu" "B.Cu")
		(net "LS_EN_U12")
	)
	(segment
		(start 9.493504 -86.531704)
		(end 10.245344 -86.531704)
		(width 0.127)
		(layer "F.Cu")
		(net "I2C_SCC_SDA2_LS")
	)
	(segment
		(start 9.18083 -87.428578)
		(end 9.18083 -86.844378)
		(width 0.127)
		(layer "F.Cu")
		(net "I2C_SCC_SDA2_LS")
	)
	(segment
		(start 10.49655 -85.86343)
		(end 10.49655 -84.904072)
		(width 0.127)
		(layer "F.Cu")
		(net "I2C_SCC_SDA2_LS")
	)
	(segment
		(start 9.18083 -86.844378)
		(end 9.493504 -86.531704)
		(width 0.127)
		(layer "F.Cu")
		(net "I2C_SCC_SDA2_LS")
	)
	(segment
		(start 10.245344 -86.531704)
		(end 10.49655 -86.280498)
		(width 0.127)
		(layer "F.Cu")
		(net "I2C_SCC_SDA2_LS")
	)
	(segment
		(start 123.500134 -74.500232)
		(end 124.000006 -75.000104)
		(width 0.127)
		(layer "F.Cu")
		(net "I2C_SCC_SDA2_LS")
	)
	(segment
		(start 10.49655 -86.280498)
		(end 10.49655 -85.86343)
		(width 0.127)
		(layer "F.Cu")
		(net "I2C_SCC_SDA2_LS")
	)
	(via
		(at 124.000006 -75.000104)
		(size 0.4572)
		(drill 0.2032)
		(layers "F.Cu" "B.Cu")
		(net "I2C_SCC_SDA2_LS")
	)
	(via
		(at 138.7094 -88.4682)
		(size 0.508)
		(drill 0.254)
		(layers "F.Cu" "B.Cu")
		(net "I2C_SCC_SDA2_LS")
	)
	(via
		(at 10.49655 -84.904072)
		(size 0.508)
		(drill 0.254)
		(layers "F.Cu" "B.Cu")
		(net "I2C_SCC_SDA2_LS")
	)
	(via
		(at 10.49655 -85.86343)
		(size 0.6604)
		(drill 0.3302)
		(layers "F.Cu" "B.Cu")
		(net "I2C_SCC_SDA2_LS")
	)
	(segment
		(start 138.4808 -89.2429)
		(end 138.4808 -88.6968)
		(width 0.127)
		(layer "B.Cu")
		(net "I2C_SCC_SDA2_LS")
	)
	(segment
		(start 138.4808 -88.6968)
		(end 138.7094 -88.4682)
		(width 0.127)
		(layer "B.Cu")
		(net "I2C_SCC_SDA2_LS")
	)
	(segment
		(start 124.442982 -75.000104)
		(end 124.000006 -75.000104)
		(width 0.127)
		(layer "In2.Cu")
		(net "I2C_SCC_SDA2_LS")
	)
	(segment
		(start 130.753612 -85.151214)
		(end 130.753612 -84.134452)
		(width 0.127)
		(layer "In2.Cu")
		(net "I2C_SCC_SDA2_LS")
	)
	(segment
		(start 129.841244 -79.284322)
		(end 129.12725 -78.570328)
		(width 0.127)
		(layer "In2.Cu")
		(net "I2C_SCC_SDA2_LS")
	)
	(segment
		(start 124.987812 -75.544934)
		(end 124.442982 -75.000104)
		(width 0.127)
		(layer "In2.Cu")
		(net "I2C_SCC_SDA2_LS")
	)
	(segment
		(start 127.916432 -76.473558)
		(end 127.596138 -76.153264)
		(width 0.127)
		(layer "In2.Cu")
		(net "I2C_SCC_SDA2_LS")
	)
	(segment
		(start 127.596138 -76.153264)
		(end 127.596138 -75.999848)
		(width 0.127)
		(layer "In2.Cu")
		(net "I2C_SCC_SDA2_LS")
	)
	(segment
		(start 130.753612 -84.134452)
		(end 129.841244 -83.222084)
		(width 0.127)
		(layer "In2.Cu")
		(net "I2C_SCC_SDA2_LS")
	)
	(segment
		(start 129.841244 -83.222084)
		(end 129.841244 -79.284322)
		(width 0.127)
		(layer "In2.Cu")
		(net "I2C_SCC_SDA2_LS")
	)
	(segment
		(start 127.141224 -75.544934)
		(end 124.987812 -75.544934)
		(width 0.127)
		(layer "In2.Cu")
		(net "I2C_SCC_SDA2_LS")
	)
	(segment
		(start 133.050026 -87.447628)
		(end 130.753612 -85.151214)
		(width 0.127)
		(layer "In2.Cu")
		(net "I2C_SCC_SDA2_LS")
	)
	(segment
		(start 129.12725 -78.570328)
		(end 129.013204 -78.570328)
		(width 0.127)
		(layer "In2.Cu")
		(net "I2C_SCC_SDA2_LS")
	)
	(segment
		(start 128.548892 -76.991972)
		(end 128.030478 -76.473558)
		(width 0.127)
		(layer "In2.Cu")
		(net "I2C_SCC_SDA2_LS")
	)
	(segment
		(start 129.013204 -78.570328)
		(end 128.548892 -78.106016)
		(width 0.127)
		(layer "In2.Cu")
		(net "I2C_SCC_SDA2_LS")
	)
	(segment
		(start 138.7094 -88.4682)
		(end 137.688828 -87.447628)
		(width 0.127)
		(layer "In2.Cu")
		(net "I2C_SCC_SDA2_LS")
	)
	(segment
		(start 128.548892 -78.106016)
		(end 128.548892 -76.991972)
		(width 0.127)
		(layer "In2.Cu")
		(net "I2C_SCC_SDA2_LS")
	)
	(segment
		(start 137.688828 -87.447628)
		(end 133.050026 -87.447628)
		(width 0.127)
		(layer "In2.Cu")
		(net "I2C_SCC_SDA2_LS")
	)
	(segment
		(start 128.030478 -76.473558)
		(end 127.916432 -76.473558)
		(width 0.127)
		(layer "In2.Cu")
		(net "I2C_SCC_SDA2_LS")
	)
	(segment
		(start 127.596138 -75.999848)
		(end 127.141224 -75.544934)
		(width 0.127)
		(layer "In2.Cu")
		(net "I2C_SCC_SDA2_LS")
	)
	(segment
		(start 136.655048 -97.050098)
		(end 138.33602 -95.369126)
		(width 0.127)
		(layer "In5.Cu")
		(net "I2C_SCC_SDA2_LS")
	)
	(segment
		(start 129.33426 -97.759774)
		(end 135.562086 -97.759774)
		(width 0.127)
		(layer "In5.Cu")
		(net "I2C_SCC_SDA2_LS")
	)
	(segment
		(start 12.60729 -94.387924)
		(end 15.6464 -97.427034)
		(width 0.127)
		(layer "In5.Cu")
		(net "I2C_SCC_SDA2_LS")
	)
	(segment
		(start 124.222764 -99.579938)
		(end 125.415802 -98.3869)
		(width 0.127)
		(layer "In5.Cu")
		(net "I2C_SCC_SDA2_LS")
	)
	(segment
		(start 10.49655 -88.37295)
		(end 12.60729 -90.48369)
		(width 0.127)
		(layer "In5.Cu")
		(net "I2C_SCC_SDA2_LS")
	)
	(segment
		(start 128.707134 -98.3869)
		(end 129.33426 -97.759774)
		(width 0.127)
		(layer "In5.Cu")
		(net "I2C_SCC_SDA2_LS")
	)
	(segment
		(start 15.6464 -97.427034)
		(end 15.6464 -102.159562)
		(width 0.127)
		(layer "In5.Cu")
		(net "I2C_SCC_SDA2_LS")
	)
	(segment
		(start 135.562086 -97.759774)
		(end 136.447276 -97.184972)
		(width 0.127)
		(layer "In5.Cu")
		(net "I2C_SCC_SDA2_LS")
	)
	(segment
		(start 64.299846 -123.232418)
		(end 79.620364 -107.9119)
		(width 0.127)
		(layer "In5.Cu")
		(net "I2C_SCC_SDA2_LS")
	)
	(segment
		(start 124.111258 -99.579938)
		(end 124.222764 -99.579938)
		(width 0.127)
		(layer "In5.Cu")
		(net "I2C_SCC_SDA2_LS")
	)
	(segment
		(start 138.7094 -89.844626)
		(end 138.7094 -88.4682)
		(width 0.127)
		(layer "In5.Cu")
		(net "I2C_SCC_SDA2_LS")
	)
	(segment
		(start 12.60729 -90.48369)
		(end 12.60729 -94.387924)
		(width 0.127)
		(layer "In5.Cu")
		(net "I2C_SCC_SDA2_LS")
	)
	(segment
		(start 103.51135 -99.579938)
		(end 121.584466 -99.579938)
		(width 0.127)
		(layer "In5.Cu")
		(net "I2C_SCC_SDA2_LS")
	)
	(segment
		(start 124.111004 -99.580192)
		(end 124.111258 -99.579938)
		(width 0.127)
		(layer "In5.Cu")
		(net "I2C_SCC_SDA2_LS")
	)
	(segment
		(start 136.447276 -97.184972)
		(end 136.44753 -97.184972)
		(width 0.127)
		(layer "In5.Cu")
		(net "I2C_SCC_SDA2_LS")
	)
	(segment
		(start 138.33602 -95.369126)
		(end 138.33602 -90.218006)
		(width 0.127)
		(layer "In5.Cu")
		(net "I2C_SCC_SDA2_LS")
	)
	(segment
		(start 79.620364 -107.9119)
		(end 95.179388 -107.9119)
		(width 0.127)
		(layer "In5.Cu")
		(net "I2C_SCC_SDA2_LS")
	)
	(segment
		(start 15.6464 -102.159562)
		(end 36.719256 -123.232418)
		(width 0.127)
		(layer "In5.Cu")
		(net "I2C_SCC_SDA2_LS")
	)
	(segment
		(start 36.719256 -123.232418)
		(end 64.299846 -123.232418)
		(width 0.127)
		(layer "In5.Cu")
		(net "I2C_SCC_SDA2_LS")
	)
	(segment
		(start 138.33602 -90.218006)
		(end 138.7094 -89.844626)
		(width 0.127)
		(layer "In5.Cu")
		(net "I2C_SCC_SDA2_LS")
	)
	(segment
		(start 10.49655 -84.904072)
		(end 10.49655 -88.37295)
		(width 0.127)
		(layer "In5.Cu")
		(net "I2C_SCC_SDA2_LS")
	)
	(segment
		(start 121.584466 -99.579938)
		(end 121.58472 -99.580192)
		(width 0.127)
		(layer "In5.Cu")
		(net "I2C_SCC_SDA2_LS")
	)
	(segment
		(start 121.58472 -99.580192)
		(end 124.111004 -99.580192)
		(width 0.127)
		(layer "In5.Cu")
		(net "I2C_SCC_SDA2_LS")
	)
	(segment
		(start 125.415802 -98.3869)
		(end 128.707134 -98.3869)
		(width 0.127)
		(layer "In5.Cu")
		(net "I2C_SCC_SDA2_LS")
	)
	(segment
		(start 95.179388 -107.9119)
		(end 103.51135 -99.579938)
		(width 0.127)
		(layer "In5.Cu")
		(net "I2C_SCC_SDA2_LS")
	)
	(segment
		(start 136.44753 -97.184972)
		(end 136.655048 -97.050098)
		(width 0.127)
		(layer "In5.Cu")
		(net "I2C_SCC_SDA2_LS")
	)
	(segment
		(start 202.7936 -49.218088)
		(end 202.7936 -53.568092)
		(width 0.127)
		(layer "F.Cu")
		(net "I2C_SCC_SDA2")
	)
	(segment
		(start 9.9949 -93.1799)
		(end 9.7028 -93.1799)
		(width 0.127)
		(layer "F.Cu")
		(net "I2C_SCC_SDA2")
	)
	(segment
		(start 10.1854 -92.9894)
		(end 9.9949 -93.1799)
		(width 0.127)
		(layer "F.Cu")
		(net "I2C_SCC_SDA2")
	)
	(segment
		(start 9.18083 -91.70543)
		(end 9.18083 -90.679778)
		(width 0.127)
		(layer "F.Cu")
		(net "I2C_SCC_SDA2")
	)
	(segment
		(start 202.7936 -53.568092)
		(end 203.610972 -54.385464)
		(width 0.127)
		(layer "F.Cu")
		(net "I2C_SCC_SDA2")
	)
	(segment
		(start 185.04789 -19.473418)
		(end 189.971426 -19.473418)
		(width 0.127)
		(layer "F.Cu")
		(net "I2C_SCC_SDA2")
	)
	(segment
		(start 201.371708 -21.16328)
		(end 201.371708 -33.399222)
		(width 0.127)
		(layer "F.Cu")
		(net "I2C_SCC_SDA2")
	)
	(segment
		(start 19.696684 -70.28053)
		(end 20.494752 -70.28053)
		(width 0.127)
		(layer "F.Cu")
		(net "I2C_SCC_SDA2")
	)
	(segment
		(start 201.371708 -33.399222)
		(end 201.10831 -33.66262)
		(width 0.127)
		(layer "F.Cu")
		(net "I2C_SCC_SDA2")
	)
	(segment
		(start 151.004778 -70.050406)
		(end 153.930096 -70.050406)
		(width 0.127)
		(layer "F.Cu")
		(net "I2C_SCC_SDA2")
	)
	(segment
		(start 183.599836 -8.800084)
		(end 184.25668 -9.456928)
		(width 0.127)
		(layer "F.Cu")
		(net "I2C_SCC_SDA2")
	)
	(segment
		(start 201.10831 -47.532798)
		(end 202.7936 -49.218088)
		(width 0.127)
		(layer "F.Cu")
		(net "I2C_SCC_SDA2")
	)
	(segment
		(start 20.447 -77.343)
		(end 20.4724 -77.3684)
		(width 0.127)
		(layer "F.Cu")
		(net "I2C_SCC_SDA2")
	)
	(segment
		(start 10.1854 -92.3036)
		(end 10.1854 -92.9894)
		(width 0.127)
		(layer "F.Cu")
		(net "I2C_SCC_SDA2")
	)
	(segment
		(start 154.612594 -70.732904)
		(end 154.612594 -71.15937)
		(width 0.127)
		(layer "F.Cu")
		(net "I2C_SCC_SDA2")
	)
	(segment
		(start 19.6723 -77.343)
		(end 20.447 -77.343)
		(width 0.127)
		(layer "F.Cu")
		(net "I2C_SCC_SDA2")
	)
	(segment
		(start 203.135992 -76.86548)
		(end 202.74788 -76.86548)
		(width 0.127)
		(layer "F.Cu")
		(net "I2C_SCC_SDA2")
	)
	(segment
		(start 151.7523 -81.4705)
		(end 150.278592 -79.996792)
		(width 0.127)
		(layer "F.Cu")
		(net "I2C_SCC_SDA2")
	)
	(segment
		(start 152.185624 -81.903824)
		(end 151.7523 -81.4705)
		(width 0.127)
		(layer "F.Cu")
		(net "I2C_SCC_SDA2")
	)
	(segment
		(start 184.25668 -18.682208)
		(end 185.04789 -19.473418)
		(width 0.127)
		(layer "F.Cu")
		(net "I2C_SCC_SDA2")
	)
	(segment
		(start 9.7028 -93.1799)
		(end 9.7028 -92.2274)
		(width 0.127)
		(layer "F.Cu")
		(net "I2C_SCC_SDA2")
	)
	(segment
		(start 11.668252 -59.805316)
		(end 11.668252 -60.258452)
		(width 0.127)
		(layer "F.Cu")
		(net "I2C_SCC_SDA2")
	)
	(segment
		(start 12.52728 -61.11748)
		(end 12.52728 -63.57112)
		(width 0.127)
		(layer "F.Cu")
		(net "I2C_SCC_SDA2")
	)
	(segment
		(start 152.536398 -81.903824)
		(end 152.185624 -81.903824)
		(width 0.127)
		(layer "F.Cu")
		(net "I2C_SCC_SDA2")
	)
	(segment
		(start 184.25668 -9.456928)
		(end 184.25668 -18.682208)
		(width 0.127)
		(layer "F.Cu")
		(net "I2C_SCC_SDA2")
	)
	(segment
		(start 11.668252 -60.258452)
		(end 12.52728 -61.11748)
		(width 0.127)
		(layer "F.Cu")
		(net "I2C_SCC_SDA2")
	)
	(segment
		(start 9.7028 -92.2274)
		(end 9.18083 -91.70543)
		(width 0.127)
		(layer "F.Cu")
		(net "I2C_SCC_SDA2")
	)
	(segment
		(start 153.930096 -70.050406)
		(end 154.612594 -70.732904)
		(width 0.127)
		(layer "F.Cu")
		(net "I2C_SCC_SDA2")
	)
	(segment
		(start 201.10831 -33.66262)
		(end 201.10831 -47.532798)
		(width 0.127)
		(layer "F.Cu")
		(net "I2C_SCC_SDA2")
	)
	(segment
		(start 199.681846 -19.473418)
		(end 201.371708 -21.16328)
		(width 0.127)
		(layer "F.Cu")
		(net "I2C_SCC_SDA2")
	)
	(segment
		(start 189.971426 -19.473418)
		(end 199.681846 -19.473418)
		(width 0.127)
		(layer "F.Cu")
		(net "I2C_SCC_SDA2")
	)
	(segment
		(start 150.278592 -70.776592)
		(end 151.004778 -70.050406)
		(width 0.127)
		(layer "F.Cu")
		(net "I2C_SCC_SDA2")
	)
	(segment
		(start 150.278592 -79.996792)
		(end 150.278592 -70.776592)
		(width 0.127)
		(layer "F.Cu")
		(net "I2C_SCC_SDA2")
	)
	(segment
		(start 203.670662 -76.33081)
		(end 203.135992 -76.86548)
		(width 0.127)
		(layer "F.Cu")
		(net "I2C_SCC_SDA2")
	)
	(via
		(at 20.494752 -70.28053)
		(size 0.508)
		(drill 0.254)
		(layers "F.Cu" "B.Cu")
		(net "I2C_SCC_SDA2")
	)
	(via
		(at 203.610972 -54.385464)
		(size 0.508)
		(drill 0.254)
		(layers "F.Cu" "B.Cu")
		(net "I2C_SCC_SDA2")
	)
	(via
		(at 203.670662 -76.33081)
		(size 0.508)
		(drill 0.254)
		(layers "F.Cu" "B.Cu")
		(net "I2C_SCC_SDA2")
	)
	(via
		(at 20.4724 -77.3684)
		(size 0.508)
		(drill 0.254)
		(layers "F.Cu" "B.Cu")
		(net "I2C_SCC_SDA2")
	)
	(via
		(at 10.1854 -92.3036)
		(size 0.508)
		(drill 0.254)
		(layers "F.Cu" "B.Cu")
		(net "I2C_SCC_SDA2")
	)
	(via
		(at 158.488126 -81.275936)
		(size 0.6096)
		(drill 0.3048)
		(layers "F.Cu" "B.Cu")
		(net "I2C_SCC_SDA2")
	)
	(via
		(at 189.971426 -19.473418)
		(size 0.508)
		(drill 0.254)
		(layers "F.Cu" "B.Cu")
		(net "I2C_SCC_SDA2")
	)
	(via
		(at 12.52728 -63.57112)
		(size 0.508)
		(drill 0.254)
		(layers "F.Cu" "B.Cu")
		(net "I2C_SCC_SDA2")
	)
	(via
		(at 151.7523 -81.4705)
		(size 0.508)
		(drill 0.254)
		(layers "F.Cu" "B.Cu")
		(net "I2C_SCC_SDA2")
	)
	(via
		(at 93.995494 -43.797982)
		(size 0.508)
		(drill 0.254)
		(layers "F.Cu" "B.Cu")
		(net "I2C_SCC_SDA2")
	)
	(segment
		(start 203.670662 -76.33081)
		(end 202.688952 -77.31252)
		(width 0.127)
		(layer "B.Cu")
		(net "I2C_SCC_SDA2")
	)
	(segment
		(start 158.488126 -81.275936)
		(end 151.946864 -81.275936)
		(width 0.127)
		(layer "B.Cu")
		(net "I2C_SCC_SDA2")
	)
	(segment
		(start 185.17108 -75.12304)
		(end 167.05707 -75.12304)
		(width 0.127)
		(layer "B.Cu")
		(net "I2C_SCC_SDA2")
	)
	(segment
		(start 187.36056 -77.31252)
		(end 185.17108 -75.12304)
		(width 0.127)
		(layer "B.Cu")
		(net "I2C_SCC_SDA2")
	)
	(segment
		(start 151.946864 -81.275936)
		(end 151.7523 -81.4705)
		(width 0.127)
		(layer "B.Cu")
		(net "I2C_SCC_SDA2")
	)
	(segment
		(start 202.688952 -77.31252)
		(end 187.36056 -77.31252)
		(width 0.127)
		(layer "B.Cu")
		(net "I2C_SCC_SDA2")
	)
	(segment
		(start 160.904174 -81.275936)
		(end 158.488126 -81.275936)
		(width 0.127)
		(layer "B.Cu")
		(net "I2C_SCC_SDA2")
	)
	(segment
		(start 167.05707 -75.12304)
		(end 160.904174 -81.275936)
		(width 0.127)
		(layer "B.Cu")
		(net "I2C_SCC_SDA2")
	)
	(segment
		(start 150.030434 -21.82368)
		(end 138.336274 -21.82368)
		(width 0.127)
		(layer "In2.Cu")
		(net "I2C_SCC_SDA2")
	)
	(segment
		(start 165.0238 -12.5984)
		(end 162.7632 -14.859)
		(width 0.127)
		(layer "In2.Cu")
		(net "I2C_SCC_SDA2")
	)
	(segment
		(start 102.110794 -44.341034)
		(end 94.538546 -44.341034)
		(width 0.127)
		(layer "In2.Cu")
		(net "I2C_SCC_SDA2")
	)
	(segment
		(start 108.600748 -37.85108)
		(end 102.110794 -44.341034)
		(width 0.127)
		(layer "In2.Cu")
		(net "I2C_SCC_SDA2")
	)
	(segment
		(start 189.971426 -19.473418)
		(end 185.702956 -19.473418)
		(width 0.127)
		(layer "In2.Cu")
		(net "I2C_SCC_SDA2")
	)
	(segment
		(start 156.995114 -14.859)
		(end 150.030434 -21.82368)
		(width 0.127)
		(layer "In2.Cu")
		(net "I2C_SCC_SDA2")
	)
	(segment
		(start 94.538546 -44.341034)
		(end 93.995494 -43.797982)
		(width 0.127)
		(layer "In2.Cu")
		(net "I2C_SCC_SDA2")
	)
	(segment
		(start 167.103298 -12.5984)
		(end 165.0238 -12.5984)
		(width 0.127)
		(layer "In2.Cu")
		(net "I2C_SCC_SDA2")
	)
	(segment
		(start 138.336274 -21.82368)
		(end 122.308874 -37.85108)
		(width 0.127)
		(layer "In2.Cu")
		(net "I2C_SCC_SDA2")
	)
	(segment
		(start 168.012872 -11.688826)
		(end 167.103298 -12.5984)
		(width 0.127)
		(layer "In2.Cu")
		(net "I2C_SCC_SDA2")
	)
	(segment
		(start 184.236868 -18.00733)
		(end 176.88433 -18.00733)
		(width 0.127)
		(layer "In2.Cu")
		(net "I2C_SCC_SDA2")
	)
	(segment
		(start 185.702956 -19.473418)
		(end 184.236868 -18.00733)
		(width 0.127)
		(layer "In2.Cu")
		(net "I2C_SCC_SDA2")
	)
	(segment
		(start 176.88433 -18.00733)
		(end 170.565826 -11.688826)
		(width 0.127)
		(layer "In2.Cu")
		(net "I2C_SCC_SDA2")
	)
	(segment
		(start 170.565826 -11.688826)
		(end 168.012872 -11.688826)
		(width 0.127)
		(layer "In2.Cu")
		(net "I2C_SCC_SDA2")
	)
	(segment
		(start 162.7632 -14.859)
		(end 156.995114 -14.859)
		(width 0.127)
		(layer "In2.Cu")
		(net "I2C_SCC_SDA2")
	)
	(segment
		(start 122.308874 -37.85108)
		(end 108.600748 -37.85108)
		(width 0.127)
		(layer "In2.Cu")
		(net "I2C_SCC_SDA2")
	)
	(segment
		(start 9.906 -91.3638)
		(end 9.906 -92.0242)
		(width 0.127)
		(layer "In5.Cu")
		(net "I2C_SCC_SDA2")
	)
	(segment
		(start 12.52728 -63.57112)
		(end 12.52728 -65.002918)
		(width 0.127)
		(layer "In5.Cu")
		(net "I2C_SCC_SDA2")
	)
	(segment
		(start 31.877 -26.5176)
		(end 31.877 -34.587434)
		(width 0.127)
		(layer "In5.Cu")
		(net "I2C_SCC_SDA2")
	)
	(segment
		(start 21.025104 -63.57112)
		(end 12.52728 -63.57112)
		(width 0.127)
		(layer "In5.Cu")
		(net "I2C_SCC_SDA2")
	)
	(segment
		(start 17.244822 -67.0306)
		(end 20.494752 -70.28053)
		(width 0.127)
		(layer "In5.Cu")
		(net "I2C_SCC_SDA2")
	)
	(segment
		(start 93.936312 -43.797982)
		(end 91.369642 -41.231312)
		(width 0.127)
		(layer "In5.Cu")
		(net "I2C_SCC_SDA2")
	)
	(segment
		(start 45.742098 -24.314658)
		(end 34.079942 -24.314658)
		(width 0.127)
		(layer "In5.Cu")
		(net "I2C_SCC_SDA2")
	)
	(segment
		(start 9.005062 -90.462862)
		(end 9.906 -91.3638)
		(width 0.127)
		(layer "In5.Cu")
		(net "I2C_SCC_SDA2")
	)
	(segment
		(start 57.631584 -12.425172)
		(end 45.742098 -24.314658)
		(width 0.127)
		(layer "In5.Cu")
		(net "I2C_SCC_SDA2")
	)
	(segment
		(start 203.610972 -76.27112)
		(end 203.670662 -76.33081)
		(width 0.127)
		(layer "In5.Cu")
		(net "I2C_SCC_SDA2")
	)
	(segment
		(start 91.369642 -35.22218)
		(end 90.401394 -34.253932)
		(width 0.127)
		(layer "In5.Cu")
		(net "I2C_SCC_SDA2")
	)
	(segment
		(start 93.995494 -43.797982)
		(end 93.936312 -43.797982)
		(width 0.127)
		(layer "In5.Cu")
		(net "I2C_SCC_SDA2")
	)
	(segment
		(start 13.932154 -79.9084)
		(end 9.005062 -84.835492)
		(width 0.127)
		(layer "In5.Cu")
		(net "I2C_SCC_SDA2")
	)
	(segment
		(start 203.610972 -54.385464)
		(end 203.610972 -76.27112)
		(width 0.127)
		(layer "In5.Cu")
		(net "I2C_SCC_SDA2")
	)
	(segment
		(start 21.118576 -79.338424)
		(end 20.5486 -79.9084)
		(width 0.127)
		(layer "In5.Cu")
		(net "I2C_SCC_SDA2")
	)
	(segment
		(start 26.170636 -40.293798)
		(end 26.170636 -58.425588)
		(width 0.127)
		(layer "In5.Cu")
		(net "I2C_SCC_SDA2")
	)
	(segment
		(start 91.369642 -41.231312)
		(end 91.369642 -35.22218)
		(width 0.127)
		(layer "In5.Cu")
		(net "I2C_SCC_SDA2")
	)
	(segment
		(start 78.063598 -12.425172)
		(end 57.631584 -12.425172)
		(width 0.127)
		(layer "In5.Cu")
		(net "I2C_SCC_SDA2")
	)
	(segment
		(start 20.494752 -70.28053)
		(end 21.082 -70.867778)
		(width 0.127)
		(layer "In5.Cu")
		(net "I2C_SCC_SDA2")
	)
	(segment
		(start 31.877 -34.587434)
		(end 26.170636 -40.293798)
		(width 0.127)
		(layer "In5.Cu")
		(net "I2C_SCC_SDA2")
	)
	(segment
		(start 20.4724 -76.454)
		(end 20.4724 -77.3684)
		(width 0.127)
		(layer "In5.Cu")
		(net "I2C_SCC_SDA2")
	)
	(segment
		(start 20.4724 -77.3684)
		(end 21.118576 -78.014576)
		(width 0.127)
		(layer "In5.Cu")
		(net "I2C_SCC_SDA2")
	)
	(segment
		(start 20.5486 -79.9084)
		(end 13.932154 -79.9084)
		(width 0.127)
		(layer "In5.Cu")
		(net "I2C_SCC_SDA2")
	)
	(segment
		(start 21.082 -70.867778)
		(end 21.082 -75.8444)
		(width 0.127)
		(layer "In5.Cu")
		(net "I2C_SCC_SDA2")
	)
	(segment
		(start 90.401394 -34.253932)
		(end 90.401394 -24.762968)
		(width 0.127)
		(layer "In5.Cu")
		(net "I2C_SCC_SDA2")
	)
	(segment
		(start 26.170636 -58.425588)
		(end 21.025104 -63.57112)
		(width 0.127)
		(layer "In5.Cu")
		(net "I2C_SCC_SDA2")
	)
	(segment
		(start 9.005062 -84.835492)
		(end 9.005062 -90.462862)
		(width 0.127)
		(layer "In5.Cu")
		(net "I2C_SCC_SDA2")
	)
	(segment
		(start 9.906 -92.0242)
		(end 10.1854 -92.3036)
		(width 0.127)
		(layer "In5.Cu")
		(net "I2C_SCC_SDA2")
	)
	(segment
		(start 21.082 -75.8444)
		(end 20.4724 -76.454)
		(width 0.127)
		(layer "In5.Cu")
		(net "I2C_SCC_SDA2")
	)
	(segment
		(start 34.079942 -24.314658)
		(end 31.877 -26.5176)
		(width 0.127)
		(layer "In5.Cu")
		(net "I2C_SCC_SDA2")
	)
	(segment
		(start 90.401394 -24.762968)
		(end 78.063598 -12.425172)
		(width 0.127)
		(layer "In5.Cu")
		(net "I2C_SCC_SDA2")
	)
	(segment
		(start 14.554962 -67.0306)
		(end 17.244822 -67.0306)
		(width 0.127)
		(layer "In5.Cu")
		(net "I2C_SCC_SDA2")
	)
	(segment
		(start 12.52728 -65.002918)
		(end 14.554962 -67.0306)
		(width 0.127)
		(layer "In5.Cu")
		(net "I2C_SCC_SDA2")
	)
	(segment
		(start 21.118576 -78.014576)
		(end 21.118576 -79.338424)
		(width 0.127)
		(layer "In5.Cu")
		(net "I2C_SCC_SDA2")
	)
	(segment
		(start 9.6266 -84.93252)
		(end 9.6266 -85.38718)
		(width 0.127)
		(layer "F.Cu")
		(net "I2C_SCC_SCL2_LS")
	)
	(segment
		(start 9.6266 -85.38718)
		(end 9.22655 -85.78723)
		(width 0.127)
		(layer "F.Cu")
		(net "I2C_SCC_SCL2_LS")
	)
	(segment
		(start 8.53059 -87.428578)
		(end 8.53059 -86.48319)
		(width 0.127)
		(layer "F.Cu")
		(net "I2C_SCC_SCL2_LS")
	)
	(segment
		(start 8.53059 -86.48319)
		(end 9.22655 -85.78723)
		(width 0.127)
		(layer "F.Cu")
		(net "I2C_SCC_SCL2_LS")
	)
	(segment
		(start 122.500136 -72.500236)
		(end 123.000008 -73.000108)
		(width 0.127)
		(layer "F.Cu")
		(net "I2C_SCC_SCL2_LS")
	)
	(via
		(at 139.7254 -88.4682)
		(size 0.508)
		(drill 0.254)
		(layers "F.Cu" "B.Cu")
		(net "I2C_SCC_SCL2_LS")
	)
	(via
		(at 123.000008 -73.000108)
		(size 0.4572)
		(drill 0.2032)
		(layers "F.Cu" "B.Cu")
		(net "I2C_SCC_SCL2_LS")
	)
	(via
		(at 9.6266 -84.93252)
		(size 0.508)
		(drill 0.254)
		(layers "F.Cu" "B.Cu")
		(net "I2C_SCC_SCL2_LS")
	)
	(via
		(at 9.22655 -85.78723)
		(size 0.6604)
		(drill 0.3302)
		(layers "F.Cu" "B.Cu")
		(net "I2C_SCC_SCL2_LS")
	)
	(segment
		(start 139.4968 -88.6968)
		(end 139.7254 -88.4682)
		(width 0.127)
		(layer "B.Cu")
		(net "I2C_SCC_SCL2_LS")
	)
	(segment
		(start 139.4968 -89.2429)
		(end 139.4968 -88.6968)
		(width 0.127)
		(layer "B.Cu")
		(net "I2C_SCC_SCL2_LS")
	)
	(segment
		(start 125.85065 -74.54265)
		(end 125.5268 -74.2188)
		(width 0.127)
		(layer "In2.Cu")
		(net "I2C_SCC_SCL2_LS")
	)
	(segment
		(start 127.553212 -74.956924)
		(end 127.138938 -74.54265)
		(width 0.127)
		(layer "In2.Cu")
		(net "I2C_SCC_SCL2_LS")
	)
	(segment
		(start 130.232404 -82.894678)
		(end 130.232404 -78.90383)
		(width 0.127)
		(layer "In2.Cu")
		(net "I2C_SCC_SCL2_LS")
	)
	(segment
		(start 132.744464 -86.4235)
		(end 131.15163 -84.830666)
		(width 0.127)
		(layer "In2.Cu")
		(net "I2C_SCC_SCL2_LS")
	)
	(segment
		(start 139.34313 -86.4235)
		(end 132.744464 -86.4235)
		(width 0.127)
		(layer "In2.Cu")
		(net "I2C_SCC_SCL2_LS")
	)
	(segment
		(start 123.5329 -73.533)
		(end 123.000008 -73.000108)
		(width 0.127)
		(layer "In2.Cu")
		(net "I2C_SCC_SCL2_LS")
	)
	(segment
		(start 131.15163 -84.830666)
		(end 131.15163 -83.813904)
		(width 0.127)
		(layer "In2.Cu")
		(net "I2C_SCC_SCL2_LS")
	)
	(segment
		(start 139.7254 -86.80577)
		(end 139.34313 -86.4235)
		(width 0.127)
		(layer "In2.Cu")
		(net "I2C_SCC_SCL2_LS")
	)
	(segment
		(start 127.553212 -75.11034)
		(end 127.553212 -74.956924)
		(width 0.127)
		(layer "In2.Cu")
		(net "I2C_SCC_SCL2_LS")
	)
	(segment
		(start 128.120902 -75.563984)
		(end 128.006856 -75.563984)
		(width 0.127)
		(layer "In2.Cu")
		(net "I2C_SCC_SCL2_LS")
	)
	(segment
		(start 129.484374 -76.927456)
		(end 128.120902 -75.563984)
		(width 0.127)
		(layer "In2.Cu")
		(net "I2C_SCC_SCL2_LS")
	)
	(segment
		(start 125.5268 -73.9648)
		(end 125.095 -73.533)
		(width 0.127)
		(layer "In2.Cu")
		(net "I2C_SCC_SCL2_LS")
	)
	(segment
		(start 129.484374 -78.1558)
		(end 129.484374 -76.927456)
		(width 0.127)
		(layer "In2.Cu")
		(net "I2C_SCC_SCL2_LS")
	)
	(segment
		(start 125.095 -73.533)
		(end 123.5329 -73.533)
		(width 0.127)
		(layer "In2.Cu")
		(net "I2C_SCC_SCL2_LS")
	)
	(segment
		(start 130.232404 -78.90383)
		(end 129.484374 -78.1558)
		(width 0.127)
		(layer "In2.Cu")
		(net "I2C_SCC_SCL2_LS")
	)
	(segment
		(start 131.15163 -83.813904)
		(end 130.232404 -82.894678)
		(width 0.127)
		(layer "In2.Cu")
		(net "I2C_SCC_SCL2_LS")
	)
	(segment
		(start 139.7254 -88.4682)
		(end 139.7254 -86.80577)
		(width 0.127)
		(layer "In2.Cu")
		(net "I2C_SCC_SCL2_LS")
	)
	(segment
		(start 125.5268 -74.2188)
		(end 125.5268 -73.9648)
		(width 0.127)
		(layer "In2.Cu")
		(net "I2C_SCC_SCL2_LS")
	)
	(segment
		(start 128.006856 -75.563984)
		(end 127.553212 -75.11034)
		(width 0.127)
		(layer "In2.Cu")
		(net "I2C_SCC_SCL2_LS")
	)
	(segment
		(start 127.138938 -74.54265)
		(end 125.85065 -74.54265)
		(width 0.127)
		(layer "In2.Cu")
		(net "I2C_SCC_SCL2_LS")
	)
	(segment
		(start 136.976612 -97.4471)
		(end 138.840718 -95.582994)
		(width 0.127)
		(layer "In5.Cu")
		(net "I2C_SCC_SCL2_LS")
	)
	(segment
		(start 139.091162 -95.197676)
		(end 139.091162 -94.844616)
		(width 0.127)
		(layer "In5.Cu")
		(net "I2C_SCC_SCL2_LS")
	)
	(segment
		(start 12.09929 -94.59849)
		(end 15.1384 -97.6376)
		(width 0.127)
		(layer "In5.Cu")
		(net "I2C_SCC_SCL2_LS")
	)
	(segment
		(start 136.743186 -97.598992)
		(end 136.976612 -97.4471)
		(width 0.127)
		(layer "In5.Cu")
		(net "I2C_SCC_SCL2_LS")
	)
	(segment
		(start 124.727208 -100.088192)
		(end 125.9205 -98.8949)
		(width 0.127)
		(layer "In5.Cu")
		(net "I2C_SCC_SCL2_LS")
	)
	(segment
		(start 135.713216 -98.267774)
		(end 136.742678 -97.599246)
		(width 0.127)
		(layer "In5.Cu")
		(net "I2C_SCC_SCL2_LS")
	)
	(segment
		(start 36.36645 -123.740418)
		(end 65.064132 -123.740418)
		(width 0.127)
		(layer "In5.Cu")
		(net "I2C_SCC_SCL2_LS")
	)
	(segment
		(start 121.3739 -100.087938)
		(end 121.374154 -100.088192)
		(width 0.127)
		(layer "In5.Cu")
		(net "I2C_SCC_SCL2_LS")
	)
	(segment
		(start 136.742678 -97.599246)
		(end 136.743186 -97.598992)
		(width 0.127)
		(layer "In5.Cu")
		(net "I2C_SCC_SCL2_LS")
	)
	(segment
		(start 129.544826 -98.267774)
		(end 135.713216 -98.267774)
		(width 0.127)
		(layer "In5.Cu")
		(net "I2C_SCC_SCL2_LS")
	)
	(segment
		(start 128.9177 -98.8949)
		(end 129.544826 -98.267774)
		(width 0.127)
		(layer "In5.Cu")
		(net "I2C_SCC_SCL2_LS")
	)
	(segment
		(start 139.7254 -94.210378)
		(end 139.7254 -88.4682)
		(width 0.127)
		(layer "In5.Cu")
		(net "I2C_SCC_SCL2_LS")
	)
	(segment
		(start 9.6266 -84.93252)
		(end 9.906 -85.21192)
		(width 0.127)
		(layer "In5.Cu")
		(net "I2C_SCC_SCL2_LS")
	)
	(segment
		(start 80.38465 -108.4199)
		(end 95.389954 -108.4199)
		(width 0.127)
		(layer "In5.Cu")
		(net "I2C_SCC_SCL2_LS")
	)
	(segment
		(start 121.374154 -100.088192)
		(end 124.727208 -100.088192)
		(width 0.127)
		(layer "In5.Cu")
		(net "I2C_SCC_SCL2_LS")
	)
	(segment
		(start 138.844274 -95.57766)
		(end 139.091162 -95.197676)
		(width 0.127)
		(layer "In5.Cu")
		(net "I2C_SCC_SCL2_LS")
	)
	(segment
		(start 138.840972 -95.582486)
		(end 138.844274 -95.57766)
		(width 0.127)
		(layer "In5.Cu")
		(net "I2C_SCC_SCL2_LS")
	)
	(segment
		(start 12.09929 -90.694256)
		(end 12.09929 -94.59849)
		(width 0.127)
		(layer "In5.Cu")
		(net "I2C_SCC_SCL2_LS")
	)
	(segment
		(start 95.389954 -108.4199)
		(end 103.721916 -100.087938)
		(width 0.127)
		(layer "In5.Cu")
		(net "I2C_SCC_SCL2_LS")
	)
	(segment
		(start 125.9205 -98.8949)
		(end 128.9177 -98.8949)
		(width 0.127)
		(layer "In5.Cu")
		(net "I2C_SCC_SCL2_LS")
	)
	(segment
		(start 103.721916 -100.087938)
		(end 121.3739 -100.087938)
		(width 0.127)
		(layer "In5.Cu")
		(net "I2C_SCC_SCL2_LS")
	)
	(segment
		(start 9.906 -85.21192)
		(end 9.906 -88.500966)
		(width 0.127)
		(layer "In5.Cu")
		(net "I2C_SCC_SCL2_LS")
	)
	(segment
		(start 65.064132 -123.740418)
		(end 80.38465 -108.4199)
		(width 0.127)
		(layer "In5.Cu")
		(net "I2C_SCC_SCL2_LS")
	)
	(segment
		(start 139.091162 -94.844616)
		(end 139.7254 -94.210378)
		(width 0.127)
		(layer "In5.Cu")
		(net "I2C_SCC_SCL2_LS")
	)
	(segment
		(start 15.1384 -102.512368)
		(end 36.36645 -123.740418)
		(width 0.127)
		(layer "In5.Cu")
		(net "I2C_SCC_SCL2_LS")
	)
	(segment
		(start 138.840718 -95.582994)
		(end 138.840972 -95.582486)
		(width 0.127)
		(layer "In5.Cu")
		(net "I2C_SCC_SCL2_LS")
	)
	(segment
		(start 9.906 -88.500966)
		(end 12.09929 -90.694256)
		(width 0.127)
		(layer "In5.Cu")
		(net "I2C_SCC_SCL2_LS")
	)
	(segment
		(start 15.1384 -97.6376)
		(end 15.1384 -102.512368)
		(width 0.127)
		(layer "In5.Cu")
		(net "I2C_SCC_SCL2_LS")
	)
	(segment
		(start 203.610972 -49.316894)
		(end 201.61631 -47.322232)
		(width 0.127)
		(layer "F.Cu")
		(net "I2C_SCC_SCL2")
	)
	(segment
		(start 19.6723 -78.613)
		(end 20.4724 -78.613)
		(width 0.127)
		(layer "F.Cu")
		(net "I2C_SCC_SCL2")
	)
	(segment
		(start 203.638912 -77.71384)
		(end 203.638912 -77.361288)
		(width 0.127)
		(layer "F.Cu")
		(net "I2C_SCC_SCL2")
	)
	(segment
		(start 203.344272 -78.00848)
		(end 203.638912 -77.71384)
		(width 0.127)
		(layer "F.Cu")
		(net "I2C_SCC_SCL2")
	)
	(segment
		(start 201.879708 -33.339786)
		(end 201.879708 -20.894548)
		(width 0.127)
		(layer "F.Cu")
		(net "I2C_SCC_SCL2")
	)
	(segment
		(start 19.696684 -71.55053)
		(end 20.494752 -71.55053)
		(width 0.127)
		(layer "F.Cu")
		(net "I2C_SCC_SCL2")
	)
	(segment
		(start 183.599836 -7.400036)
		(end 184.771792 -8.571992)
		(width 0.127)
		(layer "F.Cu")
		(net "I2C_SCC_SCL2")
	)
	(segment
		(start 20.4724 -78.613)
		(end 20.4978 -78.5876)
		(width 0.127)
		(layer "F.Cu")
		(net "I2C_SCC_SCL2")
	)
	(segment
		(start 150.684992 -69.517006)
		(end 154.760676 -69.517006)
		(width 0.127)
		(layer "F.Cu")
		(net "I2C_SCC_SCL2")
	)
	(segment
		(start 201.61631 -47.322232)
		(end 201.61631 -35.940746)
		(width 0.127)
		(layer "F.Cu")
		(net "I2C_SCC_SCL2")
	)
	(segment
		(start 11.5951 -61.2267)
		(end 11.5951 -63.57112)
		(width 0.127)
		(layer "F.Cu")
		(net "I2C_SCC_SCL2")
	)
	(segment
		(start 8.53059 -93.04909)
		(end 8.53059 -90.679778)
		(width 0.127)
		(layer "F.Cu")
		(net "I2C_SCC_SCL2")
	)
	(segment
		(start 201.879708 -20.894548)
		(end 199.942704 -18.957544)
		(width 0.127)
		(layer "F.Cu")
		(net "I2C_SCC_SCL2")
	)
	(segment
		(start 202.2856 -35.271456)
		(end 202.2856 -33.745678)
		(width 0.127)
		(layer "F.Cu")
		(net "I2C_SCC_SCL2")
	)
	(segment
		(start 9.0932 -93.0656)
		(end 8.9789 -93.1799)
		(width 0.127)
		(layer "F.Cu")
		(net "I2C_SCC_SCL2")
	)
	(segment
		(start 184.771792 -8.571992)
		(end 184.771792 -18.400776)
		(width 0.127)
		(layer "F.Cu")
		(net "I2C_SCC_SCL2")
	)
	(segment
		(start 149.770592 -70.431406)
		(end 150.684992 -69.517006)
		(width 0.127)
		(layer "F.Cu")
		(net "I2C_SCC_SCL2")
	)
	(segment
		(start 203.610972 -53.369464)
		(end 203.610972 -49.316894)
		(width 0.127)
		(layer "F.Cu")
		(net "I2C_SCC_SCL2")
	)
	(segment
		(start 155.755594 -70.511924)
		(end 155.755594 -71.15937)
		(width 0.127)
		(layer "F.Cu")
		(net "I2C_SCC_SCL2")
	)
	(segment
		(start 8.6614 -93.1799)
		(end 8.53059 -93.04909)
		(width 0.127)
		(layer "F.Cu")
		(net "I2C_SCC_SCL2")
	)
	(segment
		(start 152.236424 -82.970624)
		(end 151.7523 -82.4865)
		(width 0.127)
		(layer "F.Cu")
		(net "I2C_SCC_SCL2")
	)
	(segment
		(start 149.770592 -80.504792)
		(end 149.770592 -70.431406)
		(width 0.127)
		(layer "F.Cu")
		(net "I2C_SCC_SCL2")
	)
	(segment
		(start 154.760676 -69.517006)
		(end 155.755594 -70.511924)
		(width 0.127)
		(layer "F.Cu")
		(net "I2C_SCC_SCL2")
	)
	(segment
		(start 9.0932 -92.3036)
		(end 9.0932 -93.0656)
		(width 0.127)
		(layer "F.Cu")
		(net "I2C_SCC_SCL2")
	)
	(segment
		(start 184.771792 -18.400776)
		(end 185.32856 -18.957544)
		(width 0.127)
		(layer "F.Cu")
		(net "I2C_SCC_SCL2")
	)
	(segment
		(start 10.652252 -60.283852)
		(end 11.5951 -61.2267)
		(width 0.127)
		(layer "F.Cu")
		(net "I2C_SCC_SCL2")
	)
	(segment
		(start 8.9789 -93.1799)
		(end 8.6614 -93.1799)
		(width 0.127)
		(layer "F.Cu")
		(net "I2C_SCC_SCL2")
	)
	(segment
		(start 185.32856 -18.957544)
		(end 190.696342 -18.957544)
		(width 0.127)
		(layer "F.Cu")
		(net "I2C_SCC_SCL2")
	)
	(segment
		(start 202.2856 -33.745678)
		(end 201.879708 -33.339786)
		(width 0.127)
		(layer "F.Cu")
		(net "I2C_SCC_SCL2")
	)
	(segment
		(start 199.942704 -18.957544)
		(end 190.696342 -18.957544)
		(width 0.127)
		(layer "F.Cu")
		(net "I2C_SCC_SCL2")
	)
	(segment
		(start 10.652252 -59.805316)
		(end 10.652252 -60.283852)
		(width 0.127)
		(layer "F.Cu")
		(net "I2C_SCC_SCL2")
	)
	(segment
		(start 151.7523 -82.4865)
		(end 149.770592 -80.504792)
		(width 0.127)
		(layer "F.Cu")
		(net "I2C_SCC_SCL2")
	)
	(segment
		(start 201.61631 -35.940746)
		(end 202.2856 -35.271456)
		(width 0.127)
		(layer "F.Cu")
		(net "I2C_SCC_SCL2")
	)
	(segment
		(start 152.536398 -82.970624)
		(end 152.236424 -82.970624)
		(width 0.127)
		(layer "F.Cu")
		(net "I2C_SCC_SCL2")
	)
	(segment
		(start 202.74788 -78.00848)
		(end 203.344272 -78.00848)
		(width 0.127)
		(layer "F.Cu")
		(net "I2C_SCC_SCL2")
	)
	(via
		(at 95.152464 -43.784012)
		(size 0.508)
		(drill 0.254)
		(layers "F.Cu" "B.Cu")
		(net "I2C_SCC_SCL2")
	)
	(via
		(at 151.7523 -82.4865)
		(size 0.508)
		(drill 0.254)
		(layers "F.Cu" "B.Cu")
		(net "I2C_SCC_SCL2")
	)
	(via
		(at 155.347924 -81.903824)
		(size 0.6096)
		(drill 0.3048)
		(layers "F.Cu" "B.Cu")
		(net "I2C_SCC_SCL2")
	)
	(via
		(at 203.610972 -53.369464)
		(size 0.508)
		(drill 0.254)
		(layers "F.Cu" "B.Cu")
		(net "I2C_SCC_SCL2")
	)
	(via
		(at 11.5951 -63.57112)
		(size 0.508)
		(drill 0.254)
		(layers "F.Cu" "B.Cu")
		(net "I2C_SCC_SCL2")
	)
	(via
		(at 20.494752 -71.55053)
		(size 0.508)
		(drill 0.254)
		(layers "F.Cu" "B.Cu")
		(net "I2C_SCC_SCL2")
	)
	(via
		(at 20.4978 -78.5876)
		(size 0.508)
		(drill 0.254)
		(layers "F.Cu" "B.Cu")
		(net "I2C_SCC_SCL2")
	)
	(via
		(at 9.0932 -92.3036)
		(size 0.508)
		(drill 0.254)
		(layers "F.Cu" "B.Cu")
		(net "I2C_SCC_SCL2")
	)
	(via
		(at 203.638912 -77.361288)
		(size 0.508)
		(drill 0.254)
		(layers "F.Cu" "B.Cu")
		(net "I2C_SCC_SCL2")
	)
	(via
		(at 190.696342 -18.957544)
		(size 0.508)
		(drill 0.254)
		(layers "F.Cu" "B.Cu")
		(net "I2C_SCC_SCL2")
	)
	(segment
		(start 160.994852 -81.903824)
		(end 155.347924 -81.903824)
		(width 0.127)
		(layer "B.Cu")
		(net "I2C_SCC_SCL2")
	)
	(segment
		(start 152.334976 -81.903824)
		(end 151.7523 -82.4865)
		(width 0.127)
		(layer "B.Cu")
		(net "I2C_SCC_SCL2")
	)
	(segment
		(start 184.960514 -75.63104)
		(end 167.267636 -75.63104)
		(width 0.127)
		(layer "B.Cu")
		(net "I2C_SCC_SCL2")
	)
	(segment
		(start 203.638912 -77.361288)
		(end 203.179426 -77.820774)
		(width 0.127)
		(layer "B.Cu")
		(net "I2C_SCC_SCL2")
	)
	(segment
		(start 155.347924 -81.903824)
		(end 152.334976 -81.903824)
		(width 0.127)
		(layer "B.Cu")
		(net "I2C_SCC_SCL2")
	)
	(segment
		(start 187.150248 -77.820774)
		(end 184.960514 -75.63104)
		(width 0.127)
		(layer "B.Cu")
		(net "I2C_SCC_SCL2")
	)
	(segment
		(start 203.179426 -77.820774)
		(end 187.150248 -77.820774)
		(width 0.127)
		(layer "B.Cu")
		(net "I2C_SCC_SCL2")
	)
	(segment
		(start 167.267636 -75.63104)
		(end 160.994852 -81.903824)
		(width 0.127)
		(layer "B.Cu")
		(net "I2C_SCC_SCL2")
	)
	(segment
		(start 166.892732 -12.0904)
		(end 164.813234 -12.0904)
		(width 0.127)
		(layer "In2.Cu")
		(net "I2C_SCC_SCL2")
	)
	(segment
		(start 184.465722 -17.49933)
		(end 177.64633 -17.49933)
		(width 0.127)
		(layer "In2.Cu")
		(net "I2C_SCC_SCL2")
	)
	(segment
		(start 177.64633 -17.49933)
		(end 171.327826 -11.180826)
		(width 0.127)
		(layer "In2.Cu")
		(net "I2C_SCC_SCL2")
	)
	(segment
		(start 101.767132 -43.833034)
		(end 95.201486 -43.833034)
		(width 0.127)
		(layer "In2.Cu")
		(net "I2C_SCC_SCL2")
	)
	(segment
		(start 162.552634 -14.351)
		(end 156.56941 -14.351)
		(width 0.127)
		(layer "In2.Cu")
		(net "I2C_SCC_SCL2")
	)
	(segment
		(start 138.125708 -21.31568)
		(end 122.395234 -37.046154)
		(width 0.127)
		(layer "In2.Cu")
		(net "I2C_SCC_SCL2")
	)
	(segment
		(start 108.554012 -37.046154)
		(end 101.767132 -43.833034)
		(width 0.127)
		(layer "In2.Cu")
		(net "I2C_SCC_SCL2")
	)
	(segment
		(start 164.813234 -12.0904)
		(end 162.552634 -14.351)
		(width 0.127)
		(layer "In2.Cu")
		(net "I2C_SCC_SCL2")
	)
	(segment
		(start 185.923936 -18.957544)
		(end 184.465722 -17.49933)
		(width 0.127)
		(layer "In2.Cu")
		(net "I2C_SCC_SCL2")
	)
	(segment
		(start 149.60473 -21.31568)
		(end 138.125708 -21.31568)
		(width 0.127)
		(layer "In2.Cu")
		(net "I2C_SCC_SCL2")
	)
	(segment
		(start 122.395234 -37.046154)
		(end 108.554012 -37.046154)
		(width 0.127)
		(layer "In2.Cu")
		(net "I2C_SCC_SCL2")
	)
	(segment
		(start 156.56941 -14.351)
		(end 149.60473 -21.31568)
		(width 0.127)
		(layer "In2.Cu")
		(net "I2C_SCC_SCL2")
	)
	(segment
		(start 190.696342 -18.957544)
		(end 185.923936 -18.957544)
		(width 0.127)
		(layer "In2.Cu")
		(net "I2C_SCC_SCL2")
	)
	(segment
		(start 167.802306 -11.180826)
		(end 166.892732 -12.0904)
		(width 0.127)
		(layer "In2.Cu")
		(net "I2C_SCC_SCL2")
	)
	(segment
		(start 171.327826 -11.180826)
		(end 167.802306 -11.180826)
		(width 0.127)
		(layer "In2.Cu")
		(net "I2C_SCC_SCL2")
	)
	(segment
		(start 95.201486 -43.833034)
		(end 95.152464 -43.784012)
		(width 0.127)
		(layer "In2.Cu")
		(net "I2C_SCC_SCL2")
	)
	(segment
		(start 20.610576 -79.127858)
		(end 20.338034 -79.4004)
		(width 0.127)
		(layer "In5.Cu")
		(net "I2C_SCC_SCL2")
	)
	(segment
		(start 203.638912 -77.361288)
		(end 203.638912 -77.071982)
		(width 0.127)
		(layer "In5.Cu")
		(net "I2C_SCC_SCL2")
	)
	(segment
		(start 20.4978 -78.5876)
		(end 20.610576 -78.700376)
		(width 0.127)
		(layer "In5.Cu")
		(net "I2C_SCC_SCL2")
	)
	(segment
		(start 25.662636 -40.083232)
		(end 31.369 -34.376868)
		(width 0.127)
		(layer "In5.Cu")
		(net "I2C_SCC_SCL2")
	)
	(segment
		(start 8.497062 -90.673428)
		(end 9.398 -91.574366)
		(width 0.127)
		(layer "In5.Cu")
		(net "I2C_SCC_SCL2")
	)
	(segment
		(start 20.494752 -71.55053)
		(end 20.494752 -71.07301)
		(width 0.127)
		(layer "In5.Cu")
		(net "I2C_SCC_SCL2")
	)
	(segment
		(start 31.369 -26.307034)
		(end 34.015426 -23.660608)
		(width 0.127)
		(layer "In5.Cu")
		(net "I2C_SCC_SCL2")
	)
	(segment
		(start 19.9136 -72.131682)
		(end 19.9136 -78.0034)
		(width 0.127)
		(layer "In5.Cu")
		(net "I2C_SCC_SCL2")
	)
	(segment
		(start 9.398 -91.574366)
		(end 9.398 -91.9988)
		(width 0.127)
		(layer "In5.Cu")
		(net "I2C_SCC_SCL2")
	)
	(segment
		(start 31.369 -34.376868)
		(end 31.369 -26.307034)
		(width 0.127)
		(layer "In5.Cu")
		(net "I2C_SCC_SCL2")
	)
	(segment
		(start 9.398 -91.9988)
		(end 9.0932 -92.3036)
		(width 0.127)
		(layer "In5.Cu")
		(net "I2C_SCC_SCL2")
	)
	(segment
		(start 77.853286 -11.916918)
		(end 78.27391 -11.916918)
		(width 0.127)
		(layer "In5.Cu")
		(net "I2C_SCC_SCL2")
	)
	(segment
		(start 11.5951 -65.086738)
		(end 11.5951 -63.57112)
		(width 0.127)
		(layer "In5.Cu")
		(net "I2C_SCC_SCL2")
	)
	(segment
		(start 14.732762 -68.2244)
		(end 11.5951 -65.086738)
		(width 0.127)
		(layer "In5.Cu")
		(net "I2C_SCC_SCL2")
	)
	(segment
		(start 8.497062 -84.593938)
		(end 8.497062 -90.673428)
		(width 0.127)
		(layer "In5.Cu")
		(net "I2C_SCC_SCL2")
	)
	(segment
		(start 203.089256 -76.522326)
		(end 203.089256 -53.89118)
		(width 0.127)
		(layer "In5.Cu")
		(net "I2C_SCC_SCL2")
	)
	(segment
		(start 77.853032 -11.917172)
		(end 77.853286 -11.916918)
		(width 0.127)
		(layer "In5.Cu")
		(net "I2C_SCC_SCL2")
	)
	(segment
		(start 34.015426 -23.660608)
		(end 45.677582 -23.660608)
		(width 0.127)
		(layer "In5.Cu")
		(net "I2C_SCC_SCL2")
	)
	(segment
		(start 20.412964 -63.03772)
		(end 25.662636 -57.788048)
		(width 0.127)
		(layer "In5.Cu")
		(net "I2C_SCC_SCL2")
	)
	(segment
		(start 20.494752 -71.07301)
		(end 17.646142 -68.2244)
		(width 0.127)
		(layer "In5.Cu")
		(net "I2C_SCC_SCL2")
	)
	(segment
		(start 11.5951 -63.57112)
		(end 12.1285 -63.03772)
		(width 0.127)
		(layer "In5.Cu")
		(net "I2C_SCC_SCL2")
	)
	(segment
		(start 12.1285 -63.03772)
		(end 20.412964 -63.03772)
		(width 0.127)
		(layer "In5.Cu")
		(net "I2C_SCC_SCL2")
	)
	(segment
		(start 57.421018 -11.917172)
		(end 77.853032 -11.917172)
		(width 0.127)
		(layer "In5.Cu")
		(net "I2C_SCC_SCL2")
	)
	(segment
		(start 203.638912 -77.071982)
		(end 203.089256 -76.522326)
		(width 0.127)
		(layer "In5.Cu")
		(net "I2C_SCC_SCL2")
	)
	(segment
		(start 90.909394 -33.279588)
		(end 91.886532 -34.256726)
		(width 0.127)
		(layer "In5.Cu")
		(net "I2C_SCC_SCL2")
	)
	(segment
		(start 94.314264 -42.945812)
		(end 95.152464 -43.784012)
		(width 0.127)
		(layer "In5.Cu")
		(net "I2C_SCC_SCL2")
	)
	(segment
		(start 13.6906 -79.4004)
		(end 8.497062 -84.593938)
		(width 0.127)
		(layer "In5.Cu")
		(net "I2C_SCC_SCL2")
	)
	(segment
		(start 25.662636 -57.788048)
		(end 25.662636 -40.083232)
		(width 0.127)
		(layer "In5.Cu")
		(net "I2C_SCC_SCL2")
	)
	(segment
		(start 91.886532 -40.899334)
		(end 93.93301 -42.945812)
		(width 0.127)
		(layer "In5.Cu")
		(net "I2C_SCC_SCL2")
	)
	(segment
		(start 20.338034 -79.4004)
		(end 13.6906 -79.4004)
		(width 0.127)
		(layer "In5.Cu")
		(net "I2C_SCC_SCL2")
	)
	(segment
		(start 19.9136 -78.0034)
		(end 20.4978 -78.5876)
		(width 0.127)
		(layer "In5.Cu")
		(net "I2C_SCC_SCL2")
	)
	(segment
		(start 45.677582 -23.660608)
		(end 57.421018 -11.917172)
		(width 0.127)
		(layer "In5.Cu")
		(net "I2C_SCC_SCL2")
	)
	(segment
		(start 17.646142 -68.2244)
		(end 14.732762 -68.2244)
		(width 0.127)
		(layer "In5.Cu")
		(net "I2C_SCC_SCL2")
	)
	(segment
		(start 20.610576 -78.700376)
		(end 20.610576 -79.127858)
		(width 0.127)
		(layer "In5.Cu")
		(net "I2C_SCC_SCL2")
	)
	(segment
		(start 203.089256 -53.89118)
		(end 203.610972 -53.369464)
		(width 0.127)
		(layer "In5.Cu")
		(net "I2C_SCC_SCL2")
	)
	(segment
		(start 93.93301 -42.945812)
		(end 94.314264 -42.945812)
		(width 0.127)
		(layer "In5.Cu")
		(net "I2C_SCC_SCL2")
	)
	(segment
		(start 90.909394 -24.552402)
		(end 90.909394 -33.279588)
		(width 0.127)
		(layer "In5.Cu")
		(net "I2C_SCC_SCL2")
	)
	(segment
		(start 78.27391 -11.916918)
		(end 90.909394 -24.552402)
		(width 0.127)
		(layer "In5.Cu")
		(net "I2C_SCC_SCL2")
	)
	(segment
		(start 20.494752 -71.55053)
		(end 19.9136 -72.131682)
		(width 0.127)
		(layer "In5.Cu")
		(net "I2C_SCC_SCL2")
	)
	(segment
		(start 91.886532 -34.256726)
		(end 91.886532 -40.899334)
		(width 0.127)
		(layer "In5.Cu")
		(net "I2C_SCC_SCL2")
	)
	(segment
		(start 57.023 -82.677)
		(end 57.023 -80.5434)
		(width 0.127)
		(layer "F.Cu")
		(net "I2C_DRIVE_PWR_SDA4_LS")
	)
	(segment
		(start 58.0644 -83.7184)
		(end 58.5216 -83.7184)
		(width 0.127)
		(layer "F.Cu")
		(net "I2C_DRIVE_PWR_SDA4_LS")
	)
	(segment
		(start 57.706768 -79.859632)
		(end 57.706768 -79.12227)
		(width 0.127)
		(layer "F.Cu")
		(net "I2C_DRIVE_PWR_SDA4_LS")
	)
	(segment
		(start 57.531 -83.185)
		(end 58.0644 -83.7184)
		(width 0.127)
		(layer "F.Cu")
		(net "I2C_DRIVE_PWR_SDA4_LS")
	)
	(segment
		(start 57.531 -83.185)
		(end 57.023 -82.677)
		(width 0.127)
		(layer "F.Cu")
		(net "I2C_DRIVE_PWR_SDA4_LS")
	)
	(segment
		(start 57.023 -80.5434)
		(end 57.706768 -79.859632)
		(width 0.127)
		(layer "F.Cu")
		(net "I2C_DRIVE_PWR_SDA4_LS")
	)
	(segment
		(start 122.500136 -74.500232)
		(end 123.000008 -74.00036)
		(width 0.127)
		(layer "F.Cu")
		(net "I2C_DRIVE_PWR_SDA4_LS")
	)
	(via
		(at 123.000008 -74.00036)
		(size 0.4572)
		(drill 0.2032)
		(layers "F.Cu" "B.Cu")
		(net "I2C_DRIVE_PWR_SDA4_LS")
	)
	(via
		(at 57.531 -83.185)
		(size 0.6604)
		(drill 0.3302)
		(layers "F.Cu" "B.Cu")
		(net "I2C_DRIVE_PWR_SDA4_LS")
	)
	(via
		(at 58.5216 -83.7184)
		(size 0.508)
		(drill 0.254)
		(layers "F.Cu" "B.Cu")
		(net "I2C_DRIVE_PWR_SDA4_LS")
	)
	(via
		(at 137.2108 -88.4682)
		(size 0.508)
		(drill 0.254)
		(layers "F.Cu" "B.Cu")
		(net "I2C_DRIVE_PWR_SDA4_LS")
	)
	(segment
		(start 137.2108 -89.2429)
		(end 137.2108 -88.4682)
		(width 0.127)
		(layer "B.Cu")
		(net "I2C_DRIVE_PWR_SDA4_LS")
	)
	(segment
		(start 127.54483 -78.101952)
		(end 127.54483 -76.948538)
		(width 0.127)
		(layer "In2.Cu")
		(net "I2C_DRIVE_PWR_SDA4_LS")
	)
	(segment
		(start 123.924568 -75.565)
		(end 123.54941 -75.189842)
		(width 0.127)
		(layer "In2.Cu")
		(net "I2C_DRIVE_PWR_SDA4_LS")
	)
	(segment
		(start 127.030988 -76.434696)
		(end 125.710696 -76.434696)
		(width 0.127)
		(layer "In2.Cu")
		(net "I2C_DRIVE_PWR_SDA4_LS")
	)
	(segment
		(start 127.950722 -78.393798)
		(end 127.836676 -78.393798)
		(width 0.127)
		(layer "In2.Cu")
		(net "I2C_DRIVE_PWR_SDA4_LS")
	)
	(segment
		(start 128.606296 -79.163418)
		(end 128.606296 -79.049372)
		(width 0.127)
		(layer "In2.Cu")
		(net "I2C_DRIVE_PWR_SDA4_LS")
	)
	(segment
		(start 128.606296 -79.049372)
		(end 127.950722 -78.393798)
		(width 0.127)
		(layer "In2.Cu")
		(net "I2C_DRIVE_PWR_SDA4_LS")
	)
	(segment
		(start 123.54941 -74.549762)
		(end 123.000008 -74.00036)
		(width 0.127)
		(layer "In2.Cu")
		(net "I2C_DRIVE_PWR_SDA4_LS")
	)
	(segment
		(start 130.38963 -85.505798)
		(end 130.38963 -84.489036)
		(width 0.127)
		(layer "In2.Cu")
		(net "I2C_DRIVE_PWR_SDA4_LS")
	)
	(segment
		(start 123.54941 -75.189842)
		(end 123.54941 -74.549762)
		(width 0.127)
		(layer "In2.Cu")
		(net "I2C_DRIVE_PWR_SDA4_LS")
	)
	(segment
		(start 136.698228 -87.955628)
		(end 132.83946 -87.955628)
		(width 0.127)
		(layer "In2.Cu")
		(net "I2C_DRIVE_PWR_SDA4_LS")
	)
	(segment
		(start 137.2108 -88.4682)
		(end 136.698228 -87.955628)
		(width 0.127)
		(layer "In2.Cu")
		(net "I2C_DRIVE_PWR_SDA4_LS")
	)
	(segment
		(start 128.836674 -79.393796)
		(end 128.606296 -79.163418)
		(width 0.127)
		(layer "In2.Cu")
		(net "I2C_DRIVE_PWR_SDA4_LS")
	)
	(segment
		(start 127.836676 -78.393798)
		(end 127.54483 -78.101952)
		(width 0.127)
		(layer "In2.Cu")
		(net "I2C_DRIVE_PWR_SDA4_LS")
	)
	(segment
		(start 125.2982 -76.0222)
		(end 124.9172 -76.0222)
		(width 0.127)
		(layer "In2.Cu")
		(net "I2C_DRIVE_PWR_SDA4_LS")
	)
	(segment
		(start 124.9172 -76.0222)
		(end 124.46 -75.565)
		(width 0.127)
		(layer "In2.Cu")
		(net "I2C_DRIVE_PWR_SDA4_LS")
	)
	(segment
		(start 129.45872 -83.558126)
		(end 129.45872 -79.901796)
		(width 0.127)
		(layer "In2.Cu")
		(net "I2C_DRIVE_PWR_SDA4_LS")
	)
	(segment
		(start 128.95072 -79.393796)
		(end 128.836674 -79.393796)
		(width 0.127)
		(layer "In2.Cu")
		(net "I2C_DRIVE_PWR_SDA4_LS")
	)
	(segment
		(start 130.38963 -84.489036)
		(end 129.45872 -83.558126)
		(width 0.127)
		(layer "In2.Cu")
		(net "I2C_DRIVE_PWR_SDA4_LS")
	)
	(segment
		(start 129.45872 -79.901796)
		(end 128.95072 -79.393796)
		(width 0.127)
		(layer "In2.Cu")
		(net "I2C_DRIVE_PWR_SDA4_LS")
	)
	(segment
		(start 124.46 -75.565)
		(end 123.924568 -75.565)
		(width 0.127)
		(layer "In2.Cu")
		(net "I2C_DRIVE_PWR_SDA4_LS")
	)
	(segment
		(start 127.54483 -76.948538)
		(end 127.030988 -76.434696)
		(width 0.127)
		(layer "In2.Cu")
		(net "I2C_DRIVE_PWR_SDA4_LS")
	)
	(segment
		(start 132.83946 -87.955628)
		(end 130.38963 -85.505798)
		(width 0.127)
		(layer "In2.Cu")
		(net "I2C_DRIVE_PWR_SDA4_LS")
	)
	(segment
		(start 125.710696 -76.434696)
		(end 125.2982 -76.0222)
		(width 0.127)
		(layer "In2.Cu")
		(net "I2C_DRIVE_PWR_SDA4_LS")
	)
	(segment
		(start 134.791196 -88.9762)
		(end 136.7028 -88.9762)
		(width 0.127)
		(layer "In5.Cu")
		(net "I2C_DRIVE_PWR_SDA4_LS")
	)
	(segment
		(start 122.649488 -94.226888)
		(end 123.654312 -94.226888)
		(width 0.127)
		(layer "In5.Cu")
		(net "I2C_DRIVE_PWR_SDA4_LS")
	)
	(segment
		(start 66.11747 -88.70442)
		(end 77.336142 -99.923092)
		(width 0.127)
		(layer "In5.Cu")
		(net "I2C_DRIVE_PWR_SDA4_LS")
	)
	(segment
		(start 64.523366 -88.70442)
		(end 66.11747 -88.70442)
		(width 0.127)
		(layer "In5.Cu")
		(net "I2C_DRIVE_PWR_SDA4_LS")
	)
	(segment
		(start 124.517404 -93.7768)
		(end 125.0823 -93.211904)
		(width 0.127)
		(layer "In5.Cu")
		(net "I2C_DRIVE_PWR_SDA4_LS")
	)
	(segment
		(start 128.012952 -88.713818)
		(end 128.012952 -88.431878)
		(width 0.127)
		(layer "In5.Cu")
		(net "I2C_DRIVE_PWR_SDA4_LS")
	)
	(segment
		(start 77.336142 -99.923092)
		(end 98.078798 -99.923092)
		(width 0.127)
		(layer "In5.Cu")
		(net "I2C_DRIVE_PWR_SDA4_LS")
	)
	(segment
		(start 125.0823 -93.211904)
		(end 125.0823 -92.094304)
		(width 0.127)
		(layer "In5.Cu")
		(net "I2C_DRIVE_PWR_SDA4_LS")
	)
	(segment
		(start 101.977952 -96.023938)
		(end 120.852438 -96.023938)
		(width 0.127)
		(layer "In5.Cu")
		(net "I2C_DRIVE_PWR_SDA4_LS")
	)
	(segment
		(start 124.1044 -93.7768)
		(end 124.517404 -93.7768)
		(width 0.127)
		(layer "In5.Cu")
		(net "I2C_DRIVE_PWR_SDA4_LS")
	)
	(segment
		(start 136.7028 -88.9762)
		(end 137.2108 -88.4682)
		(width 0.127)
		(layer "In5.Cu")
		(net "I2C_DRIVE_PWR_SDA4_LS")
	)
	(segment
		(start 128.43383 -88.011)
		(end 133.825996 -88.011)
		(width 0.127)
		(layer "In5.Cu")
		(net "I2C_DRIVE_PWR_SDA4_LS")
	)
	(segment
		(start 58.5216 -83.7184)
		(end 59.537346 -83.7184)
		(width 0.127)
		(layer "In5.Cu")
		(net "I2C_DRIVE_PWR_SDA4_LS")
	)
	(segment
		(start 128.012952 -88.431878)
		(end 128.43383 -88.011)
		(width 0.127)
		(layer "In5.Cu")
		(net "I2C_DRIVE_PWR_SDA4_LS")
	)
	(segment
		(start 120.852438 -96.023938)
		(end 122.649488 -94.226888)
		(width 0.127)
		(layer "In5.Cu")
		(net "I2C_DRIVE_PWR_SDA4_LS")
	)
	(segment
		(start 133.825996 -88.011)
		(end 134.791196 -88.9762)
		(width 0.127)
		(layer "In5.Cu")
		(net "I2C_DRIVE_PWR_SDA4_LS")
	)
	(segment
		(start 98.078798 -99.923092)
		(end 101.977952 -96.023938)
		(width 0.127)
		(layer "In5.Cu")
		(net "I2C_DRIVE_PWR_SDA4_LS")
	)
	(segment
		(start 59.537346 -83.7184)
		(end 64.523366 -88.70442)
		(width 0.127)
		(layer "In5.Cu")
		(net "I2C_DRIVE_PWR_SDA4_LS")
	)
	(segment
		(start 125.7427 -91.433904)
		(end 125.7427 -90.98407)
		(width 0.127)
		(layer "In5.Cu")
		(net "I2C_DRIVE_PWR_SDA4_LS")
	)
	(segment
		(start 125.7427 -90.98407)
		(end 128.012952 -88.713818)
		(width 0.127)
		(layer "In5.Cu")
		(net "I2C_DRIVE_PWR_SDA4_LS")
	)
	(segment
		(start 123.654312 -94.226888)
		(end 124.1044 -93.7768)
		(width 0.127)
		(layer "In5.Cu")
		(net "I2C_DRIVE_PWR_SDA4_LS")
	)
	(segment
		(start 125.0823 -92.094304)
		(end 125.7427 -91.433904)
		(width 0.127)
		(layer "In5.Cu")
		(net "I2C_DRIVE_PWR_SDA4_LS")
	)
	(segment
		(start 56.4388 -72.709024)
		(end 56.4388 -70.555612)
		(width 0.127)
		(layer "F.Cu")
		(net "I2C_DRIVE_PWR_SDA4")
	)
	(segment
		(start 57.706768 -75.156568)
		(end 57.3786 -74.8284)
		(width 0.127)
		(layer "F.Cu")
		(net "I2C_DRIVE_PWR_SDA4")
	)
	(segment
		(start 56.135524 -73.0123)
		(end 56.4388 -72.709024)
		(width 0.127)
		(layer "F.Cu")
		(net "I2C_DRIVE_PWR_SDA4")
	)
	(segment
		(start 57.706768 -75.87107)
		(end 57.706768 -75.156568)
		(width 0.127)
		(layer "F.Cu")
		(net "I2C_DRIVE_PWR_SDA4")
	)
	(segment
		(start 55.7276 -73.914)
		(end 55.7276 -73.0123)
		(width 0.127)
		(layer "F.Cu")
		(net "I2C_DRIVE_PWR_SDA4")
	)
	(segment
		(start 56.642 -74.8284)
		(end 56.1086 -74.295)
		(width 0.127)
		(layer "F.Cu")
		(net "I2C_DRIVE_PWR_SDA4")
	)
	(segment
		(start 57.3786 -74.8284)
		(end 56.642 -74.8284)
		(width 0.127)
		(layer "F.Cu")
		(net "I2C_DRIVE_PWR_SDA4")
	)
	(segment
		(start 56.4388 -70.555612)
		(end 56.46928 -70.525132)
		(width 0.127)
		(layer "F.Cu")
		(net "I2C_DRIVE_PWR_SDA4")
	)
	(segment
		(start 56.1086 -74.295)
		(end 55.7276 -73.914)
		(width 0.127)
		(layer "F.Cu")
		(net "I2C_DRIVE_PWR_SDA4")
	)
	(segment
		(start 55.7276 -73.0123)
		(end 56.135524 -73.0123)
		(width 0.127)
		(layer "F.Cu")
		(net "I2C_DRIVE_PWR_SDA4")
	)
	(via
		(at 56.46928 -70.525132)
		(size 0.508)
		(drill 0.254)
		(layers "F.Cu" "B.Cu")
		(net "I2C_DRIVE_PWR_SDA4")
	)
	(via
		(at 56.1086 -74.295)
		(size 0.6604)
		(drill 0.3302)
		(layers "F.Cu" "B.Cu")
		(net "I2C_DRIVE_PWR_SDA4")
	)
	(segment
		(start 85.67801 -28.49118)
		(end 80.498696 -33.670494)
		(width 0.127)
		(layer "In2.Cu")
		(net "I2C_DRIVE_PWR_SDA4")
	)
	(segment
		(start 68.807838 -67.271392)
		(end 67.094608 -67.271392)
		(width 0.127)
		(layer "In2.Cu")
		(net "I2C_DRIVE_PWR_SDA4")
	)
	(segment
		(start 74.011536 -62.067694)
		(end 68.807838 -67.271392)
		(width 0.127)
		(layer "In2.Cu")
		(net "I2C_DRIVE_PWR_SDA4")
	)
	(segment
		(start 78.817216 -47.01159)
		(end 78.272132 -47.01159)
		(width 0.127)
		(layer "In2.Cu")
		(net "I2C_DRIVE_PWR_SDA4")
	)
	(segment
		(start 97.017332 -28.49118)
		(end 96.650556 -28.49118)
		(width 0.127)
		(layer "In2.Cu")
		(net "I2C_DRIVE_PWR_SDA4")
	)
	(segment
		(start 111.825024 -9.424924)
		(end 111.825024 -13.683488)
		(width 0.127)
		(layer "In2.Cu")
		(net "I2C_DRIVE_PWR_SDA4")
	)
	(segment
		(start 96.650556 -28.49118)
		(end 96.650302 -28.491434)
		(width 0.127)
		(layer "In2.Cu")
		(net "I2C_DRIVE_PWR_SDA4")
	)
	(segment
		(start 74.011536 -58.077862)
		(end 74.011536 -62.067694)
		(width 0.127)
		(layer "In2.Cu")
		(net "I2C_DRIVE_PWR_SDA4")
	)
	(segment
		(start 67.094608 -67.271392)
		(end 64.508888 -69.857112)
		(width 0.127)
		(layer "In2.Cu")
		(net "I2C_DRIVE_PWR_SDA4")
	)
	(segment
		(start 94.755716 -28.49118)
		(end 85.67801 -28.49118)
		(width 0.127)
		(layer "In2.Cu")
		(net "I2C_DRIVE_PWR_SDA4")
	)
	(segment
		(start 76.927964 -55.161434)
		(end 74.011536 -58.077862)
		(width 0.127)
		(layer "In2.Cu")
		(net "I2C_DRIVE_PWR_SDA4")
	)
	(segment
		(start 57.1373 -69.857112)
		(end 56.46928 -70.525132)
		(width 0.127)
		(layer "In2.Cu")
		(net "I2C_DRIVE_PWR_SDA4")
	)
	(segment
		(start 80.498696 -33.670494)
		(end 80.498696 -45.33011)
		(width 0.127)
		(layer "In2.Cu")
		(net "I2C_DRIVE_PWR_SDA4")
	)
	(segment
		(start 111.200184 -8.800084)
		(end 111.825024 -9.424924)
		(width 0.127)
		(layer "In2.Cu")
		(net "I2C_DRIVE_PWR_SDA4")
	)
	(segment
		(start 94.75597 -28.491434)
		(end 94.755716 -28.49118)
		(width 0.127)
		(layer "In2.Cu")
		(net "I2C_DRIVE_PWR_SDA4")
	)
	(segment
		(start 111.825024 -13.683488)
		(end 97.017332 -28.49118)
		(width 0.127)
		(layer "In2.Cu")
		(net "I2C_DRIVE_PWR_SDA4")
	)
	(segment
		(start 78.272132 -47.01159)
		(end 76.927964 -48.355758)
		(width 0.127)
		(layer "In2.Cu")
		(net "I2C_DRIVE_PWR_SDA4")
	)
	(segment
		(start 80.498696 -45.33011)
		(end 78.817216 -47.01159)
		(width 0.127)
		(layer "In2.Cu")
		(net "I2C_DRIVE_PWR_SDA4")
	)
	(segment
		(start 96.650302 -28.491434)
		(end 94.75597 -28.491434)
		(width 0.127)
		(layer "In2.Cu")
		(net "I2C_DRIVE_PWR_SDA4")
	)
	(segment
		(start 64.508888 -69.857112)
		(end 57.1373 -69.857112)
		(width 0.127)
		(layer "In2.Cu")
		(net "I2C_DRIVE_PWR_SDA4")
	)
	(segment
		(start 76.927964 -48.355758)
		(end 76.927964 -55.161434)
		(width 0.127)
		(layer "In2.Cu")
		(net "I2C_DRIVE_PWR_SDA4")
	)
	(segment
		(start 57.785 -81.3308)
		(end 57.785 -81.0006)
		(width 0.127)
		(layer "F.Cu")
		(net "I2C_DRIVE_PWR_SCL4_LS")
	)
	(segment
		(start 58.5216 -82.8548)
		(end 58.5216 -82.0674)
		(width 0.127)
		(layer "F.Cu")
		(net "I2C_DRIVE_PWR_SCL4_LS")
	)
	(segment
		(start 57.785 -80.60944)
		(end 57.785 -81.0006)
		(width 0.127)
		(layer "F.Cu")
		(net "I2C_DRIVE_PWR_SCL4_LS")
	)
	(segment
		(start 58.357008 -79.12227)
		(end 58.357008 -80.037432)
		(width 0.127)
		(layer "F.Cu")
		(net "I2C_DRIVE_PWR_SCL4_LS")
	)
	(segment
		(start 127.500126 -78.500224)
		(end 127.999998 -79.000096)
		(width 0.127)
		(layer "F.Cu")
		(net "I2C_DRIVE_PWR_SCL4_LS")
	)
	(segment
		(start 58.5216 -82.0674)
		(end 57.785 -81.3308)
		(width 0.127)
		(layer "F.Cu")
		(net "I2C_DRIVE_PWR_SCL4_LS")
	)
	(segment
		(start 58.357008 -80.037432)
		(end 57.785 -80.60944)
		(width 0.127)
		(layer "F.Cu")
		(net "I2C_DRIVE_PWR_SCL4_LS")
	)
	(via
		(at 127.999998 -79.000096)
		(size 0.4572)
		(drill 0.2032)
		(layers "F.Cu" "B.Cu")
		(net "I2C_DRIVE_PWR_SCL4_LS")
	)
	(via
		(at 136.1948 -88.4682)
		(size 0.508)
		(drill 0.254)
		(layers "F.Cu" "B.Cu")
		(net "I2C_DRIVE_PWR_SCL4_LS")
	)
	(via
		(at 57.785 -81.0006)
		(size 0.6604)
		(drill 0.3302)
		(layers "F.Cu" "B.Cu")
		(net "I2C_DRIVE_PWR_SCL4_LS")
	)
	(via
		(at 58.5216 -82.8548)
		(size 0.508)
		(drill 0.254)
		(layers "F.Cu" "B.Cu")
		(net "I2C_DRIVE_PWR_SCL4_LS")
	)
	(segment
		(start 136.1948 -89.2429)
		(end 136.1948 -88.4682)
		(width 0.127)
		(layer "B.Cu")
		(net "I2C_DRIVE_PWR_SCL4_LS")
	)
	(segment
		(start 128.397 -81.788)
		(end 128.397 -79.397098)
		(width 0.127)
		(layer "In2.Cu")
		(net "I2C_DRIVE_PWR_SCL4_LS")
	)
	(segment
		(start 129.88163 -84.70773)
		(end 128.8034 -83.6295)
		(width 0.127)
		(layer "In2.Cu")
		(net "I2C_DRIVE_PWR_SCL4_LS")
	)
	(segment
		(start 128.8034 -82.1944)
		(end 128.397 -81.788)
		(width 0.127)
		(layer "In2.Cu")
		(net "I2C_DRIVE_PWR_SCL4_LS")
	)
	(segment
		(start 129.88163 -85.716364)
		(end 129.88163 -84.70773)
		(width 0.127)
		(layer "In2.Cu")
		(net "I2C_DRIVE_PWR_SCL4_LS")
	)
	(segment
		(start 136.1948 -88.4682)
		(end 132.633466 -88.4682)
		(width 0.127)
		(layer "In2.Cu")
		(net "I2C_DRIVE_PWR_SCL4_LS")
	)
	(segment
		(start 128.8034 -83.6295)
		(end 128.8034 -82.1944)
		(width 0.127)
		(layer "In2.Cu")
		(net "I2C_DRIVE_PWR_SCL4_LS")
	)
	(segment
		(start 132.633466 -88.4682)
		(end 129.88163 -85.716364)
		(width 0.127)
		(layer "In2.Cu")
		(net "I2C_DRIVE_PWR_SCL4_LS")
	)
	(segment
		(start 128.397 -79.397098)
		(end 127.999998 -79.000096)
		(width 0.127)
		(layer "In2.Cu")
		(net "I2C_DRIVE_PWR_SCL4_LS")
	)
	(segment
		(start 59.392312 -82.8548)
		(end 64.603122 -88.06561)
		(width 0.127)
		(layer "In5.Cu")
		(net "I2C_DRIVE_PWR_SCL4_LS")
	)
	(segment
		(start 77.546708 -99.415092)
		(end 97.868232 -99.415092)
		(width 0.127)
		(layer "In5.Cu")
		(net "I2C_DRIVE_PWR_SCL4_LS")
	)
	(segment
		(start 97.868232 -99.415092)
		(end 101.767386 -95.515938)
		(width 0.127)
		(layer "In5.Cu")
		(net "I2C_DRIVE_PWR_SCL4_LS")
	)
	(segment
		(start 58.5216 -82.8548)
		(end 59.392312 -82.8548)
		(width 0.127)
		(layer "In5.Cu")
		(net "I2C_DRIVE_PWR_SCL4_LS")
	)
	(segment
		(start 123.6853 -91.762326)
		(end 126.458726 -88.9889)
		(width 0.127)
		(layer "In5.Cu")
		(net "I2C_DRIVE_PWR_SCL4_LS")
	)
	(segment
		(start 123.6853 -93.4339)
		(end 123.6853 -91.762326)
		(width 0.127)
		(layer "In5.Cu")
		(net "I2C_DRIVE_PWR_SCL4_LS")
	)
	(segment
		(start 123.4186 -93.7006)
		(end 123.6853 -93.4339)
		(width 0.127)
		(layer "In5.Cu")
		(net "I2C_DRIVE_PWR_SCL4_LS")
	)
	(segment
		(start 135.001762 -88.4682)
		(end 136.1948 -88.4682)
		(width 0.127)
		(layer "In5.Cu")
		(net "I2C_DRIVE_PWR_SCL4_LS")
	)
	(segment
		(start 127.894334 -87.503)
		(end 134.036562 -87.503)
		(width 0.127)
		(layer "In5.Cu")
		(net "I2C_DRIVE_PWR_SCL4_LS")
	)
	(segment
		(start 126.72187 -88.9889)
		(end 126.996952 -88.713818)
		(width 0.127)
		(layer "In5.Cu")
		(net "I2C_DRIVE_PWR_SCL4_LS")
	)
	(segment
		(start 120.009412 -95.515938)
		(end 121.575576 -93.94952)
		(width 0.127)
		(layer "In5.Cu")
		(net "I2C_DRIVE_PWR_SCL4_LS")
	)
	(segment
		(start 126.996952 -88.713818)
		(end 126.996952 -88.400382)
		(width 0.127)
		(layer "In5.Cu")
		(net "I2C_DRIVE_PWR_SCL4_LS")
	)
	(segment
		(start 126.458726 -88.9889)
		(end 126.72187 -88.9889)
		(width 0.127)
		(layer "In5.Cu")
		(net "I2C_DRIVE_PWR_SCL4_LS")
	)
	(segment
		(start 126.996952 -88.400382)
		(end 127.894334 -87.503)
		(width 0.127)
		(layer "In5.Cu")
		(net "I2C_DRIVE_PWR_SCL4_LS")
	)
	(segment
		(start 121.575576 -93.94952)
		(end 121.824496 -93.7006)
		(width 0.127)
		(layer "In5.Cu")
		(net "I2C_DRIVE_PWR_SCL4_LS")
	)
	(segment
		(start 66.197226 -88.06561)
		(end 77.546708 -99.415092)
		(width 0.127)
		(layer "In5.Cu")
		(net "I2C_DRIVE_PWR_SCL4_LS")
	)
	(segment
		(start 64.603122 -88.06561)
		(end 66.197226 -88.06561)
		(width 0.127)
		(layer "In5.Cu")
		(net "I2C_DRIVE_PWR_SCL4_LS")
	)
	(segment
		(start 134.036562 -87.503)
		(end 135.001762 -88.4682)
		(width 0.127)
		(layer "In5.Cu")
		(net "I2C_DRIVE_PWR_SCL4_LS")
	)
	(segment
		(start 121.824496 -93.7006)
		(end 123.4186 -93.7006)
		(width 0.127)
		(layer "In5.Cu")
		(net "I2C_DRIVE_PWR_SCL4_LS")
	)
	(segment
		(start 101.767386 -95.515938)
		(end 120.009412 -95.515938)
		(width 0.127)
		(layer "In5.Cu")
		(net "I2C_DRIVE_PWR_SCL4_LS")
	)
	(segment
		(start 57.5564 -74.0918)
		(end 57.7088 -74.2442)
		(width 0.127)
		(layer "F.Cu")
		(net "I2C_DRIVE_PWR_SCL4")
	)
	(segment
		(start 57.0865 -73.1393)
		(end 57.5564 -73.1393)
		(width 0.127)
		(layer "F.Cu")
		(net "I2C_DRIVE_PWR_SCL4")
	)
	(segment
		(start 56.9468 -71.1708)
		(end 56.9468 -72.9996)
		(width 0.127)
		(layer "F.Cu")
		(net "I2C_DRIVE_PWR_SCL4")
	)
	(segment
		(start 58.357008 -75.87107)
		(end 58.357008 -74.892408)
		(width 0.127)
		(layer "F.Cu")
		(net "I2C_DRIVE_PWR_SCL4")
	)
	(segment
		(start 58.357008 -74.892408)
		(end 57.7088 -74.2442)
		(width 0.127)
		(layer "F.Cu")
		(net "I2C_DRIVE_PWR_SCL4")
	)
	(segment
		(start 57.5564 -73.1393)
		(end 57.5564 -74.0918)
		(width 0.127)
		(layer "F.Cu")
		(net "I2C_DRIVE_PWR_SCL4")
	)
	(segment
		(start 56.9468 -72.9996)
		(end 57.0865 -73.1393)
		(width 0.127)
		(layer "F.Cu")
		(net "I2C_DRIVE_PWR_SCL4")
	)
	(segment
		(start 57.277 -70.8406)
		(end 56.9468 -71.1708)
		(width 0.127)
		(layer "F.Cu")
		(net "I2C_DRIVE_PWR_SCL4")
	)
	(via
		(at 57.277 -70.8406)
		(size 0.508)
		(drill 0.254)
		(layers "F.Cu" "B.Cu")
		(net "I2C_DRIVE_PWR_SCL4")
	)
	(via
		(at 57.7088 -74.2442)
		(size 0.6604)
		(drill 0.3302)
		(layers "F.Cu" "B.Cu")
		(net "I2C_DRIVE_PWR_SCL4")
	)
	(segment
		(start 74.519536 -62.27826)
		(end 74.519536 -58.288428)
		(width 0.127)
		(layer "In2.Cu")
		(net "I2C_DRIVE_PWR_SCL4")
	)
	(segment
		(start 77.435964 -49.236884)
		(end 78.177898 -48.49495)
		(width 0.127)
		(layer "In2.Cu")
		(net "I2C_DRIVE_PWR_SCL4")
	)
	(segment
		(start 64.728598 -70.374002)
		(end 67.323208 -67.779392)
		(width 0.127)
		(layer "In2.Cu")
		(net "I2C_DRIVE_PWR_SCL4")
	)
	(segment
		(start 94.54515 -28.99918)
		(end 94.545404 -28.999434)
		(width 0.127)
		(layer "In2.Cu")
		(net "I2C_DRIVE_PWR_SCL4")
	)
	(segment
		(start 74.519536 -58.288428)
		(end 77.435964 -55.372)
		(width 0.127)
		(layer "In2.Cu")
		(net "I2C_DRIVE_PWR_SCL4")
	)
	(segment
		(start 78.177898 -48.49495)
		(end 78.705456 -48.49495)
		(width 0.127)
		(layer "In2.Cu")
		(net "I2C_DRIVE_PWR_SCL4")
	)
	(segment
		(start 81.006696 -46.19371)
		(end 81.006696 -33.88106)
		(width 0.127)
		(layer "In2.Cu")
		(net "I2C_DRIVE_PWR_SCL4")
	)
	(segment
		(start 67.323208 -67.779392)
		(end 69.018404 -67.779392)
		(width 0.127)
		(layer "In2.Cu")
		(net "I2C_DRIVE_PWR_SCL4")
	)
	(segment
		(start 94.545404 -28.999434)
		(end 97.227644 -28.999434)
		(width 0.127)
		(layer "In2.Cu")
		(net "I2C_DRIVE_PWR_SCL4")
	)
	(segment
		(start 97.227644 -28.999434)
		(end 112.333024 -13.894054)
		(width 0.127)
		(layer "In2.Cu")
		(net "I2C_DRIVE_PWR_SCL4")
	)
	(segment
		(start 81.006696 -33.88106)
		(end 85.888576 -28.99918)
		(width 0.127)
		(layer "In2.Cu")
		(net "I2C_DRIVE_PWR_SCL4")
	)
	(segment
		(start 112.333024 -8.532876)
		(end 111.200184 -7.400036)
		(width 0.127)
		(layer "In2.Cu")
		(net "I2C_DRIVE_PWR_SCL4")
	)
	(segment
		(start 57.743598 -70.374002)
		(end 64.728598 -70.374002)
		(width 0.127)
		(layer "In2.Cu")
		(net "I2C_DRIVE_PWR_SCL4")
	)
	(segment
		(start 85.888576 -28.99918)
		(end 94.54515 -28.99918)
		(width 0.127)
		(layer "In2.Cu")
		(net "I2C_DRIVE_PWR_SCL4")
	)
	(segment
		(start 112.333024 -13.894054)
		(end 112.333024 -8.532876)
		(width 0.127)
		(layer "In2.Cu")
		(net "I2C_DRIVE_PWR_SCL4")
	)
	(segment
		(start 57.277 -70.8406)
		(end 57.743598 -70.374002)
		(width 0.127)
		(layer "In2.Cu")
		(net "I2C_DRIVE_PWR_SCL4")
	)
	(segment
		(start 69.018404 -67.779392)
		(end 74.519536 -62.27826)
		(width 0.127)
		(layer "In2.Cu")
		(net "I2C_DRIVE_PWR_SCL4")
	)
	(segment
		(start 78.705456 -48.49495)
		(end 81.006696 -46.19371)
		(width 0.127)
		(layer "In2.Cu")
		(net "I2C_DRIVE_PWR_SCL4")
	)
	(segment
		(start 77.435964 -55.372)
		(end 77.435964 -49.236884)
		(width 0.127)
		(layer "In2.Cu")
		(net "I2C_DRIVE_PWR_SCL4")
	)
	(segment
		(start 126.500128 -78.500224)
		(end 127 -78.000352)
		(width 0.127)
		(layer "F.Cu")
		(net "I2C_DRIVE_INS_SDA5_LS")
	)
	(segment
		(start 61.87694 -83.7438)
		(end 61.491114 -83.357974)
		(width 0.127)
		(layer "F.Cu")
		(net "I2C_DRIVE_INS_SDA5_LS")
	)
	(segment
		(start 62.5094 -83.7438)
		(end 61.87694 -83.7438)
		(width 0.127)
		(layer "F.Cu")
		(net "I2C_DRIVE_INS_SDA5_LS")
	)
	(segment
		(start 62.36589 -79.112618)
		(end 62.36589 -79.893414)
		(width 0.127)
		(layer "F.Cu")
		(net "I2C_DRIVE_INS_SDA5_LS")
	)
	(segment
		(start 62.36589 -79.893414)
		(end 61.491114 -80.76819)
		(width 0.127)
		(layer "F.Cu")
		(net "I2C_DRIVE_INS_SDA5_LS")
	)
	(segment
		(start 61.491114 -83.357974)
		(end 61.491114 -83.132422)
		(width 0.127)
		(layer "F.Cu")
		(net "I2C_DRIVE_INS_SDA5_LS")
	)
	(segment
		(start 61.491114 -80.76819)
		(end 61.491114 -83.132422)
		(width 0.127)
		(layer "F.Cu")
		(net "I2C_DRIVE_INS_SDA5_LS")
	)
	(via
		(at 61.491114 -83.132422)
		(size 0.6604)
		(drill 0.3302)
		(layers "F.Cu" "B.Cu")
		(net "I2C_DRIVE_INS_SDA5_LS")
	)
	(via
		(at 135.6614 -86.97214)
		(size 0.508)
		(drill 0.254)
		(layers "F.Cu" "B.Cu")
		(net "I2C_DRIVE_INS_SDA5_LS")
	)
	(via
		(at 127 -78.000352)
		(size 0.4572)
		(drill 0.2032)
		(layers "F.Cu" "B.Cu")
		(net "I2C_DRIVE_INS_SDA5_LS")
	)
	(via
		(at 62.5094 -83.7438)
		(size 0.508)
		(drill 0.254)
		(layers "F.Cu" "B.Cu")
		(net "I2C_DRIVE_INS_SDA5_LS")
	)
	(segment
		(start 132.728462 -83.2104)
		(end 135.204454 -83.2104)
		(width 0.127)
		(layer "B.Cu")
		(net "I2C_DRIVE_INS_SDA5_LS")
	)
	(segment
		(start 131.6228 -82.104738)
		(end 132.728462 -83.2104)
		(width 0.127)
		(layer "B.Cu")
		(net "I2C_DRIVE_INS_SDA5_LS")
	)
	(segment
		(start 131.18084 -80.606392)
		(end 131.6228 -81.048352)
		(width 0.127)
		(layer "B.Cu")
		(net "I2C_DRIVE_INS_SDA5_LS")
	)
	(segment
		(start 135.622538 -83.628484)
		(end 135.622538 -84.2645)
		(width 0.127)
		(layer "B.Cu")
		(net "I2C_DRIVE_INS_SDA5_LS")
	)
	(segment
		(start 129.7432 -79.5655)
		(end 130.784092 -80.606392)
		(width 0.127)
		(layer "B.Cu")
		(net "I2C_DRIVE_INS_SDA5_LS")
	)
	(segment
		(start 136.135872 -84.777834)
		(end 136.135872 -85.162136)
		(width 0.127)
		(layer "B.Cu")
		(net "I2C_DRIVE_INS_SDA5_LS")
	)
	(segment
		(start 127.51689 -78.517242)
		(end 127.51689 -79.128112)
		(width 0.127)
		(layer "B.Cu")
		(net "I2C_DRIVE_INS_SDA5_LS")
	)
	(segment
		(start 131.6228 -81.048352)
		(end 131.6228 -82.104738)
		(width 0.127)
		(layer "B.Cu")
		(net "I2C_DRIVE_INS_SDA5_LS")
	)
	(segment
		(start 135.204454 -83.2104)
		(end 135.622538 -83.628484)
		(width 0.127)
		(layer "B.Cu")
		(net "I2C_DRIVE_INS_SDA5_LS")
	)
	(segment
		(start 136.321038 -86.312502)
		(end 135.6614 -86.97214)
		(width 0.127)
		(layer "B.Cu")
		(net "I2C_DRIVE_INS_SDA5_LS")
	)
	(segment
		(start 136.135872 -85.162136)
		(end 136.321038 -85.347302)
		(width 0.127)
		(layer "B.Cu")
		(net "I2C_DRIVE_INS_SDA5_LS")
	)
	(segment
		(start 130.784092 -80.606392)
		(end 131.18084 -80.606392)
		(width 0.127)
		(layer "B.Cu")
		(net "I2C_DRIVE_INS_SDA5_LS")
	)
	(segment
		(start 127.51689 -79.128112)
		(end 127.954278 -79.5655)
		(width 0.127)
		(layer "B.Cu")
		(net "I2C_DRIVE_INS_SDA5_LS")
	)
	(segment
		(start 127 -78.000352)
		(end 127.51689 -78.517242)
		(width 0.127)
		(layer "B.Cu")
		(net "I2C_DRIVE_INS_SDA5_LS")
	)
	(segment
		(start 127.954278 -79.5655)
		(end 129.7432 -79.5655)
		(width 0.127)
		(layer "B.Cu")
		(net "I2C_DRIVE_INS_SDA5_LS")
	)
	(segment
		(start 136.321038 -85.347302)
		(end 136.321038 -86.312502)
		(width 0.127)
		(layer "B.Cu")
		(net "I2C_DRIVE_INS_SDA5_LS")
	)
	(segment
		(start 135.622538 -84.2645)
		(end 136.135872 -84.777834)
		(width 0.127)
		(layer "B.Cu")
		(net "I2C_DRIVE_INS_SDA5_LS")
	)
	(segment
		(start 116.751608 -93.991938)
		(end 118.05412 -92.689426)
		(width 0.127)
		(layer "In5.Cu")
		(net "I2C_DRIVE_INS_SDA5_LS")
	)
	(segment
		(start 64.455802 -85.690202)
		(end 66.052192 -85.690202)
		(width 0.127)
		(layer "In5.Cu")
		(net "I2C_DRIVE_INS_SDA5_LS")
	)
	(segment
		(start 79.534258 -96.53524)
		(end 98.592386 -96.53524)
		(width 0.127)
		(layer "In5.Cu")
		(net "I2C_DRIVE_INS_SDA5_LS")
	)
	(segment
		(start 134.66826 -85.979)
		(end 135.6614 -86.97214)
		(width 0.127)
		(layer "In5.Cu")
		(net "I2C_DRIVE_INS_SDA5_LS")
	)
	(segment
		(start 126.711202 -85.979)
		(end 134.66826 -85.979)
		(width 0.127)
		(layer "In5.Cu")
		(net "I2C_DRIVE_INS_SDA5_LS")
	)
	(segment
		(start 77.020166 -94.021148)
		(end 79.534258 -96.53524)
		(width 0.127)
		(layer "In5.Cu")
		(net "I2C_DRIVE_INS_SDA5_LS")
	)
	(segment
		(start 66.052192 -85.690202)
		(end 74.383138 -94.021148)
		(width 0.127)
		(layer "In5.Cu")
		(net "I2C_DRIVE_INS_SDA5_LS")
	)
	(segment
		(start 74.383138 -94.021148)
		(end 77.020166 -94.021148)
		(width 0.127)
		(layer "In5.Cu")
		(net "I2C_DRIVE_INS_SDA5_LS")
	)
	(segment
		(start 62.5094 -83.7438)
		(end 64.455802 -85.690202)
		(width 0.127)
		(layer "In5.Cu")
		(net "I2C_DRIVE_INS_SDA5_LS")
	)
	(segment
		(start 119.26316 -92.689426)
		(end 119.699786 -92.2528)
		(width 0.127)
		(layer "In5.Cu")
		(net "I2C_DRIVE_INS_SDA5_LS")
	)
	(segment
		(start 120.437402 -92.2528)
		(end 126.711202 -85.979)
		(width 0.127)
		(layer "In5.Cu")
		(net "I2C_DRIVE_INS_SDA5_LS")
	)
	(segment
		(start 118.05412 -92.689426)
		(end 119.26316 -92.689426)
		(width 0.127)
		(layer "In5.Cu")
		(net "I2C_DRIVE_INS_SDA5_LS")
	)
	(segment
		(start 98.592386 -96.53524)
		(end 101.135688 -93.991938)
		(width 0.127)
		(layer "In5.Cu")
		(net "I2C_DRIVE_INS_SDA5_LS")
	)
	(segment
		(start 101.135688 -93.991938)
		(end 116.751608 -93.991938)
		(width 0.127)
		(layer "In5.Cu")
		(net "I2C_DRIVE_INS_SDA5_LS")
	)
	(segment
		(start 119.699786 -92.2528)
		(end 120.437402 -92.2528)
		(width 0.127)
		(layer "In5.Cu")
		(net "I2C_DRIVE_INS_SDA5_LS")
	)
	(segment
		(start 61.722 -74.5236)
		(end 61.087 -74.5236)
		(width 0.127)
		(layer "F.Cu")
		(net "I2C_DRIVE_INS_SDA5")
	)
	(segment
		(start 62.36589 -75.861418)
		(end 62.36589 -75.16749)
		(width 0.127)
		(layer "F.Cu")
		(net "I2C_DRIVE_INS_SDA5")
	)
	(segment
		(start 60.6806 -73.1393)
		(end 61.151008 -73.1393)
		(width 0.127)
		(layer "F.Cu")
		(net "I2C_DRIVE_INS_SDA5")
	)
	(segment
		(start 61.087 -74.5236)
		(end 60.8838 -74.3204)
		(width 0.127)
		(layer "F.Cu")
		(net "I2C_DRIVE_INS_SDA5")
	)
	(segment
		(start 60.8838 -74.3204)
		(end 60.6806 -74.1172)
		(width 0.127)
		(layer "F.Cu")
		(net "I2C_DRIVE_INS_SDA5")
	)
	(segment
		(start 60.6806 -74.1172)
		(end 60.6806 -73.1393)
		(width 0.127)
		(layer "F.Cu")
		(net "I2C_DRIVE_INS_SDA5")
	)
	(segment
		(start 61.151008 -73.1393)
		(end 61.570108 -72.7202)
		(width 0.127)
		(layer "F.Cu")
		(net "I2C_DRIVE_INS_SDA5")
	)
	(segment
		(start 62.36589 -75.16749)
		(end 61.722 -74.5236)
		(width 0.127)
		(layer "F.Cu")
		(net "I2C_DRIVE_INS_SDA5")
	)
	(via
		(at 60.8838 -74.3204)
		(size 0.6604)
		(drill 0.3302)
		(layers "F.Cu" "B.Cu")
		(net "I2C_DRIVE_INS_SDA5")
	)
	(via
		(at 61.570108 -72.7202)
		(size 0.508)
		(drill 0.254)
		(layers "F.Cu" "B.Cu")
		(net "I2C_DRIVE_INS_SDA5")
	)
	(segment
		(start 73.307448 -64.208914)
		(end 73.307448 -65.33261)
		(width 0.127)
		(layer "In2.Cu")
		(net "I2C_DRIVE_INS_SDA5")
	)
	(segment
		(start 97.43821 -29.507434)
		(end 94.334838 -29.507434)
		(width 0.127)
		(layer "In2.Cu")
		(net "I2C_DRIVE_INS_SDA5")
	)
	(segment
		(start 82.71002 -32.896302)
		(end 82.71002 -33.62198)
		(width 0.127)
		(layer "In2.Cu")
		(net "I2C_DRIVE_INS_SDA5")
	)
	(segment
		(start 113.652808 -8.252968)
		(end 113.652808 -14.08557)
		(width 0.127)
		(layer "In2.Cu")
		(net "I2C_DRIVE_INS_SDA5")
	)
	(segment
		(start 82.71002 -33.62198)
		(end 81.571084 -34.760916)
		(width 0.127)
		(layer "In2.Cu")
		(net "I2C_DRIVE_INS_SDA5")
	)
	(segment
		(start 98.231198 -29.50718)
		(end 97.438464 -29.50718)
		(width 0.127)
		(layer "In2.Cu")
		(net "I2C_DRIVE_INS_SDA5")
	)
	(segment
		(start 78.772258 -55.286148)
		(end 78.266798 -55.286148)
		(width 0.127)
		(layer "In2.Cu")
		(net "I2C_DRIVE_INS_SDA5")
	)
	(segment
		(start 76.276708 -57.276238)
		(end 76.276708 -61.239654)
		(width 0.127)
		(layer "In2.Cu")
		(net "I2C_DRIVE_INS_SDA5")
	)
	(segment
		(start 79.033878 -55.024528)
		(end 78.772258 -55.286148)
		(width 0.127)
		(layer "In2.Cu")
		(net "I2C_DRIVE_INS_SDA5")
	)
	(segment
		(start 113.000028 -7.600188)
		(end 113.652808 -8.252968)
		(width 0.127)
		(layer "In2.Cu")
		(net "I2C_DRIVE_INS_SDA5")
	)
	(segment
		(start 97.438464 -29.50718)
		(end 97.43821 -29.507434)
		(width 0.127)
		(layer "In2.Cu")
		(net "I2C_DRIVE_INS_SDA5")
	)
	(segment
		(start 94.334838 -29.507434)
		(end 94.334584 -29.50718)
		(width 0.127)
		(layer "In2.Cu")
		(net "I2C_DRIVE_INS_SDA5")
	)
	(segment
		(start 63.100966 -72.7202)
		(end 61.570108 -72.7202)
		(width 0.127)
		(layer "In2.Cu")
		(net "I2C_DRIVE_INS_SDA5")
	)
	(segment
		(start 76.276708 -61.239654)
		(end 73.307448 -64.208914)
		(width 0.127)
		(layer "In2.Cu")
		(net "I2C_DRIVE_INS_SDA5")
	)
	(segment
		(start 67.533774 -68.287392)
		(end 63.100966 -72.7202)
		(width 0.127)
		(layer "In2.Cu")
		(net "I2C_DRIVE_INS_SDA5")
	)
	(segment
		(start 78.266798 -55.286148)
		(end 76.276708 -57.276238)
		(width 0.127)
		(layer "In2.Cu")
		(net "I2C_DRIVE_INS_SDA5")
	)
	(segment
		(start 73.307448 -65.33261)
		(end 70.352666 -68.287392)
		(width 0.127)
		(layer "In2.Cu")
		(net "I2C_DRIVE_INS_SDA5")
	)
	(segment
		(start 113.652808 -14.08557)
		(end 98.231198 -29.50718)
		(width 0.127)
		(layer "In2.Cu")
		(net "I2C_DRIVE_INS_SDA5")
	)
	(segment
		(start 94.334584 -29.50718)
		(end 86.099142 -29.50718)
		(width 0.127)
		(layer "In2.Cu")
		(net "I2C_DRIVE_INS_SDA5")
	)
	(segment
		(start 81.571084 -47.000922)
		(end 79.033878 -49.538128)
		(width 0.127)
		(layer "In2.Cu")
		(net "I2C_DRIVE_INS_SDA5")
	)
	(segment
		(start 86.099142 -29.50718)
		(end 82.71002 -32.896302)
		(width 0.127)
		(layer "In2.Cu")
		(net "I2C_DRIVE_INS_SDA5")
	)
	(segment
		(start 79.033878 -49.538128)
		(end 79.033878 -55.024528)
		(width 0.127)
		(layer "In2.Cu")
		(net "I2C_DRIVE_INS_SDA5")
	)
	(segment
		(start 81.571084 -34.760916)
		(end 81.571084 -47.000922)
		(width 0.127)
		(layer "In2.Cu")
		(net "I2C_DRIVE_INS_SDA5")
	)
	(segment
		(start 70.352666 -68.287392)
		(end 67.533774 -68.287392)
		(width 0.127)
		(layer "In2.Cu")
		(net "I2C_DRIVE_INS_SDA5")
	)
	(segment
		(start 63.01613 -79.112618)
		(end 63.01613 -79.96174)
		(width 0.127)
		(layer "F.Cu")
		(net "I2C_DRIVE_INS_SCL5_LS")
	)
	(segment
		(start 136.762744 -84.053172)
		(end 135.817102 -83.10753)
		(width 0.127)
		(layer "F.Cu")
		(net "I2C_DRIVE_INS_SCL5_LS")
	)
	(segment
		(start 63.01613 -79.96174)
		(end 62.469522 -80.508348)
		(width 0.127)
		(layer "F.Cu")
		(net "I2C_DRIVE_INS_SCL5_LS")
	)
	(segment
		(start 133.368034 -83.10753)
		(end 132.109464 -81.84896)
		(width 0.127)
		(layer "F.Cu")
		(net "I2C_DRIVE_INS_SCL5_LS")
	)
	(segment
		(start 129.713482 -79.500222)
		(end 129.500122 -79.500222)
		(width 0.127)
		(layer "F.Cu")
		(net "I2C_DRIVE_INS_SCL5_LS")
	)
	(segment
		(start 130.660394 -79.976726)
		(end 130.189986 -79.976726)
		(width 0.127)
		(layer "F.Cu")
		(net "I2C_DRIVE_INS_SCL5_LS")
	)
	(segment
		(start 132.109464 -81.84896)
		(end 132.109464 -81.425796)
		(width 0.127)
		(layer "F.Cu")
		(net "I2C_DRIVE_INS_SCL5_LS")
	)
	(segment
		(start 137.595356 -84.265262)
		(end 137.37971 -84.049616)
		(width 0.127)
		(layer "F.Cu")
		(net "I2C_DRIVE_INS_SCL5_LS")
	)
	(segment
		(start 137.37971 -84.049616)
		(end 136.7663 -84.049616)
		(width 0.127)
		(layer "F.Cu")
		(net "I2C_DRIVE_INS_SCL5_LS")
	)
	(segment
		(start 136.7663 -84.049616)
		(end 136.762744 -84.053172)
		(width 0.127)
		(layer "F.Cu")
		(net "I2C_DRIVE_INS_SCL5_LS")
	)
	(segment
		(start 62.469522 -82.8802)
		(end 62.469522 -81.798922)
		(width 0.127)
		(layer "F.Cu")
		(net "I2C_DRIVE_INS_SCL5_LS")
	)
	(segment
		(start 130.189986 -79.976726)
		(end 129.713482 -79.500222)
		(width 0.127)
		(layer "F.Cu")
		(net "I2C_DRIVE_INS_SCL5_LS")
	)
	(segment
		(start 132.109464 -81.425796)
		(end 130.660394 -79.976726)
		(width 0.127)
		(layer "F.Cu")
		(net "I2C_DRIVE_INS_SCL5_LS")
	)
	(segment
		(start 62.469522 -80.508348)
		(end 62.469522 -81.798922)
		(width 0.127)
		(layer "F.Cu")
		(net "I2C_DRIVE_INS_SCL5_LS")
	)
	(segment
		(start 135.817102 -83.10753)
		(end 133.368034 -83.10753)
		(width 0.127)
		(layer "F.Cu")
		(net "I2C_DRIVE_INS_SCL5_LS")
	)
	(via
		(at 62.469522 -82.8802)
		(size 0.508)
		(drill 0.254)
		(layers "F.Cu" "B.Cu")
		(net "I2C_DRIVE_INS_SCL5_LS")
	)
	(via
		(at 136.762744 -84.053172)
		(size 0.508)
		(drill 0.254)
		(layers "F.Cu" "B.Cu")
		(net "I2C_DRIVE_INS_SCL5_LS")
	)
	(via
		(at 62.469522 -81.798922)
		(size 0.6604)
		(drill 0.3302)
		(layers "F.Cu" "B.Cu")
		(net "I2C_DRIVE_INS_SCL5_LS")
	)
	(segment
		(start 77.837792 -93.303344)
		(end 74.3839 -93.303344)
		(width 0.127)
		(layer "In5.Cu")
		(net "I2C_DRIVE_INS_SCL5_LS")
	)
	(segment
		(start 136.878568 -86.444582)
		(end 135.904986 -85.471)
		(width 0.127)
		(layer "In5.Cu")
		(net "I2C_DRIVE_INS_SCL5_LS")
	)
	(segment
		(start 74.3839 -93.303344)
		(end 65.792858 -84.712302)
		(width 0.127)
		(layer "In5.Cu")
		(net "I2C_DRIVE_INS_SCL5_LS")
	)
	(segment
		(start 126.500636 -85.471)
		(end 120.696736 -91.2749)
		(width 0.127)
		(layer "In5.Cu")
		(net "I2C_DRIVE_INS_SCL5_LS")
	)
	(segment
		(start 136.762744 -84.053172)
		(end 137.116312 -84.40674)
		(width 0.127)
		(layer "In5.Cu")
		(net "I2C_DRIVE_INS_SCL5_LS")
	)
	(segment
		(start 137.116312 -84.440776)
		(end 137.650982 -84.975446)
		(width 0.127)
		(layer "In5.Cu")
		(net "I2C_DRIVE_INS_SCL5_LS")
	)
	(segment
		(start 80.561688 -96.02724)
		(end 77.837792 -93.303344)
		(width 0.127)
		(layer "In5.Cu")
		(net "I2C_DRIVE_INS_SCL5_LS")
	)
	(segment
		(start 64.301624 -84.712302)
		(end 62.469522 -82.8802)
		(width 0.127)
		(layer "In5.Cu")
		(net "I2C_DRIVE_INS_SCL5_LS")
	)
	(segment
		(start 120.696736 -91.2749)
		(end 118.364 -91.2749)
		(width 0.127)
		(layer "In5.Cu")
		(net "I2C_DRIVE_INS_SCL5_LS")
	)
	(segment
		(start 137.650982 -84.975446)
		(end 137.650982 -86.240366)
		(width 0.127)
		(layer "In5.Cu")
		(net "I2C_DRIVE_INS_SCL5_LS")
	)
	(segment
		(start 116.154962 -93.483938)
		(end 100.925122 -93.483938)
		(width 0.127)
		(layer "In5.Cu")
		(net "I2C_DRIVE_INS_SCL5_LS")
	)
	(segment
		(start 135.904986 -85.471)
		(end 126.500636 -85.471)
		(width 0.127)
		(layer "In5.Cu")
		(net "I2C_DRIVE_INS_SCL5_LS")
	)
	(segment
		(start 137.116312 -84.40674)
		(end 137.116312 -84.440776)
		(width 0.127)
		(layer "In5.Cu")
		(net "I2C_DRIVE_INS_SCL5_LS")
	)
	(segment
		(start 98.38182 -96.02724)
		(end 80.561688 -96.02724)
		(width 0.127)
		(layer "In5.Cu")
		(net "I2C_DRIVE_INS_SCL5_LS")
	)
	(segment
		(start 137.446766 -86.444582)
		(end 136.878568 -86.444582)
		(width 0.127)
		(layer "In5.Cu")
		(net "I2C_DRIVE_INS_SCL5_LS")
	)
	(segment
		(start 137.650982 -86.240366)
		(end 137.446766 -86.444582)
		(width 0.127)
		(layer "In5.Cu")
		(net "I2C_DRIVE_INS_SCL5_LS")
	)
	(segment
		(start 118.364 -91.2749)
		(end 116.154962 -93.483938)
		(width 0.127)
		(layer "In5.Cu")
		(net "I2C_DRIVE_INS_SCL5_LS")
	)
	(segment
		(start 100.925122 -93.483938)
		(end 98.38182 -96.02724)
		(width 0.127)
		(layer "In5.Cu")
		(net "I2C_DRIVE_INS_SCL5_LS")
	)
	(segment
		(start 65.792858 -84.712302)
		(end 64.301624 -84.712302)
		(width 0.127)
		(layer "In5.Cu")
		(net "I2C_DRIVE_INS_SCL5_LS")
	)
	(segment
		(start 63.01613 -75.861418)
		(end 63.01613 -74.59853)
		(width 0.127)
		(layer "F.Cu")
		(net "I2C_DRIVE_INS_SCL5")
	)
	(segment
		(start 62.0141 -73.5838)
		(end 62.4332 -73.1647)
		(width 0.127)
		(layer "F.Cu")
		(net "I2C_DRIVE_INS_SCL5")
	)
	(segment
		(start 62.4332 -74.0156)
		(end 62.6872 -74.2696)
		(width 0.127)
		(layer "F.Cu")
		(net "I2C_DRIVE_INS_SCL5")
	)
	(segment
		(start 63.01613 -74.59853)
		(end 62.6872 -74.2696)
		(width 0.127)
		(layer "F.Cu")
		(net "I2C_DRIVE_INS_SCL5")
	)
	(segment
		(start 61.5696 -73.5838)
		(end 62.0141 -73.5838)
		(width 0.127)
		(layer "F.Cu")
		(net "I2C_DRIVE_INS_SCL5")
	)
	(segment
		(start 62.4332 -73.1647)
		(end 62.4332 -74.0156)
		(width 0.127)
		(layer "F.Cu")
		(net "I2C_DRIVE_INS_SCL5")
	)
	(via
		(at 61.5696 -73.5838)
		(size 0.508)
		(drill 0.254)
		(layers "F.Cu" "B.Cu")
		(net "I2C_DRIVE_INS_SCL5")
	)
	(via
		(at 62.6872 -74.2696)
		(size 0.6604)
		(drill 0.3302)
		(layers "F.Cu" "B.Cu")
		(net "I2C_DRIVE_INS_SCL5")
	)
	(segment
		(start 74.581766 -63.653162)
		(end 76.784708 -61.45022)
		(width 0.127)
		(layer "In2.Cu")
		(net "I2C_DRIVE_INS_SCL5")
	)
	(segment
		(start 94.124272 -30.015434)
		(end 97.648776 -30.015434)
		(width 0.127)
		(layer "In2.Cu")
		(net "I2C_DRIVE_INS_SCL5")
	)
	(segment
		(start 86.696804 -30.01518)
		(end 94.124018 -30.01518)
		(width 0.127)
		(layer "In2.Cu")
		(net "I2C_DRIVE_INS_SCL5")
	)
	(segment
		(start 97.648776 -30.015434)
		(end 97.64903 -30.01518)
		(width 0.127)
		(layer "In2.Cu")
		(net "I2C_DRIVE_INS_SCL5")
	)
	(segment
		(start 73.602342 -66.047112)
		(end 74.581766 -65.067688)
		(width 0.127)
		(layer "In2.Cu")
		(net "I2C_DRIVE_INS_SCL5")
	)
	(segment
		(start 82.28076 -47.417736)
		(end 82.28076 -34.791142)
		(width 0.127)
		(layer "In2.Cu")
		(net "I2C_DRIVE_INS_SCL5")
	)
	(segment
		(start 98.020886 -30.015434)
		(end 98.44151 -30.015434)
		(width 0.127)
		(layer "In2.Cu")
		(net "I2C_DRIVE_INS_SCL5")
	)
	(segment
		(start 94.124018 -30.01518)
		(end 94.124272 -30.015434)
		(width 0.127)
		(layer "In2.Cu")
		(net "I2C_DRIVE_INS_SCL5")
	)
	(segment
		(start 76.784708 -59.383676)
		(end 78.071726 -58.096658)
		(width 0.127)
		(layer "In2.Cu")
		(net "I2C_DRIVE_INS_SCL5")
	)
	(segment
		(start 79.541878 -57.259728)
		(end 79.541878 -50.156618)
		(width 0.127)
		(layer "In2.Cu")
		(net "I2C_DRIVE_INS_SCL5")
	)
	(segment
		(start 114.160808 -7.36092)
		(end 113.000028 -6.20014)
		(width 0.127)
		(layer "In2.Cu")
		(net "I2C_DRIVE_INS_SCL5")
	)
	(segment
		(start 79.541878 -50.156618)
		(end 82.28076 -47.417736)
		(width 0.127)
		(layer "In2.Cu")
		(net "I2C_DRIVE_INS_SCL5")
	)
	(segment
		(start 73.311512 -66.047112)
		(end 73.602342 -66.047112)
		(width 0.127)
		(layer "In2.Cu")
		(net "I2C_DRIVE_INS_SCL5")
	)
	(segment
		(start 62.955932 -73.5838)
		(end 67.74434 -68.795392)
		(width 0.127)
		(layer "In2.Cu")
		(net "I2C_DRIVE_INS_SCL5")
	)
	(segment
		(start 78.071726 -58.096658)
		(end 78.704948 -58.096658)
		(width 0.127)
		(layer "In2.Cu")
		(net "I2C_DRIVE_INS_SCL5")
	)
	(segment
		(start 76.784708 -61.45022)
		(end 76.784708 -59.383676)
		(width 0.127)
		(layer "In2.Cu")
		(net "I2C_DRIVE_INS_SCL5")
	)
	(segment
		(start 70.563232 -68.795392)
		(end 73.311512 -66.047112)
		(width 0.127)
		(layer "In2.Cu")
		(net "I2C_DRIVE_INS_SCL5")
	)
	(segment
		(start 74.581766 -65.067688)
		(end 74.581766 -63.653162)
		(width 0.127)
		(layer "In2.Cu")
		(net "I2C_DRIVE_INS_SCL5")
	)
	(segment
		(start 98.020632 -30.01518)
		(end 98.020886 -30.015434)
		(width 0.127)
		(layer "In2.Cu")
		(net "I2C_DRIVE_INS_SCL5")
	)
	(segment
		(start 98.44151 -30.015434)
		(end 114.160808 -14.296136)
		(width 0.127)
		(layer "In2.Cu")
		(net "I2C_DRIVE_INS_SCL5")
	)
	(segment
		(start 97.64903 -30.01518)
		(end 98.020632 -30.01518)
		(width 0.127)
		(layer "In2.Cu")
		(net "I2C_DRIVE_INS_SCL5")
	)
	(segment
		(start 84.712048 -31.999936)
		(end 86.696804 -30.01518)
		(width 0.127)
		(layer "In2.Cu")
		(net "I2C_DRIVE_INS_SCL5")
	)
	(segment
		(start 61.5696 -73.5838)
		(end 62.955932 -73.5838)
		(width 0.127)
		(layer "In2.Cu")
		(net "I2C_DRIVE_INS_SCL5")
	)
	(segment
		(start 78.704948 -58.096658)
		(end 79.541878 -57.259728)
		(width 0.127)
		(layer "In2.Cu")
		(net "I2C_DRIVE_INS_SCL5")
	)
	(segment
		(start 82.28076 -34.791142)
		(end 84.712048 -32.359854)
		(width 0.127)
		(layer "In2.Cu")
		(net "I2C_DRIVE_INS_SCL5")
	)
	(segment
		(start 84.712048 -32.359854)
		(end 84.712048 -31.999936)
		(width 0.127)
		(layer "In2.Cu")
		(net "I2C_DRIVE_INS_SCL5")
	)
	(segment
		(start 67.74434 -68.795392)
		(end 70.563232 -68.795392)
		(width 0.127)
		(layer "In2.Cu")
		(net "I2C_DRIVE_INS_SCL5")
	)
	(segment
		(start 114.160808 -14.296136)
		(end 114.160808 -7.36092)
		(width 0.127)
		(layer "In2.Cu")
		(net "I2C_DRIVE_INS_SCL5")
	)
	(segment
		(start 135.975344 -84.037932)
		(end 135.975344 -84.270088)
		(width 0.127)
		(layer "F.Cu")
		(net "I2C_DRIVE_FLT_LED_SDA6_LS")
	)
	(segment
		(start 133.268974 -83.61553)
		(end 135.552942 -83.61553)
		(width 0.127)
		(layer "F.Cu")
		(net "I2C_DRIVE_FLT_LED_SDA6_LS")
	)
	(segment
		(start 65.96126 -80.712056)
		(end 66.481706 -80.19161)
		(width 0.127)
		(layer "F.Cu")
		(net "I2C_DRIVE_FLT_LED_SDA6_LS")
	)
	(segment
		(start 67.084956 -80.19161)
		(end 67.299078 -79.977488)
		(width 0.127)
		(layer "F.Cu")
		(net "I2C_DRIVE_FLT_LED_SDA6_LS")
	)
	(segment
		(start 135.552942 -83.61553)
		(end 135.975344 -84.037932)
		(width 0.127)
		(layer "F.Cu")
		(net "I2C_DRIVE_FLT_LED_SDA6_LS")
	)
	(segment
		(start 65.96126 -81.50225)
		(end 65.96126 -80.712056)
		(width 0.127)
		(layer "F.Cu")
		(net "I2C_DRIVE_FLT_LED_SDA6_LS")
	)
	(segment
		(start 65.96126 -81.959704)
		(end 65.96126 -81.50225)
		(width 0.127)
		(layer "F.Cu")
		(net "I2C_DRIVE_FLT_LED_SDA6_LS")
	)
	(segment
		(start 67.299078 -79.977488)
		(end 67.299078 -79.186024)
		(width 0.127)
		(layer "F.Cu")
		(net "I2C_DRIVE_FLT_LED_SDA6_LS")
	)
	(segment
		(start 66.38671 -82.385154)
		(end 65.96126 -81.959704)
		(width 0.127)
		(layer "F.Cu")
		(net "I2C_DRIVE_FLT_LED_SDA6_LS")
	)
	(segment
		(start 136.114282 -84.270088)
		(end 136.772904 -84.92871)
		(width 0.127)
		(layer "F.Cu")
		(net "I2C_DRIVE_FLT_LED_SDA6_LS")
	)
	(segment
		(start 66.481706 -80.19161)
		(end 67.084956 -80.19161)
		(width 0.127)
		(layer "F.Cu")
		(net "I2C_DRIVE_FLT_LED_SDA6_LS")
	)
	(segment
		(start 131.153662 -81.500218)
		(end 133.268974 -83.61553)
		(width 0.127)
		(layer "F.Cu")
		(net "I2C_DRIVE_FLT_LED_SDA6_LS")
	)
	(segment
		(start 130.50012 -81.500218)
		(end 131.153662 -81.500218)
		(width 0.127)
		(layer "F.Cu")
		(net "I2C_DRIVE_FLT_LED_SDA6_LS")
	)
	(segment
		(start 135.975344 -84.270088)
		(end 136.114282 -84.270088)
		(width 0.127)
		(layer "F.Cu")
		(net "I2C_DRIVE_FLT_LED_SDA6_LS")
	)
	(via
		(at 136.772904 -84.92871)
		(size 0.508)
		(drill 0.254)
		(layers "F.Cu" "B.Cu")
		(net "I2C_DRIVE_FLT_LED_SDA6_LS")
	)
	(via
		(at 66.38671 -82.385154)
		(size 0.508)
		(drill 0.254)
		(layers "F.Cu" "B.Cu")
		(net "I2C_DRIVE_FLT_LED_SDA6_LS")
	)
	(via
		(at 65.96126 -81.50225)
		(size 0.6604)
		(drill 0.3302)
		(layers "F.Cu" "B.Cu")
		(net "I2C_DRIVE_FLT_LED_SDA6_LS")
	)
	(segment
		(start 75.526392 -81.832958)
		(end 75.526392 -79.678022)
		(width 0.127)
		(layer "In5.Cu")
		(net "I2C_DRIVE_FLT_LED_SDA6_LS")
	)
	(segment
		(start 75.7174 -86.516718)
		(end 75.7174 -82.023966)
		(width 0.127)
		(layer "In5.Cu")
		(net "I2C_DRIVE_FLT_LED_SDA6_LS")
	)
	(segment
		(start 67.724274 -78.578456)
		(end 66.572638 -79.730092)
		(width 0.127)
		(layer "In5.Cu")
		(net "I2C_DRIVE_FLT_LED_SDA6_LS")
	)
	(segment
		(start 119.178578 -88.75014)
		(end 116.053616 -88.75014)
		(width 0.127)
		(layer "In5.Cu")
		(net "I2C_DRIVE_FLT_LED_SDA6_LS")
	)
	(segment
		(start 75.526392 -79.678022)
		(end 74.426826 -78.578456)
		(width 0.127)
		(layer "In5.Cu")
		(net "I2C_DRIVE_FLT_LED_SDA6_LS")
	)
	(segment
		(start 100.1141 -91.420696)
		(end 98.11512 -93.419676)
		(width 0.127)
		(layer "In5.Cu")
		(net "I2C_DRIVE_FLT_LED_SDA6_LS")
	)
	(segment
		(start 66.572638 -82.199226)
		(end 66.38671 -82.385154)
		(width 0.127)
		(layer "In5.Cu")
		(net "I2C_DRIVE_FLT_LED_SDA6_LS")
	)
	(segment
		(start 136.772904 -84.92871)
		(end 136.290558 -84.446364)
		(width 0.127)
		(layer "In5.Cu")
		(net "I2C_DRIVE_FLT_LED_SDA6_LS")
	)
	(segment
		(start 136.290558 -84.446364)
		(end 134.43331 -84.446364)
		(width 0.127)
		(layer "In5.Cu")
		(net "I2C_DRIVE_FLT_LED_SDA6_LS")
	)
	(segment
		(start 122.397266 -86.205314)
		(end 121.723404 -86.205314)
		(width 0.127)
		(layer "In5.Cu")
		(net "I2C_DRIVE_FLT_LED_SDA6_LS")
	)
	(segment
		(start 134.43331 -84.446364)
		(end 132.649214 -82.662268)
		(width 0.127)
		(layer "In5.Cu")
		(net "I2C_DRIVE_FLT_LED_SDA6_LS")
	)
	(segment
		(start 121.723404 -86.205314)
		(end 119.178578 -88.75014)
		(width 0.127)
		(layer "In5.Cu")
		(net "I2C_DRIVE_FLT_LED_SDA6_LS")
	)
	(segment
		(start 82.620358 -93.419676)
		(end 75.7174 -86.516718)
		(width 0.127)
		(layer "In5.Cu")
		(net "I2C_DRIVE_FLT_LED_SDA6_LS")
	)
	(segment
		(start 66.572638 -79.730092)
		(end 66.572638 -82.199226)
		(width 0.127)
		(layer "In5.Cu")
		(net "I2C_DRIVE_FLT_LED_SDA6_LS")
	)
	(segment
		(start 75.7174 -82.023966)
		(end 75.526392 -81.832958)
		(width 0.127)
		(layer "In5.Cu")
		(net "I2C_DRIVE_FLT_LED_SDA6_LS")
	)
	(segment
		(start 74.426826 -78.578456)
		(end 67.724274 -78.578456)
		(width 0.127)
		(layer "In5.Cu")
		(net "I2C_DRIVE_FLT_LED_SDA6_LS")
	)
	(segment
		(start 129.8956 -83.947)
		(end 124.65558 -83.947)
		(width 0.127)
		(layer "In5.Cu")
		(net "I2C_DRIVE_FLT_LED_SDA6_LS")
	)
	(segment
		(start 98.11512 -93.419676)
		(end 82.620358 -93.419676)
		(width 0.127)
		(layer "In5.Cu")
		(net "I2C_DRIVE_FLT_LED_SDA6_LS")
	)
	(segment
		(start 131.180332 -82.662268)
		(end 129.8956 -83.947)
		(width 0.127)
		(layer "In5.Cu")
		(net "I2C_DRIVE_FLT_LED_SDA6_LS")
	)
	(segment
		(start 132.649214 -82.662268)
		(end 131.180332 -82.662268)
		(width 0.127)
		(layer "In5.Cu")
		(net "I2C_DRIVE_FLT_LED_SDA6_LS")
	)
	(segment
		(start 124.65558 -83.947)
		(end 122.397266 -86.205314)
		(width 0.127)
		(layer "In5.Cu")
		(net "I2C_DRIVE_FLT_LED_SDA6_LS")
	)
	(segment
		(start 116.053616 -88.75014)
		(end 113.38306 -91.420696)
		(width 0.127)
		(layer "In5.Cu")
		(net "I2C_DRIVE_FLT_LED_SDA6_LS")
	)
	(segment
		(start 113.38306 -91.420696)
		(end 100.1141 -91.420696)
		(width 0.127)
		(layer "In5.Cu")
		(net "I2C_DRIVE_FLT_LED_SDA6_LS")
	)
	(segment
		(start 67.299078 -75.934824)
		(end 67.299078 -74.639678)
		(width 0.127)
		(layer "F.Cu")
		(net "I2C_DRIVE_FLT_LED_SDA6")
	)
	(segment
		(start 66.9036 -74.2442)
		(end 66.4464 -74.2442)
		(width 0.127)
		(layer "F.Cu")
		(net "I2C_DRIVE_FLT_LED_SDA6")
	)
	(segment
		(start 66.04 -73.1393)
		(end 66.04 -74.1172)
		(width 0.127)
		(layer "F.Cu")
		(net "I2C_DRIVE_FLT_LED_SDA6")
	)
	(segment
		(start 67.299078 -74.639678)
		(end 66.9036 -74.2442)
		(width 0.127)
		(layer "F.Cu")
		(net "I2C_DRIVE_FLT_LED_SDA6")
	)
	(segment
		(start 66.7512 -72.4281)
		(end 66.04 -73.1393)
		(width 0.127)
		(layer "F.Cu")
		(net "I2C_DRIVE_FLT_LED_SDA6")
	)
	(segment
		(start 66.04 -74.1172)
		(end 66.167 -74.2442)
		(width 0.127)
		(layer "F.Cu")
		(net "I2C_DRIVE_FLT_LED_SDA6")
	)
	(segment
		(start 66.7512 -70.57009)
		(end 66.7512 -72.4281)
		(width 0.127)
		(layer "F.Cu")
		(net "I2C_DRIVE_FLT_LED_SDA6")
	)
	(segment
		(start 66.167 -74.2442)
		(end 66.4464 -74.2442)
		(width 0.127)
		(layer "F.Cu")
		(net "I2C_DRIVE_FLT_LED_SDA6")
	)
	(via
		(at 66.7512 -70.57009)
		(size 0.508)
		(drill 0.254)
		(layers "F.Cu" "B.Cu")
		(net "I2C_DRIVE_FLT_LED_SDA6")
	)
	(via
		(at 66.4464 -74.2442)
		(size 0.6604)
		(drill 0.3302)
		(layers "F.Cu" "B.Cu")
		(net "I2C_DRIVE_FLT_LED_SDA6")
	)
	(segment
		(start 78.800706 -59.3725)
		(end 78.183232 -59.3725)
		(width 0.127)
		(layer "In2.Cu")
		(net "I2C_DRIVE_FLT_LED_SDA6")
	)
	(segment
		(start 77.292708 -61.959236)
		(end 75.758802 -63.493142)
		(width 0.127)
		(layer "In2.Cu")
		(net "I2C_DRIVE_FLT_LED_SDA6")
	)
	(segment
		(start 70.773798 -69.303392)
		(end 68.017898 -69.303392)
		(width 0.127)
		(layer "In2.Cu")
		(net "I2C_DRIVE_FLT_LED_SDA6")
	)
	(segment
		(start 93.913452 -30.52318)
		(end 88.71839 -30.52318)
		(width 0.127)
		(layer "In2.Cu")
		(net "I2C_DRIVE_FLT_LED_SDA6")
	)
	(segment
		(start 98.65233 -30.52318)
		(end 98.652076 -30.523434)
		(width 0.127)
		(layer "In2.Cu")
		(net "I2C_DRIVE_FLT_LED_SDA6")
	)
	(segment
		(start 82.78876 -47.678848)
		(end 80.049878 -50.41773)
		(width 0.127)
		(layer "In2.Cu")
		(net "I2C_DRIVE_FLT_LED_SDA6")
	)
	(segment
		(start 75.758802 -63.493142)
		(end 75.758802 -65.109852)
		(width 0.127)
		(layer "In2.Cu")
		(net "I2C_DRIVE_FLT_LED_SDA6")
	)
	(segment
		(start 75.758802 -65.109852)
		(end 74.313542 -66.555112)
		(width 0.127)
		(layer "In2.Cu")
		(net "I2C_DRIVE_FLT_LED_SDA6")
	)
	(segment
		(start 74.313542 -66.555112)
		(end 73.522078 -66.555112)
		(width 0.127)
		(layer "In2.Cu")
		(net "I2C_DRIVE_FLT_LED_SDA6")
	)
	(segment
		(start 82.78876 -36.45281)
		(end 82.78876 -47.678848)
		(width 0.127)
		(layer "In2.Cu")
		(net "I2C_DRIVE_FLT_LED_SDA6")
	)
	(segment
		(start 115.424966 -9.424924)
		(end 115.424966 -14.11732)
		(width 0.127)
		(layer "In2.Cu")
		(net "I2C_DRIVE_FLT_LED_SDA6")
	)
	(segment
		(start 99.019106 -30.52318)
		(end 98.65233 -30.52318)
		(width 0.127)
		(layer "In2.Cu")
		(net "I2C_DRIVE_FLT_LED_SDA6")
	)
	(segment
		(start 114.800126 -8.800084)
		(end 115.424966 -9.424924)
		(width 0.127)
		(layer "In2.Cu")
		(net "I2C_DRIVE_FLT_LED_SDA6")
	)
	(segment
		(start 80.049878 -58.123328)
		(end 78.800706 -59.3725)
		(width 0.127)
		(layer "In2.Cu")
		(net "I2C_DRIVE_FLT_LED_SDA6")
	)
	(segment
		(start 98.652076 -30.523434)
		(end 93.913706 -30.523434)
		(width 0.127)
		(layer "In2.Cu")
		(net "I2C_DRIVE_FLT_LED_SDA6")
	)
	(segment
		(start 115.424966 -14.11732)
		(end 99.019106 -30.52318)
		(width 0.127)
		(layer "In2.Cu")
		(net "I2C_DRIVE_FLT_LED_SDA6")
	)
	(segment
		(start 77.292708 -60.263024)
		(end 77.292708 -61.959236)
		(width 0.127)
		(layer "In2.Cu")
		(net "I2C_DRIVE_FLT_LED_SDA6")
	)
	(segment
		(start 68.017898 -69.303392)
		(end 66.7512 -70.57009)
		(width 0.127)
		(layer "In2.Cu")
		(net "I2C_DRIVE_FLT_LED_SDA6")
	)
	(segment
		(start 73.522078 -66.555112)
		(end 70.773798 -69.303392)
		(width 0.127)
		(layer "In2.Cu")
		(net "I2C_DRIVE_FLT_LED_SDA6")
	)
	(segment
		(start 78.183232 -59.3725)
		(end 77.292708 -60.263024)
		(width 0.127)
		(layer "In2.Cu")
		(net "I2C_DRIVE_FLT_LED_SDA6")
	)
	(segment
		(start 93.913706 -30.523434)
		(end 93.913452 -30.52318)
		(width 0.127)
		(layer "In2.Cu")
		(net "I2C_DRIVE_FLT_LED_SDA6")
	)
	(segment
		(start 80.049878 -50.41773)
		(end 80.049878 -58.123328)
		(width 0.127)
		(layer "In2.Cu")
		(net "I2C_DRIVE_FLT_LED_SDA6")
	)
	(segment
		(start 88.71839 -30.52318)
		(end 82.78876 -36.45281)
		(width 0.127)
		(layer "In2.Cu")
		(net "I2C_DRIVE_FLT_LED_SDA6")
	)
	(segment
		(start 67.949318 -80.073754)
		(end 67.40271 -80.620362)
		(width 0.127)
		(layer "F.Cu")
		(net "I2C_DRIVE_FLT_LED_SCL6_LS")
	)
	(segment
		(start 67.40271 -81.445354)
		(end 67.40271 -82.385154)
		(width 0.127)
		(layer "F.Cu")
		(net "I2C_DRIVE_FLT_LED_SCL6_LS")
	)
	(segment
		(start 132.456936 -83.645502)
		(end 131.892802 -83.081368)
		(width 0.127)
		(layer "F.Cu")
		(net "I2C_DRIVE_FLT_LED_SCL6_LS")
	)
	(segment
		(start 131.892802 -83.081368)
		(end 131.488434 -83.081368)
		(width 0.127)
		(layer "F.Cu")
		(net "I2C_DRIVE_FLT_LED_SCL6_LS")
	)
	(segment
		(start 130.048 -81.048098)
		(end 129.500122 -80.50022)
		(width 0.127)
		(layer "F.Cu")
		(net "I2C_DRIVE_FLT_LED_SCL6_LS")
	)
	(segment
		(start 132.850128 -83.645502)
		(end 132.456936 -83.645502)
		(width 0.127)
		(layer "F.Cu")
		(net "I2C_DRIVE_FLT_LED_SCL6_LS")
	)
	(segment
		(start 67.40271 -80.620362)
		(end 67.40271 -81.445354)
		(width 0.127)
		(layer "F.Cu")
		(net "I2C_DRIVE_FLT_LED_SCL6_LS")
	)
	(segment
		(start 67.949318 -79.186024)
		(end 67.949318 -80.073754)
		(width 0.127)
		(layer "F.Cu")
		(net "I2C_DRIVE_FLT_LED_SCL6_LS")
	)
	(segment
		(start 130.048 -81.640934)
		(end 130.048 -81.048098)
		(width 0.127)
		(layer "F.Cu")
		(net "I2C_DRIVE_FLT_LED_SCL6_LS")
	)
	(segment
		(start 134.07771 -84.246466)
		(end 133.451092 -84.246466)
		(width 0.127)
		(layer "F.Cu")
		(net "I2C_DRIVE_FLT_LED_SCL6_LS")
	)
	(segment
		(start 133.451092 -84.246466)
		(end 132.850128 -83.645502)
		(width 0.127)
		(layer "F.Cu")
		(net "I2C_DRIVE_FLT_LED_SCL6_LS")
	)
	(segment
		(start 131.488434 -83.081368)
		(end 130.048 -81.640934)
		(width 0.127)
		(layer "F.Cu")
		(net "I2C_DRIVE_FLT_LED_SCL6_LS")
	)
	(via
		(at 67.40271 -82.385154)
		(size 0.508)
		(drill 0.254)
		(layers "F.Cu" "B.Cu")
		(net "I2C_DRIVE_FLT_LED_SCL6_LS")
	)
	(via
		(at 67.40271 -81.445354)
		(size 0.6604)
		(drill 0.3302)
		(layers "F.Cu" "B.Cu")
		(net "I2C_DRIVE_FLT_LED_SCL6_LS")
	)
	(via
		(at 131.892802 -83.081368)
		(size 0.508)
		(drill 0.254)
		(layers "F.Cu" "B.Cu")
		(net "I2C_DRIVE_FLT_LED_SCL6_LS")
	)
	(segment
		(start 100.293424 -91.959938)
		(end 113.890298 -91.959938)
		(width 0.127)
		(layer "In5.Cu")
		(net "I2C_DRIVE_FLT_LED_SCL6_LS")
	)
	(segment
		(start 75.2094 -86.889082)
		(end 82.247994 -93.927676)
		(width 0.127)
		(layer "In5.Cu")
		(net "I2C_DRIVE_FLT_LED_SCL6_LS")
	)
	(segment
		(start 116.592096 -89.25814)
		(end 119.389144 -89.25814)
		(width 0.127)
		(layer "In5.Cu")
		(net "I2C_DRIVE_FLT_LED_SCL6_LS")
	)
	(segment
		(start 74.196448 -79.163418)
		(end 75.018392 -79.985362)
		(width 0.127)
		(layer "In5.Cu")
		(net "I2C_DRIVE_FLT_LED_SCL6_LS")
	)
	(segment
		(start 67.40271 -82.385154)
		(end 67.080638 -82.063082)
		(width 0.127)
		(layer "In5.Cu")
		(net "I2C_DRIVE_FLT_LED_SCL6_LS")
	)
	(segment
		(start 82.247994 -93.927676)
		(end 98.325686 -93.927676)
		(width 0.127)
		(layer "In5.Cu")
		(net "I2C_DRIVE_FLT_LED_SCL6_LS")
	)
	(segment
		(start 122.752358 -86.961726)
		(end 125.295914 -84.418932)
		(width 0.127)
		(layer "In5.Cu")
		(net "I2C_DRIVE_FLT_LED_SCL6_LS")
	)
	(segment
		(start 75.2094 -82.355182)
		(end 75.2094 -86.889082)
		(width 0.127)
		(layer "In5.Cu")
		(net "I2C_DRIVE_FLT_LED_SCL6_LS")
	)
	(segment
		(start 67.080638 -79.940658)
		(end 67.857878 -79.163418)
		(width 0.127)
		(layer "In5.Cu")
		(net "I2C_DRIVE_FLT_LED_SCL6_LS")
	)
	(segment
		(start 113.890298 -91.959938)
		(end 116.592096 -89.25814)
		(width 0.127)
		(layer "In5.Cu")
		(net "I2C_DRIVE_FLT_LED_SCL6_LS")
	)
	(segment
		(start 75.018392 -79.985362)
		(end 75.018392 -82.164174)
		(width 0.127)
		(layer "In5.Cu")
		(net "I2C_DRIVE_FLT_LED_SCL6_LS")
	)
	(segment
		(start 130.033268 -84.418932)
		(end 131.370832 -83.081368)
		(width 0.127)
		(layer "In5.Cu")
		(net "I2C_DRIVE_FLT_LED_SCL6_LS")
	)
	(segment
		(start 131.370832 -83.081368)
		(end 131.892802 -83.081368)
		(width 0.127)
		(layer "In5.Cu")
		(net "I2C_DRIVE_FLT_LED_SCL6_LS")
	)
	(segment
		(start 125.295914 -84.418932)
		(end 130.033268 -84.418932)
		(width 0.127)
		(layer "In5.Cu")
		(net "I2C_DRIVE_FLT_LED_SCL6_LS")
	)
	(segment
		(start 98.325686 -93.927676)
		(end 100.293424 -91.959938)
		(width 0.127)
		(layer "In5.Cu")
		(net "I2C_DRIVE_FLT_LED_SCL6_LS")
	)
	(segment
		(start 67.080638 -82.063082)
		(end 67.080638 -79.940658)
		(width 0.127)
		(layer "In5.Cu")
		(net "I2C_DRIVE_FLT_LED_SCL6_LS")
	)
	(segment
		(start 67.857878 -79.163418)
		(end 74.196448 -79.163418)
		(width 0.127)
		(layer "In5.Cu")
		(net "I2C_DRIVE_FLT_LED_SCL6_LS")
	)
	(segment
		(start 121.685558 -86.961726)
		(end 122.752358 -86.961726)
		(width 0.127)
		(layer "In5.Cu")
		(net "I2C_DRIVE_FLT_LED_SCL6_LS")
	)
	(segment
		(start 75.018392 -82.164174)
		(end 75.2094 -82.355182)
		(width 0.127)
		(layer "In5.Cu")
		(net "I2C_DRIVE_FLT_LED_SCL6_LS")
	)
	(segment
		(start 119.389144 -89.25814)
		(end 121.685558 -86.961726)
		(width 0.127)
		(layer "In5.Cu")
		(net "I2C_DRIVE_FLT_LED_SCL6_LS")
	)
	(segment
		(start 67.949318 -75.934824)
		(end 67.949318 -74.477118)
		(width 0.127)
		(layer "F.Cu")
		(net "I2C_DRIVE_FLT_LED_SCL6")
	)
	(segment
		(start 67.7164 -74.2442)
		(end 67.9704 -73.9902)
		(width 0.127)
		(layer "F.Cu")
		(net "I2C_DRIVE_FLT_LED_SCL6")
	)
	(segment
		(start 67.949318 -74.477118)
		(end 67.7164 -74.2442)
		(width 0.127)
		(layer "F.Cu")
		(net "I2C_DRIVE_FLT_LED_SCL6")
	)
	(segment
		(start 67.4751 -73.1393)
		(end 67.9704 -73.1393)
		(width 0.127)
		(layer "F.Cu")
		(net "I2C_DRIVE_FLT_LED_SCL6")
	)
	(segment
		(start 67.9704 -73.9902)
		(end 67.9704 -73.1393)
		(width 0.127)
		(layer "F.Cu")
		(net "I2C_DRIVE_FLT_LED_SCL6")
	)
	(segment
		(start 67.2719 -71.299832)
		(end 67.2719 -72.9361)
		(width 0.127)
		(layer "F.Cu")
		(net "I2C_DRIVE_FLT_LED_SCL6")
	)
	(segment
		(start 67.667124 -70.57009)
		(end 67.667124 -70.904608)
		(width 0.127)
		(layer "F.Cu")
		(net "I2C_DRIVE_FLT_LED_SCL6")
	)
	(segment
		(start 67.667124 -70.904608)
		(end 67.2719 -71.299832)
		(width 0.127)
		(layer "F.Cu")
		(net "I2C_DRIVE_FLT_LED_SCL6")
	)
	(segment
		(start 67.2719 -72.9361)
		(end 67.4751 -73.1393)
		(width 0.127)
		(layer "F.Cu")
		(net "I2C_DRIVE_FLT_LED_SCL6")
	)
	(via
		(at 67.667124 -70.57009)
		(size 0.508)
		(drill 0.254)
		(layers "F.Cu" "B.Cu")
		(net "I2C_DRIVE_FLT_LED_SCL6")
	)
	(via
		(at 67.7164 -74.2442)
		(size 0.6604)
		(drill 0.3302)
		(layers "F.Cu" "B.Cu")
		(net "I2C_DRIVE_FLT_LED_SCL6")
	)
	(segment
		(start 78.21422 -60.81141)
		(end 78.733396 -60.81141)
		(width 0.127)
		(layer "In2.Cu")
		(net "I2C_DRIVE_FLT_LED_SCL6")
	)
	(segment
		(start 67.667124 -70.57009)
		(end 68.425822 -69.811392)
		(width 0.127)
		(layer "In2.Cu")
		(net "I2C_DRIVE_FLT_LED_SCL6")
	)
	(segment
		(start 73.732644 -67.063112)
		(end 74.524108 -67.063112)
		(width 0.127)
		(layer "In2.Cu")
		(net "I2C_DRIVE_FLT_LED_SCL6")
	)
	(segment
		(start 99.229418 -31.031434)
		(end 115.932966 -14.327886)
		(width 0.127)
		(layer "In2.Cu")
		(net "I2C_DRIVE_FLT_LED_SCL6")
	)
	(segment
		(start 68.425822 -69.811392)
		(end 70.984364 -69.811392)
		(width 0.127)
		(layer "In2.Cu")
		(net "I2C_DRIVE_FLT_LED_SCL6")
	)
	(segment
		(start 115.932966 -14.327886)
		(end 115.932966 -8.532876)
		(width 0.127)
		(layer "In2.Cu")
		(net "I2C_DRIVE_FLT_LED_SCL6")
	)
	(segment
		(start 115.932966 -8.532876)
		(end 114.800126 -7.400036)
		(width 0.127)
		(layer "In2.Cu")
		(net "I2C_DRIVE_FLT_LED_SCL6")
	)
	(segment
		(start 74.524108 -67.063112)
		(end 76.267056 -65.320164)
		(width 0.127)
		(layer "In2.Cu")
		(net "I2C_DRIVE_FLT_LED_SCL6")
	)
	(segment
		(start 83.29676 -47.889414)
		(end 83.29676 -36.663376)
		(width 0.127)
		(layer "In2.Cu")
		(net "I2C_DRIVE_FLT_LED_SCL6")
	)
	(segment
		(start 80.557878 -50.628296)
		(end 83.29676 -47.889414)
		(width 0.127)
		(layer "In2.Cu")
		(net "I2C_DRIVE_FLT_LED_SCL6")
	)
	(segment
		(start 76.267056 -64.154812)
		(end 77.800962 -62.620906)
		(width 0.127)
		(layer "In2.Cu")
		(net "I2C_DRIVE_FLT_LED_SCL6")
	)
	(segment
		(start 80.557878 -58.986928)
		(end 80.557878 -50.628296)
		(width 0.127)
		(layer "In2.Cu")
		(net "I2C_DRIVE_FLT_LED_SCL6")
	)
	(segment
		(start 76.267056 -65.320164)
		(end 76.267056 -64.154812)
		(width 0.127)
		(layer "In2.Cu")
		(net "I2C_DRIVE_FLT_LED_SCL6")
	)
	(segment
		(start 83.29676 -36.663376)
		(end 88.928956 -31.03118)
		(width 0.127)
		(layer "In2.Cu")
		(net "I2C_DRIVE_FLT_LED_SCL6")
	)
	(segment
		(start 70.984364 -69.811392)
		(end 73.732644 -67.063112)
		(width 0.127)
		(layer "In2.Cu")
		(net "I2C_DRIVE_FLT_LED_SCL6")
	)
	(segment
		(start 93.702886 -31.03118)
		(end 93.70314 -31.031434)
		(width 0.127)
		(layer "In2.Cu")
		(net "I2C_DRIVE_FLT_LED_SCL6")
	)
	(segment
		(start 78.733396 -60.81141)
		(end 80.557878 -58.986928)
		(width 0.127)
		(layer "In2.Cu")
		(net "I2C_DRIVE_FLT_LED_SCL6")
	)
	(segment
		(start 93.70314 -31.031434)
		(end 99.229418 -31.031434)
		(width 0.127)
		(layer "In2.Cu")
		(net "I2C_DRIVE_FLT_LED_SCL6")
	)
	(segment
		(start 77.800962 -61.224668)
		(end 78.21422 -60.81141)
		(width 0.127)
		(layer "In2.Cu")
		(net "I2C_DRIVE_FLT_LED_SCL6")
	)
	(segment
		(start 88.928956 -31.03118)
		(end 93.702886 -31.03118)
		(width 0.127)
		(layer "In2.Cu")
		(net "I2C_DRIVE_FLT_LED_SCL6")
	)
	(segment
		(start 77.800962 -62.620906)
		(end 77.800962 -61.224668)
		(width 0.127)
		(layer "In2.Cu")
		(net "I2C_DRIVE_FLT_LED_SCL6")
	)
	(segment
		(start 14.51483 -87.377778)
		(end 14.51483 -86.793578)
		(width 0.127)
		(layer "F.Cu")
		(net "I2C_DPB_SDA3_LS")
	)
	(segment
		(start 14.51483 -86.793578)
		(end 14.827504 -86.480904)
		(width 0.127)
		(layer "F.Cu")
		(net "I2C_DPB_SDA3_LS")
	)
	(segment
		(start 15.83055 -85.81263)
		(end 15.83055 -84.853272)
		(width 0.127)
		(layer "F.Cu")
		(net "I2C_DPB_SDA3_LS")
	)
	(segment
		(start 15.579344 -86.480904)
		(end 15.83055 -86.229698)
		(width 0.127)
		(layer "F.Cu")
		(net "I2C_DPB_SDA3_LS")
	)
	(segment
		(start 14.827504 -86.480904)
		(end 15.579344 -86.480904)
		(width 0.127)
		(layer "F.Cu")
		(net "I2C_DPB_SDA3_LS")
	)
	(segment
		(start 15.83055 -86.229698)
		(end 15.83055 -85.81263)
		(width 0.127)
		(layer "F.Cu")
		(net "I2C_DPB_SDA3_LS")
	)
	(segment
		(start 123.500134 -76.500228)
		(end 124.000006 -77.0001)
		(width 0.127)
		(layer "F.Cu")
		(net "I2C_DPB_SDA3_LS")
	)
	(via
		(at 128.7018 -93.296486)
		(size 0.508)
		(drill 0.254)
		(layers "F.Cu" "B.Cu")
		(net "I2C_DPB_SDA3_LS")
	)
	(via
		(at 15.83055 -84.853272)
		(size 0.508)
		(drill 0.254)
		(layers "F.Cu" "B.Cu")
		(net "I2C_DPB_SDA3_LS")
	)
	(via
		(at 15.83055 -85.81263)
		(size 0.6604)
		(drill 0.3302)
		(layers "F.Cu" "B.Cu")
		(net "I2C_DPB_SDA3_LS")
	)
	(via
		(at 124.000006 -77.0001)
		(size 0.4572)
		(drill 0.2032)
		(layers "F.Cu" "B.Cu")
		(net "I2C_DPB_SDA3_LS")
	)
	(segment
		(start 130.08864 -92.724986)
		(end 131.699 -91.114626)
		(width 0.127)
		(layer "B.Cu")
		(net "I2C_DPB_SDA3_LS")
	)
	(segment
		(start 129.2733 -92.724986)
		(end 130.08864 -92.724986)
		(width 0.127)
		(layer "B.Cu")
		(net "I2C_DPB_SDA3_LS")
	)
	(segment
		(start 131.699 -91.114626)
		(end 131.699 -90.3605)
		(width 0.127)
		(layer "B.Cu")
		(net "I2C_DPB_SDA3_LS")
	)
	(segment
		(start 128.7018 -93.296486)
		(end 129.2733 -92.724986)
		(width 0.127)
		(layer "B.Cu")
		(net "I2C_DPB_SDA3_LS")
	)
	(segment
		(start 126.393702 -78.836774)
		(end 126.163324 -78.606396)
		(width 0.127)
		(layer "In2.Cu")
		(net "I2C_DPB_SDA3_LS")
	)
	(segment
		(start 126.049278 -78.606396)
		(end 125.606302 -78.16342)
		(width 0.127)
		(layer "In2.Cu")
		(net "I2C_DPB_SDA3_LS")
	)
	(segment
		(start 127.5969 -90.732102)
		(end 129.302002 -89.027)
		(width 0.127)
		(layer "In2.Cu")
		(net "I2C_DPB_SDA3_LS")
	)
	(segment
		(start 125.606302 -78.16342)
		(end 125.606302 -78.049374)
		(width 0.127)
		(layer "In2.Cu")
		(net "I2C_DPB_SDA3_LS")
	)
	(segment
		(start 128.232916 -93.296486)
		(end 127.5969 -92.66047)
		(width 0.127)
		(layer "In2.Cu")
		(net "I2C_DPB_SDA3_LS")
	)
	(segment
		(start 130.083052 -87.45982)
		(end 128.8415 -86.218268)
		(width 0.127)
		(layer "In2.Cu")
		(net "I2C_DPB_SDA3_LS")
	)
	(segment
		(start 126.163324 -78.606396)
		(end 126.049278 -78.606396)
		(width 0.127)
		(layer "In2.Cu")
		(net "I2C_DPB_SDA3_LS")
	)
	(segment
		(start 127.7493 -84.1375)
		(end 127.7493 -82.6643)
		(width 0.127)
		(layer "In2.Cu")
		(net "I2C_DPB_SDA3_LS")
	)
	(segment
		(start 127.5969 -92.66047)
		(end 127.5969 -90.732102)
		(width 0.127)
		(layer "In2.Cu")
		(net "I2C_DPB_SDA3_LS")
	)
	(segment
		(start 125.606302 -78.049374)
		(end 125.163326 -77.606398)
		(width 0.127)
		(layer "In2.Cu")
		(net "I2C_DPB_SDA3_LS")
	)
	(segment
		(start 130.083052 -88.729566)
		(end 130.083052 -87.45982)
		(width 0.127)
		(layer "In2.Cu")
		(net "I2C_DPB_SDA3_LS")
	)
	(segment
		(start 125.163326 -77.606398)
		(end 124.606304 -77.606398)
		(width 0.127)
		(layer "In2.Cu")
		(net "I2C_DPB_SDA3_LS")
	)
	(segment
		(start 128.8415 -85.2297)
		(end 127.7493 -84.1375)
		(width 0.127)
		(layer "In2.Cu")
		(net "I2C_DPB_SDA3_LS")
	)
	(segment
		(start 128.8415 -86.218268)
		(end 128.8415 -85.2297)
		(width 0.127)
		(layer "In2.Cu")
		(net "I2C_DPB_SDA3_LS")
	)
	(segment
		(start 127.7493 -82.6643)
		(end 126.393702 -81.308702)
		(width 0.127)
		(layer "In2.Cu")
		(net "I2C_DPB_SDA3_LS")
	)
	(segment
		(start 128.7018 -93.296486)
		(end 128.232916 -93.296486)
		(width 0.127)
		(layer "In2.Cu")
		(net "I2C_DPB_SDA3_LS")
	)
	(segment
		(start 129.785618 -89.027)
		(end 130.083052 -88.729566)
		(width 0.127)
		(layer "In2.Cu")
		(net "I2C_DPB_SDA3_LS")
	)
	(segment
		(start 129.302002 -89.027)
		(end 129.785618 -89.027)
		(width 0.127)
		(layer "In2.Cu")
		(net "I2C_DPB_SDA3_LS")
	)
	(segment
		(start 126.393702 -81.308702)
		(end 126.393702 -78.836774)
		(width 0.127)
		(layer "In2.Cu")
		(net "I2C_DPB_SDA3_LS")
	)
	(segment
		(start 124.606304 -77.606398)
		(end 124.000006 -77.0001)
		(width 0.127)
		(layer "In2.Cu")
		(net "I2C_DPB_SDA3_LS")
	)
	(segment
		(start 19.94281 -96.092518)
		(end 15.83055 -91.980258)
		(width 0.127)
		(layer "In5.Cu")
		(net "I2C_DPB_SDA3_LS")
	)
	(segment
		(start 19.94281 -101.723444)
		(end 19.94281 -96.092518)
		(width 0.127)
		(layer "In5.Cu")
		(net "I2C_DPB_SDA3_LS")
	)
	(segment
		(start 123.801632 -98.563938)
		(end 103.090218 -98.563938)
		(width 0.127)
		(layer "In5.Cu")
		(net "I2C_DPB_SDA3_LS")
	)
	(segment
		(start 126.255018 -96.71939)
		(end 125.64618 -96.71939)
		(width 0.127)
		(layer "In5.Cu")
		(net "I2C_DPB_SDA3_LS")
	)
	(segment
		(start 125.64618 -96.71939)
		(end 123.801632 -98.563938)
		(width 0.127)
		(layer "In5.Cu")
		(net "I2C_DPB_SDA3_LS")
	)
	(segment
		(start 78.977744 -106.172)
		(end 62.933326 -122.216418)
		(width 0.127)
		(layer "In5.Cu")
		(net "I2C_DPB_SDA3_LS")
	)
	(segment
		(start 103.090218 -98.563938)
		(end 95.482156 -106.172)
		(width 0.127)
		(layer "In5.Cu")
		(net "I2C_DPB_SDA3_LS")
	)
	(segment
		(start 62.933326 -122.216418)
		(end 40.435784 -122.216418)
		(width 0.127)
		(layer "In5.Cu")
		(net "I2C_DPB_SDA3_LS")
	)
	(segment
		(start 95.482156 -106.172)
		(end 78.977744 -106.172)
		(width 0.127)
		(layer "In5.Cu")
		(net "I2C_DPB_SDA3_LS")
	)
	(segment
		(start 128.7018 -94.272608)
		(end 126.255018 -96.71939)
		(width 0.127)
		(layer "In5.Cu")
		(net "I2C_DPB_SDA3_LS")
	)
	(segment
		(start 128.7018 -93.296486)
		(end 128.7018 -94.272608)
		(width 0.127)
		(layer "In5.Cu")
		(net "I2C_DPB_SDA3_LS")
	)
	(segment
		(start 40.435784 -122.216418)
		(end 19.94281 -101.723444)
		(width 0.127)
		(layer "In5.Cu")
		(net "I2C_DPB_SDA3_LS")
	)
	(segment
		(start 15.83055 -91.980258)
		(end 15.83055 -84.853272)
		(width 0.127)
		(layer "In5.Cu")
		(net "I2C_DPB_SDA3_LS")
	)
	(segment
		(start 15.8496 -96.7486)
		(end 15.5702 -96.4692)
		(width 0.127)
		(layer "F.Cu")
		(net "I2C_DPB_SDA3")
	)
	(segment
		(start 27.91714 -96.7486)
		(end 20.140168 -96.7486)
		(width 0.127)
		(layer "F.Cu")
		(net "I2C_DPB_SDA3")
	)
	(segment
		(start 20.140168 -96.7486)
		(end 15.8496 -96.7486)
		(width 0.127)
		(layer "F.Cu")
		(net "I2C_DPB_SDA3")
	)
	(segment
		(start 14.51483 -90.628978)
		(end 14.51483 -91.618562)
		(width 0.127)
		(layer "F.Cu")
		(net "I2C_DPB_SDA3")
	)
	(segment
		(start 14.876018 -92.663518)
		(end 15.3416 -93.1291)
		(width 0.127)
		(layer "F.Cu")
		(net "I2C_DPB_SDA3")
	)
	(segment
		(start 14.876018 -91.97975)
		(end 14.876018 -92.663518)
		(width 0.127)
		(layer "F.Cu")
		(net "I2C_DPB_SDA3")
	)
	(segment
		(start 28.453842 -97.285302)
		(end 27.91714 -96.7486)
		(width 0.127)
		(layer "F.Cu")
		(net "I2C_DPB_SDA3")
	)
	(segment
		(start 15.5702 -95.7326)
		(end 16.0782 -95.2246)
		(width 0.127)
		(layer "F.Cu")
		(net "I2C_DPB_SDA3")
	)
	(segment
		(start 14.51483 -91.618562)
		(end 14.876018 -91.97975)
		(width 0.127)
		(layer "F.Cu")
		(net "I2C_DPB_SDA3")
	)
	(segment
		(start 15.5702 -96.4692)
		(end 15.5702 -95.7326)
		(width 0.127)
		(layer "F.Cu")
		(net "I2C_DPB_SDA3")
	)
	(segment
		(start 16.0782 -93.8657)
		(end 15.3416 -93.1291)
		(width 0.127)
		(layer "F.Cu")
		(net "I2C_DPB_SDA3")
	)
	(segment
		(start 16.0782 -95.2246)
		(end 16.0782 -93.8657)
		(width 0.127)
		(layer "F.Cu")
		(net "I2C_DPB_SDA3")
	)
	(via
		(at 28.453842 -97.285302)
		(size 0.508)
		(drill 0.254)
		(layers "F.Cu" "B.Cu")
		(net "I2C_DPB_SDA3")
	)
	(via
		(at 20.140168 -96.7486)
		(size 0.6604)
		(drill 0.3302)
		(layers "F.Cu" "B.Cu")
		(net "I2C_DPB_SDA3")
	)
	(via
		(at 52.996592 -83.426808)
		(size 0.508)
		(drill 0.254)
		(layers "F.Cu" "B.Cu")
		(net "I2C_DPB_SDA3")
	)
	(segment
		(start 84.382102 -27.47518)
		(end 95.176848 -27.47518)
		(width 0.127)
		(layer "In2.Cu")
		(net "I2C_DPB_SDA3")
	)
	(segment
		(start 79.395574 -32.635952)
		(end 81.426304 -30.605222)
		(width 0.127)
		(layer "In2.Cu")
		(net "I2C_DPB_SDA3")
	)
	(segment
		(start 54.7116 -77.589634)
		(end 54.7116 -70.600316)
		(width 0.127)
		(layer "In2.Cu")
		(net "I2C_DPB_SDA3")
	)
	(segment
		(start 66.553842 -66.255392)
		(end 68.386706 -66.255392)
		(width 0.127)
		(layer "In2.Cu")
		(net "I2C_DPB_SDA3")
	)
	(segment
		(start 77.440028 -37.496496)
		(end 79.395574 -35.54095)
		(width 0.127)
		(layer "In2.Cu")
		(net "I2C_DPB_SDA3")
	)
	(segment
		(start 56.48706 -68.824856)
		(end 63.984378 -68.824856)
		(width 0.127)
		(layer "In2.Cu")
		(net "I2C_DPB_SDA3")
	)
	(segment
		(start 81.809844 -30.605222)
		(end 82.772504 -29.642562)
		(width 0.127)
		(layer "In2.Cu")
		(net "I2C_DPB_SDA3")
	)
	(segment
		(start 77.440028 -45.112686)
		(end 77.440028 -37.496496)
		(width 0.127)
		(layer "In2.Cu")
		(net "I2C_DPB_SDA3")
	)
	(segment
		(start 96.22917 -27.475434)
		(end 108.363004 -15.3416)
		(width 0.127)
		(layer "In2.Cu")
		(net "I2C_DPB_SDA3")
	)
	(segment
		(start 110.02264 -8.222742)
		(end 109.400086 -7.600188)
		(width 0.127)
		(layer "In2.Cu")
		(net "I2C_DPB_SDA3")
	)
	(segment
		(start 108.363004 -15.3416)
		(end 108.363258 -15.3416)
		(width 0.127)
		(layer "In2.Cu")
		(net "I2C_DPB_SDA3")
	)
	(segment
		(start 63.984378 -68.824856)
		(end 66.553842 -66.255392)
		(width 0.127)
		(layer "In2.Cu")
		(net "I2C_DPB_SDA3")
	)
	(segment
		(start 109.441488 -14.26337)
		(end 109.441488 -14.263116)
		(width 0.127)
		(layer "In2.Cu")
		(net "I2C_DPB_SDA3")
	)
	(segment
		(start 52.996592 -79.304642)
		(end 54.7116 -77.589634)
		(width 0.127)
		(layer "In2.Cu")
		(net "I2C_DPB_SDA3")
	)
	(segment
		(start 72.995536 -57.65673)
		(end 75.858878 -54.793388)
		(width 0.127)
		(layer "In2.Cu")
		(net "I2C_DPB_SDA3")
	)
	(segment
		(start 82.772504 -29.642562)
		(end 82.772504 -29.084778)
		(width 0.127)
		(layer "In2.Cu")
		(net "I2C_DPB_SDA3")
	)
	(segment
		(start 110.02264 -13.681964)
		(end 110.02264 -11.274552)
		(width 0.127)
		(layer "In2.Cu")
		(net "I2C_DPB_SDA3")
	)
	(segment
		(start 82.772504 -29.084778)
		(end 84.382102 -27.47518)
		(width 0.127)
		(layer "In2.Cu")
		(net "I2C_DPB_SDA3")
	)
	(segment
		(start 81.426304 -30.605222)
		(end 81.809844 -30.605222)
		(width 0.127)
		(layer "In2.Cu")
		(net "I2C_DPB_SDA3")
	)
	(segment
		(start 95.176848 -27.47518)
		(end 95.177102 -27.475434)
		(width 0.127)
		(layer "In2.Cu")
		(net "I2C_DPB_SDA3")
	)
	(segment
		(start 75.858878 -54.793388)
		(end 75.858878 -46.693836)
		(width 0.127)
		(layer "In2.Cu")
		(net "I2C_DPB_SDA3")
	)
	(segment
		(start 110.024926 -9.73836)
		(end 110.02264 -9.726676)
		(width 0.127)
		(layer "In2.Cu")
		(net "I2C_DPB_SDA3")
	)
	(segment
		(start 68.386706 -66.255392)
		(end 72.995536 -61.646562)
		(width 0.127)
		(layer "In2.Cu")
		(net "I2C_DPB_SDA3")
	)
	(segment
		(start 54.7116 -70.600316)
		(end 56.48706 -68.824856)
		(width 0.127)
		(layer "In2.Cu")
		(net "I2C_DPB_SDA3")
	)
	(segment
		(start 72.995536 -61.646562)
		(end 72.995536 -57.65673)
		(width 0.127)
		(layer "In2.Cu")
		(net "I2C_DPB_SDA3")
	)
	(segment
		(start 109.441488 -14.263116)
		(end 110.02264 -13.681964)
		(width 0.127)
		(layer "In2.Cu")
		(net "I2C_DPB_SDA3")
	)
	(segment
		(start 110.02264 -9.726676)
		(end 110.02264 -8.222742)
		(width 0.127)
		(layer "In2.Cu")
		(net "I2C_DPB_SDA3")
	)
	(segment
		(start 110.024926 -11.226546)
		(end 110.024926 -9.73836)
		(width 0.127)
		(layer "In2.Cu")
		(net "I2C_DPB_SDA3")
	)
	(segment
		(start 52.996592 -83.426808)
		(end 52.996592 -79.304642)
		(width 0.127)
		(layer "In2.Cu")
		(net "I2C_DPB_SDA3")
	)
	(segment
		(start 75.858878 -46.693836)
		(end 77.440028 -45.112686)
		(width 0.127)
		(layer "In2.Cu")
		(net "I2C_DPB_SDA3")
	)
	(segment
		(start 110.024672 -11.264392)
		(end 110.024926 -11.226546)
		(width 0.127)
		(layer "In2.Cu")
		(net "I2C_DPB_SDA3")
	)
	(segment
		(start 95.177102 -27.475434)
		(end 96.22917 -27.475434)
		(width 0.127)
		(layer "In2.Cu")
		(net "I2C_DPB_SDA3")
	)
	(segment
		(start 108.363258 -15.3416)
		(end 109.441488 -14.26337)
		(width 0.127)
		(layer "In2.Cu")
		(net "I2C_DPB_SDA3")
	)
	(segment
		(start 110.02264 -11.274552)
		(end 110.024672 -11.264392)
		(width 0.127)
		(layer "In2.Cu")
		(net "I2C_DPB_SDA3")
	)
	(segment
		(start 79.395574 -35.54095)
		(end 79.395574 -32.635952)
		(width 0.127)
		(layer "In2.Cu")
		(net "I2C_DPB_SDA3")
	)
	(segment
		(start 52.996592 -94.919038)
		(end 46.859444 -101.056186)
		(width 0.127)
		(layer "In5.Cu")
		(net "I2C_DPB_SDA3")
	)
	(segment
		(start 52.996592 -83.426808)
		(end 52.996592 -94.919038)
		(width 0.127)
		(layer "In5.Cu")
		(net "I2C_DPB_SDA3")
	)
	(segment
		(start 46.859444 -101.056186)
		(end 32.224726 -101.056186)
		(width 0.127)
		(layer "In5.Cu")
		(net "I2C_DPB_SDA3")
	)
	(segment
		(start 32.224726 -101.056186)
		(end 28.453842 -97.285302)
		(width 0.127)
		(layer "In5.Cu")
		(net "I2C_DPB_SDA3")
	)
	(segment
		(start 122.500136 -73.500234)
		(end 122.000264 -73.000362)
		(width 0.127)
		(layer "F.Cu")
		(net "I2C_DPB_SCL3_LS")
	)
	(segment
		(start 14.9606 -84.88172)
		(end 14.9606 -85.33638)
		(width 0.127)
		(layer "F.Cu")
		(net "I2C_DPB_SCL3_LS")
	)
	(segment
		(start 13.86459 -87.377778)
		(end 13.86459 -86.43239)
		(width 0.127)
		(layer "F.Cu")
		(net "I2C_DPB_SCL3_LS")
	)
	(segment
		(start 14.9606 -85.33638)
		(end 14.56055 -85.73643)
		(width 0.127)
		(layer "F.Cu")
		(net "I2C_DPB_SCL3_LS")
	)
	(segment
		(start 13.86459 -86.43239)
		(end 14.56055 -85.73643)
		(width 0.127)
		(layer "F.Cu")
		(net "I2C_DPB_SCL3_LS")
	)
	(via
		(at 14.56055 -85.73643)
		(size 0.6604)
		(drill 0.3302)
		(layers "F.Cu" "B.Cu")
		(net "I2C_DPB_SCL3_LS")
	)
	(via
		(at 122.000264 -73.000362)
		(size 0.4572)
		(drill 0.2032)
		(layers "F.Cu" "B.Cu")
		(net "I2C_DPB_SCL3_LS")
	)
	(via
		(at 14.9606 -84.88172)
		(size 0.508)
		(drill 0.254)
		(layers "F.Cu" "B.Cu")
		(net "I2C_DPB_SCL3_LS")
	)
	(via
		(at 129.7178 -93.296486)
		(size 0.508)
		(drill 0.254)
		(layers "F.Cu" "B.Cu")
		(net "I2C_DPB_SCL3_LS")
	)
	(segment
		(start 132.715 -90.943684)
		(end 132.715 -90.3605)
		(width 0.127)
		(layer "B.Cu")
		(net "I2C_DPB_SCL3_LS")
	)
	(segment
		(start 129.7178 -93.296486)
		(end 130.362198 -93.296486)
		(width 0.127)
		(layer "B.Cu")
		(net "I2C_DPB_SCL3_LS")
	)
	(segment
		(start 130.362198 -93.296486)
		(end 132.715 -90.943684)
		(width 0.127)
		(layer "B.Cu")
		(net "I2C_DPB_SCL3_LS")
	)
	(segment
		(start 126.6063 -78.163674)
		(end 126.6063 -78.049374)
		(width 0.127)
		(layer "In2.Cu")
		(net "I2C_DPB_SCL3_LS")
	)
	(segment
		(start 127.445262 -81.585562)
		(end 127.445262 -78.88859)
		(width 0.127)
		(layer "In2.Cu")
		(net "I2C_DPB_SCL3_LS")
	)
	(segment
		(start 130.034284 -89.4969)
		(end 130.27787 -89.4969)
		(width 0.127)
		(layer "In2.Cu")
		(net "I2C_DPB_SCL3_LS")
	)
	(segment
		(start 123.4694 -75.8444)
		(end 123.0376 -75.4126)
		(width 0.127)
		(layer "In2.Cu")
		(net "I2C_DPB_SCL3_LS")
	)
	(segment
		(start 129.996184 -89.535)
		(end 130.034284 -89.4969)
		(width 0.127)
		(layer "In2.Cu")
		(net "I2C_DPB_SCL3_LS")
	)
	(segment
		(start 126.146306 -77.58938)
		(end 125.99289 -77.58938)
		(width 0.127)
		(layer "In2.Cu")
		(net "I2C_DPB_SCL3_LS")
	)
	(segment
		(start 129.7178 -93.296486)
		(end 129.1844 -92.763086)
		(width 0.127)
		(layer "In2.Cu")
		(net "I2C_DPB_SCL3_LS")
	)
	(segment
		(start 128.1049 -90.942668)
		(end 129.512568 -89.535)
		(width 0.127)
		(layer "In2.Cu")
		(net "I2C_DPB_SCL3_LS")
	)
	(segment
		(start 128.418082 -92.763086)
		(end 128.1049 -92.449904)
		(width 0.127)
		(layer "In2.Cu")
		(net "I2C_DPB_SCL3_LS")
	)
	(segment
		(start 125.4252 -77.02169)
		(end 125.4252 -76.868274)
		(width 0.127)
		(layer "In2.Cu")
		(net "I2C_DPB_SCL3_LS")
	)
	(segment
		(start 127.445262 -78.88859)
		(end 126.95047 -78.393798)
		(width 0.127)
		(layer "In2.Cu")
		(net "I2C_DPB_SCL3_LS")
	)
	(segment
		(start 129.1844 -92.763086)
		(end 128.418082 -92.763086)
		(width 0.127)
		(layer "In2.Cu")
		(net "I2C_DPB_SCL3_LS")
	)
	(segment
		(start 129.3495 -84.963)
		(end 128.2573 -83.8708)
		(width 0.127)
		(layer "In2.Cu")
		(net "I2C_DPB_SCL3_LS")
	)
	(segment
		(start 125.99289 -77.58938)
		(end 125.4252 -77.02169)
		(width 0.127)
		(layer "In2.Cu")
		(net "I2C_DPB_SCL3_LS")
	)
	(segment
		(start 125.074426 -76.5175)
		(end 123.7107 -76.5175)
		(width 0.127)
		(layer "In2.Cu")
		(net "I2C_DPB_SCL3_LS")
	)
	(segment
		(start 126.95047 -78.393798)
		(end 126.836424 -78.393798)
		(width 0.127)
		(layer "In2.Cu")
		(net "I2C_DPB_SCL3_LS")
	)
	(segment
		(start 129.512568 -89.535)
		(end 129.996184 -89.535)
		(width 0.127)
		(layer "In2.Cu")
		(net "I2C_DPB_SCL3_LS")
	)
	(segment
		(start 123.0376 -75.4126)
		(end 122.834908 -75.4126)
		(width 0.127)
		(layer "In2.Cu")
		(net "I2C_DPB_SCL3_LS")
	)
	(segment
		(start 129.3495 -86.007702)
		(end 129.3495 -84.963)
		(width 0.127)
		(layer "In2.Cu")
		(net "I2C_DPB_SCL3_LS")
	)
	(segment
		(start 123.7107 -76.5175)
		(end 123.4694 -76.2762)
		(width 0.127)
		(layer "In2.Cu")
		(net "I2C_DPB_SCL3_LS")
	)
	(segment
		(start 128.2573 -83.8708)
		(end 128.2573 -82.3976)
		(width 0.127)
		(layer "In2.Cu")
		(net "I2C_DPB_SCL3_LS")
	)
	(segment
		(start 126.6063 -78.049374)
		(end 126.146306 -77.58938)
		(width 0.127)
		(layer "In2.Cu")
		(net "I2C_DPB_SCL3_LS")
	)
	(segment
		(start 122.606308 -75.184)
		(end 122.606308 -73.606406)
		(width 0.127)
		(layer "In2.Cu")
		(net "I2C_DPB_SCL3_LS")
	)
	(segment
		(start 131.060952 -87.719154)
		(end 129.3495 -86.007702)
		(width 0.127)
		(layer "In2.Cu")
		(net "I2C_DPB_SCL3_LS")
	)
	(segment
		(start 131.060952 -88.713818)
		(end 131.060952 -87.719154)
		(width 0.127)
		(layer "In2.Cu")
		(net "I2C_DPB_SCL3_LS")
	)
	(segment
		(start 128.2573 -82.3976)
		(end 127.445262 -81.585562)
		(width 0.127)
		(layer "In2.Cu")
		(net "I2C_DPB_SCL3_LS")
	)
	(segment
		(start 123.4694 -76.2762)
		(end 123.4694 -75.8444)
		(width 0.127)
		(layer "In2.Cu")
		(net "I2C_DPB_SCL3_LS")
	)
	(segment
		(start 125.4252 -76.868274)
		(end 125.074426 -76.5175)
		(width 0.127)
		(layer "In2.Cu")
		(net "I2C_DPB_SCL3_LS")
	)
	(segment
		(start 128.1049 -92.449904)
		(end 128.1049 -90.942668)
		(width 0.127)
		(layer "In2.Cu")
		(net "I2C_DPB_SCL3_LS")
	)
	(segment
		(start 122.606308 -73.606406)
		(end 122.000264 -73.000362)
		(width 0.127)
		(layer "In2.Cu")
		(net "I2C_DPB_SCL3_LS")
	)
	(segment
		(start 122.834908 -75.4126)
		(end 122.606308 -75.184)
		(width 0.127)
		(layer "In2.Cu")
		(net "I2C_DPB_SCL3_LS")
	)
	(segment
		(start 126.836424 -78.393798)
		(end 126.6063 -78.163674)
		(width 0.127)
		(layer "In2.Cu")
		(net "I2C_DPB_SCL3_LS")
	)
	(segment
		(start 130.27787 -89.4969)
		(end 131.060952 -88.713818)
		(width 0.127)
		(layer "In2.Cu")
		(net "I2C_DPB_SCL3_LS")
	)
	(segment
		(start 103.300784 -99.071938)
		(end 94.968822 -107.4039)
		(width 0.127)
		(layer "In5.Cu")
		(net "I2C_DPB_SCL3_LS")
	)
	(segment
		(start 124.012198 -99.071938)
		(end 103.300784 -99.071938)
		(width 0.127)
		(layer "In5.Cu")
		(net "I2C_DPB_SCL3_LS")
	)
	(segment
		(start 40.074596 -122.724418)
		(end 19.3802 -102.030022)
		(width 0.127)
		(layer "In5.Cu")
		(net "I2C_DPB_SCL3_LS")
	)
	(segment
		(start 78.840584 -107.4039)
		(end 63.520066 -122.724418)
		(width 0.127)
		(layer "In5.Cu")
		(net "I2C_DPB_SCL3_LS")
	)
	(segment
		(start 129.7178 -93.975174)
		(end 126.364746 -97.328228)
		(width 0.127)
		(layer "In5.Cu")
		(net "I2C_DPB_SCL3_LS")
	)
	(segment
		(start 129.7178 -93.296486)
		(end 129.7178 -93.975174)
		(width 0.127)
		(layer "In5.Cu")
		(net "I2C_DPB_SCL3_LS")
	)
	(segment
		(start 94.968822 -107.4039)
		(end 78.840584 -107.4039)
		(width 0.127)
		(layer "In5.Cu")
		(net "I2C_DPB_SCL3_LS")
	)
	(segment
		(start 19.3802 -96.266254)
		(end 15.1384 -92.024454)
		(width 0.127)
		(layer "In5.Cu")
		(net "I2C_DPB_SCL3_LS")
	)
	(segment
		(start 63.520066 -122.724418)
		(end 40.074596 -122.724418)
		(width 0.127)
		(layer "In5.Cu")
		(net "I2C_DPB_SCL3_LS")
	)
	(segment
		(start 15.1384 -85.05952)
		(end 14.9606 -84.88172)
		(width 0.127)
		(layer "In5.Cu")
		(net "I2C_DPB_SCL3_LS")
	)
	(segment
		(start 15.1384 -92.024454)
		(end 15.1384 -85.05952)
		(width 0.127)
		(layer "In5.Cu")
		(net "I2C_DPB_SCL3_LS")
	)
	(segment
		(start 126.364746 -97.328228)
		(end 125.755908 -97.328228)
		(width 0.127)
		(layer "In5.Cu")
		(net "I2C_DPB_SCL3_LS")
	)
	(segment
		(start 19.3802 -102.030022)
		(end 19.3802 -96.266254)
		(width 0.127)
		(layer "In5.Cu")
		(net "I2C_DPB_SCL3_LS")
	)
	(segment
		(start 125.755908 -97.328228)
		(end 124.012198 -99.071938)
		(width 0.127)
		(layer "In5.Cu")
		(net "I2C_DPB_SCL3_LS")
	)
	(segment
		(start 13.799566 -91.62796)
		(end 13.799566 -93.009466)
		(width 0.127)
		(layer "F.Cu")
		(net "I2C_DPB_SCL3")
	)
	(segment
		(start 13.86459 -90.628978)
		(end 13.86459 -91.562936)
		(width 0.127)
		(layer "F.Cu")
		(net "I2C_DPB_SCL3")
	)
	(segment
		(start 13.86459 -91.562936)
		(end 13.799566 -91.62796)
		(width 0.127)
		(layer "F.Cu")
		(net "I2C_DPB_SCL3")
	)
	(segment
		(start 18.378424 -97.3836)
		(end 27.104086 -97.3836)
		(width 0.127)
		(layer "F.Cu")
		(net "I2C_DPB_SCL3")
	)
	(segment
		(start 15.766034 -97.3836)
		(end 18.378424 -97.3836)
		(width 0.127)
		(layer "F.Cu")
		(net "I2C_DPB_SCL3")
	)
	(segment
		(start 14.6431 -93.853)
		(end 14.6431 -95.3389)
		(width 0.127)
		(layer "F.Cu")
		(net "I2C_DPB_SCL3")
	)
	(segment
		(start 15.0622 -96.679766)
		(end 15.766034 -97.3836)
		(width 0.127)
		(layer "F.Cu")
		(net "I2C_DPB_SCL3")
	)
	(segment
		(start 15.0622 -95.758)
		(end 15.0622 -96.679766)
		(width 0.127)
		(layer "F.Cu")
		(net "I2C_DPB_SCL3")
	)
	(segment
		(start 13.799566 -93.009466)
		(end 13.9192 -93.1291)
		(width 0.127)
		(layer "F.Cu")
		(net "I2C_DPB_SCL3")
	)
	(segment
		(start 13.9192 -93.1291)
		(end 14.6431 -93.853)
		(width 0.127)
		(layer "F.Cu")
		(net "I2C_DPB_SCL3")
	)
	(segment
		(start 14.6431 -95.3389)
		(end 15.0622 -95.758)
		(width 0.127)
		(layer "F.Cu")
		(net "I2C_DPB_SCL3")
	)
	(via
		(at 18.378424 -97.3836)
		(size 0.6604)
		(drill 0.3302)
		(layers "F.Cu" "B.Cu")
		(net "I2C_DPB_SCL3")
	)
	(via
		(at 53.898292 -83.392264)
		(size 0.508)
		(drill 0.254)
		(layers "F.Cu" "B.Cu")
		(net "I2C_DPB_SCL3")
	)
	(via
		(at 27.104086 -97.3836)
		(size 0.508)
		(drill 0.254)
		(layers "F.Cu" "B.Cu")
		(net "I2C_DPB_SCL3")
	)
	(segment
		(start 73.503536 -61.857128)
		(end 73.503536 -57.867296)
		(width 0.127)
		(layer "In2.Cu")
		(net "I2C_DPB_SCL3")
	)
	(segment
		(start 96.439736 -27.983434)
		(end 108.57357 -15.8496)
		(width 0.127)
		(layer "In2.Cu")
		(net "I2C_DPB_SCL3")
	)
	(segment
		(start 56.697626 -69.332856)
		(end 64.194944 -69.332856)
		(width 0.127)
		(layer "In2.Cu")
		(net "I2C_DPB_SCL3")
	)
	(segment
		(start 85.467444 -27.98318)
		(end 94.966282 -27.98318)
		(width 0.127)
		(layer "In2.Cu")
		(net "I2C_DPB_SCL3")
	)
	(segment
		(start 109.949488 -14.473936)
		(end 109.949488 -14.473682)
		(width 0.127)
		(layer "In2.Cu")
		(net "I2C_DPB_SCL3")
	)
	(segment
		(start 94.966536 -27.983434)
		(end 96.439736 -27.983434)
		(width 0.127)
		(layer "In2.Cu")
		(net "I2C_DPB_SCL3")
	)
	(segment
		(start 110.532926 -9.689084)
		(end 110.53064 -9.6774)
		(width 0.127)
		(layer "In2.Cu")
		(net "I2C_DPB_SCL3")
	)
	(segment
		(start 94.966282 -27.98318)
		(end 94.966536 -27.983434)
		(width 0.127)
		(layer "In2.Cu")
		(net "I2C_DPB_SCL3")
	)
	(segment
		(start 110.53064 -13.471398)
		(end 110.53064 -11.325098)
		(width 0.127)
		(layer "In2.Cu")
		(net "I2C_DPB_SCL3")
	)
	(segment
		(start 78.745334 -45.661072)
		(end 79.903574 -44.502832)
		(width 0.127)
		(layer "In2.Cu")
		(net "I2C_DPB_SCL3")
	)
	(segment
		(start 110.53064 -7.330694)
		(end 109.400086 -6.20014)
		(width 0.127)
		(layer "In2.Cu")
		(net "I2C_DPB_SCL3")
	)
	(segment
		(start 108.573824 -15.8496)
		(end 109.949488 -14.473936)
		(width 0.127)
		(layer "In2.Cu")
		(net "I2C_DPB_SCL3")
	)
	(segment
		(start 73.503536 -57.867296)
		(end 76.366878 -55.003954)
		(width 0.127)
		(layer "In2.Cu")
		(net "I2C_DPB_SCL3")
	)
	(segment
		(start 76.366878 -47.615602)
		(end 78.321408 -45.661072)
		(width 0.127)
		(layer "In2.Cu")
		(net "I2C_DPB_SCL3")
	)
	(segment
		(start 108.57357 -15.8496)
		(end 108.573824 -15.8496)
		(width 0.127)
		(layer "In2.Cu")
		(net "I2C_DPB_SCL3")
	)
	(segment
		(start 109.949488 -14.473682)
		(end 110.530894 -13.892276)
		(width 0.127)
		(layer "In2.Cu")
		(net "I2C_DPB_SCL3")
	)
	(segment
		(start 64.194944 -69.332856)
		(end 66.764408 -66.763392)
		(width 0.127)
		(layer "In2.Cu")
		(net "I2C_DPB_SCL3")
	)
	(segment
		(start 53.898292 -79.197708)
		(end 55.2196 -77.8764)
		(width 0.127)
		(layer "In2.Cu")
		(net "I2C_DPB_SCL3")
	)
	(segment
		(start 110.530894 -13.892276)
		(end 110.530894 -13.471652)
		(width 0.127)
		(layer "In2.Cu")
		(net "I2C_DPB_SCL3")
	)
	(segment
		(start 110.53064 -11.325098)
		(end 110.532418 -11.316462)
		(width 0.127)
		(layer "In2.Cu")
		(net "I2C_DPB_SCL3")
	)
	(segment
		(start 79.903574 -33.54705)
		(end 85.467444 -27.98318)
		(width 0.127)
		(layer "In2.Cu")
		(net "I2C_DPB_SCL3")
	)
	(segment
		(start 110.53064 -9.6774)
		(end 110.53064 -7.330694)
		(width 0.127)
		(layer "In2.Cu")
		(net "I2C_DPB_SCL3")
	)
	(segment
		(start 76.366878 -55.003954)
		(end 76.366878 -47.615602)
		(width 0.127)
		(layer "In2.Cu")
		(net "I2C_DPB_SCL3")
	)
	(segment
		(start 78.321408 -45.661072)
		(end 78.745334 -45.661072)
		(width 0.127)
		(layer "In2.Cu")
		(net "I2C_DPB_SCL3")
	)
	(segment
		(start 55.2196 -70.810882)
		(end 56.697626 -69.332856)
		(width 0.127)
		(layer "In2.Cu")
		(net "I2C_DPB_SCL3")
	)
	(segment
		(start 110.530894 -13.471652)
		(end 110.53064 -13.471398)
		(width 0.127)
		(layer "In2.Cu")
		(net "I2C_DPB_SCL3")
	)
	(segment
		(start 53.898292 -83.392264)
		(end 53.898292 -79.197708)
		(width 0.127)
		(layer "In2.Cu")
		(net "I2C_DPB_SCL3")
	)
	(segment
		(start 66.764408 -66.763392)
		(end 68.597272 -66.763392)
		(width 0.127)
		(layer "In2.Cu")
		(net "I2C_DPB_SCL3")
	)
	(segment
		(start 110.532926 -11.228324)
		(end 110.532926 -9.689084)
		(width 0.127)
		(layer "In2.Cu")
		(net "I2C_DPB_SCL3")
	)
	(segment
		(start 68.597272 -66.763392)
		(end 73.503536 -61.857128)
		(width 0.127)
		(layer "In2.Cu")
		(net "I2C_DPB_SCL3")
	)
	(segment
		(start 110.532418 -11.316462)
		(end 110.532926 -11.228324)
		(width 0.127)
		(layer "In2.Cu")
		(net "I2C_DPB_SCL3")
	)
	(segment
		(start 55.2196 -77.8764)
		(end 55.2196 -70.810882)
		(width 0.127)
		(layer "In2.Cu")
		(net "I2C_DPB_SCL3")
	)
	(segment
		(start 79.903574 -44.502832)
		(end 79.903574 -33.54705)
		(width 0.127)
		(layer "In2.Cu")
		(net "I2C_DPB_SCL3")
	)
	(segment
		(start 47.031656 -102.135686)
		(end 32.342582 -102.135686)
		(width 0.127)
		(layer "In5.Cu")
		(net "I2C_DPB_SCL3")
	)
	(segment
		(start 27.590496 -97.3836)
		(end 27.104086 -97.3836)
		(width 0.127)
		(layer "In5.Cu")
		(net "I2C_DPB_SCL3")
	)
	(segment
		(start 53.898292 -83.392264)
		(end 53.898292 -95.26905)
		(width 0.127)
		(layer "In5.Cu")
		(net "I2C_DPB_SCL3")
	)
	(segment
		(start 53.898292 -95.26905)
		(end 47.031656 -102.135686)
		(width 0.127)
		(layer "In5.Cu")
		(net "I2C_DPB_SCL3")
	)
	(segment
		(start 32.342582 -102.135686)
		(end 27.590496 -97.3836)
		(width 0.127)
		(layer "In5.Cu")
		(net "I2C_DPB_SCL3")
	)
	(segment
		(start 6.7564 -70.8533)
		(end 7.7978 -70.8533)
		(width 0.127)
		(layer "F.Cu")
		(net "FRU_EEPROM_A2")
	)
	(segment
		(start 10.795 -71.6788)
		(end 9.398 -71.6788)
		(width 0.127)
		(layer "F.Cu")
		(net "FRU_EEPROM_A2")
	)
	(segment
		(start 9.398 -71.6788)
		(end 9.0424 -71.3232)
		(width 0.127)
		(layer "F.Cu")
		(net "FRU_EEPROM_A2")
	)
	(segment
		(start 7.7978 -70.8533)
		(end 8.5725 -70.8533)
		(width 0.127)
		(layer "F.Cu")
		(net "FRU_EEPROM_A2")
	)
	(segment
		(start 8.5725 -70.8533)
		(end 9.0424 -71.3232)
		(width 0.127)
		(layer "F.Cu")
		(net "FRU_EEPROM_A2")
	)
	(via
		(at 9.0424 -71.3232)
		(size 0.6604)
		(drill 0.3302)
		(layers "F.Cu" "B.Cu")
		(net "FRU_EEPROM_A2")
	)
	(segment
		(start 10.795 -72.9488)
		(end 9.0932 -72.9488)
		(width 0.127)
		(layer "F.Cu")
		(net "FRU_EEPROM_A1")
	)
	(segment
		(start 7.7343 -71.9328)
		(end 7.7343 -73.0758)
		(width 0.127)
		(layer "F.Cu")
		(net "FRU_EEPROM_A1")
	)
	(segment
		(start 8.8646 -73.0758)
		(end 9.0424 -72.898)
		(width 0.127)
		(layer "F.Cu")
		(net "FRU_EEPROM_A1")
	)
	(segment
		(start 9.0932 -72.9488)
		(end 9.0424 -72.898)
		(width 0.127)
		(layer "F.Cu")
		(net "FRU_EEPROM_A1")
	)
	(segment
		(start 7.7343 -73.0758)
		(end 8.8646 -73.0758)
		(width 0.127)
		(layer "F.Cu")
		(net "FRU_EEPROM_A1")
	)
	(via
		(at 9.0424 -72.898)
		(size 0.6604)
		(drill 0.3302)
		(layers "F.Cu" "B.Cu")
		(net "FRU_EEPROM_A1")
	)
	(segment
		(start 7.7343 -74.2188)
		(end 8.9662 -74.2188)
		(width 0.127)
		(layer "F.Cu")
		(net "FRU_EEPROM_A0")
	)
	(segment
		(start 9.144 -74.1934)
		(end 9.0424 -74.295)
		(width 0.127)
		(layer "F.Cu")
		(net "FRU_EEPROM_A0")
	)
	(segment
		(start 7.7343 -75.3618)
		(end 7.7343 -74.2188)
		(width 0.127)
		(layer "F.Cu")
		(net "FRU_EEPROM_A0")
	)
	(segment
		(start 8.9662 -74.2188)
		(end 9.0424 -74.295)
		(width 0.127)
		(layer "F.Cu")
		(net "FRU_EEPROM_A0")
	)
	(segment
		(start 10.795 -74.2188)
		(end 10.7696 -74.1934)
		(width 0.127)
		(layer "F.Cu")
		(net "FRU_EEPROM_A0")
	)
	(segment
		(start 10.7696 -74.1934)
		(end 9.144 -74.1934)
		(width 0.127)
		(layer "F.Cu")
		(net "FRU_EEPROM_A0")
	)
	(via
		(at 9.0424 -74.295)
		(size 0.6604)
		(drill 0.3302)
		(layers "F.Cu" "B.Cu")
		(net "FRU_EEPROM_A0")
	)
	(segment
		(start 116.500148 -75.50023)
		(end 117.00002 -76.000102)
		(width 0.127)
		(layer "F.Cu")
		(net "COMP_EXP_SPARE_1_R_LS")
	)
	(via
		(at 117.516402 -82.104992)
		(size 0.6096)
		(drill 0.3048)
		(layers "F.Cu" "B.Cu")
		(net "COMP_EXP_SPARE_1_R_LS")
	)
	(via
		(at 117.00002 -76.000102)
		(size 0.4572)
		(drill 0.2032)
		(layers "F.Cu" "B.Cu")
		(net "COMP_EXP_SPARE_1_R_LS")
	)
	(segment
		(start 118.056406 -83.076542)
		(end 118.056406 -85.136228)
		(width 0.127)
		(layer "B.Cu")
		(net "COMP_EXP_SPARE_1_R_LS")
	)
	(segment
		(start 118.475252 -85.555074)
		(end 118.475252 -86.153752)
		(width 0.127)
		(layer "B.Cu")
		(net "COMP_EXP_SPARE_1_R_LS")
	)
	(segment
		(start 117.516402 -76.927964)
		(end 117.00002 -76.411582)
		(width 0.127)
		(layer "B.Cu")
		(net "COMP_EXP_SPARE_1_R_LS")
	)
	(segment
		(start 117.516402 -82.104992)
		(end 117.516402 -82.536538)
		(width 0.127)
		(layer "B.Cu")
		(net "COMP_EXP_SPARE_1_R_LS")
	)
	(segment
		(start 117.00002 -76.411582)
		(end 117.00002 -76.000102)
		(width 0.127)
		(layer "B.Cu")
		(net "COMP_EXP_SPARE_1_R_LS")
	)
	(segment
		(start 117.516402 -82.104992)
		(end 117.516402 -76.927964)
		(width 0.127)
		(layer "B.Cu")
		(net "COMP_EXP_SPARE_1_R_LS")
	)
	(segment
		(start 117.516402 -82.536538)
		(end 118.056406 -83.076542)
		(width 0.127)
		(layer "B.Cu")
		(net "COMP_EXP_SPARE_1_R_LS")
	)
	(segment
		(start 118.056406 -85.136228)
		(end 118.475252 -85.555074)
		(width 0.127)
		(layer "B.Cu")
		(net "COMP_EXP_SPARE_1_R_LS")
	)
	(segment
		(start 118.475252 -86.153752)
		(end 118.872 -86.5505)
		(width 0.127)
		(layer "B.Cu")
		(net "COMP_EXP_SPARE_1_R_LS")
	)
	(segment
		(start 123.515374 -87.964518)
		(end 123.515374 -88.505792)
		(width 0.127)
		(layer "F.Cu")
		(net "BMC_EXP_SPARE_1_R_LS")
	)
	(segment
		(start 121.996708 -89.6112)
		(end 121.487692 -90.120216)
		(width 0.127)
		(layer "F.Cu")
		(net "BMC_EXP_SPARE_1_R_LS")
	)
	(segment
		(start 120.50014 -82.607404)
		(end 121.774458 -83.881722)
		(width 0.127)
		(layer "F.Cu")
		(net "BMC_EXP_SPARE_1_R_LS")
	)
	(segment
		(start 120.50014 -82.500216)
		(end 120.50014 -82.607404)
		(width 0.127)
		(layer "F.Cu")
		(net "BMC_EXP_SPARE_1_R_LS")
	)
	(segment
		(start 123.515374 -84.739988)
		(end 123.515374 -87.964518)
		(width 0.127)
		(layer "F.Cu")
		(net "BMC_EXP_SPARE_1_R_LS")
	)
	(segment
		(start 121.774458 -83.881722)
		(end 122.657108 -83.881722)
		(width 0.127)
		(layer "F.Cu")
		(net "BMC_EXP_SPARE_1_R_LS")
	)
	(segment
		(start 122.657108 -83.881722)
		(end 123.515374 -84.739988)
		(width 0.127)
		(layer "F.Cu")
		(net "BMC_EXP_SPARE_1_R_LS")
	)
	(segment
		(start 122.409966 -89.6112)
		(end 121.996708 -89.6112)
		(width 0.127)
		(layer "F.Cu")
		(net "BMC_EXP_SPARE_1_R_LS")
	)
	(segment
		(start 123.515374 -88.505792)
		(end 122.409966 -89.6112)
		(width 0.127)
		(layer "F.Cu")
		(net "BMC_EXP_SPARE_1_R_LS")
	)
	(via
		(at 123.515374 -87.964518)
		(size 0.6604)
		(drill 0.3302)
		(layers "F.Cu" "B.Cu")
		(net "BMC_EXP_SPARE_1_R_LS")
	)
	(segment
		(start 119.500142 -77.500226)
		(end 120.000014 -78.000098)
		(width 0.127)
		(layer "F.Cu")
		(net "BMC_EXP_SPARE_0_R_LS")
	)
	(via
		(at 120.44934 -80.515968)
		(size 0.6096)
		(drill 0.3048)
		(layers "F.Cu" "B.Cu")
		(net "BMC_EXP_SPARE_0_R_LS")
	)
	(via
		(at 120.000014 -78.000098)
		(size 0.4572)
		(drill 0.2032)
		(layers "F.Cu" "B.Cu")
		(net "BMC_EXP_SPARE_0_R_LS")
	)
	(segment
		(start 120.5992 -78.599284)
		(end 120.000014 -78.000098)
		(width 0.127)
		(layer "B.Cu")
		(net "BMC_EXP_SPARE_0_R_LS")
	)
	(segment
		(start 122.207528 -84.598256)
		(end 123.665742 -86.05647)
		(width 0.127)
		(layer "B.Cu")
		(net "BMC_EXP_SPARE_0_R_LS")
	)
	(segment
		(start 120.44934 -80.515968)
		(end 120.44934 -81.087214)
		(width 0.127)
		(layer "B.Cu")
		(net "BMC_EXP_SPARE_0_R_LS")
	)
	(segment
		(start 120.44934 -81.087214)
		(end 120.774714 -81.412588)
		(width 0.127)
		(layer "B.Cu")
		(net "BMC_EXP_SPARE_0_R_LS")
	)
	(segment
		(start 122.207528 -84.159344)
		(end 122.207528 -84.598256)
		(width 0.127)
		(layer "B.Cu")
		(net "BMC_EXP_SPARE_0_R_LS")
	)
	(segment
		(start 120.774714 -82.72653)
		(end 122.207528 -84.159344)
		(width 0.127)
		(layer "B.Cu")
		(net "BMC_EXP_SPARE_0_R_LS")
	)
	(segment
		(start 120.44934 -80.515968)
		(end 120.44934 -80.020668)
		(width 0.127)
		(layer "B.Cu")
		(net "BMC_EXP_SPARE_0_R_LS")
	)
	(segment
		(start 120.44934 -80.020668)
		(end 120.5992 -79.870808)
		(width 0.127)
		(layer "B.Cu")
		(net "BMC_EXP_SPARE_0_R_LS")
	)
	(segment
		(start 123.665742 -86.05647)
		(end 123.665742 -88.114124)
		(width 0.127)
		(layer "B.Cu")
		(net "BMC_EXP_SPARE_0_R_LS")
	)
	(segment
		(start 120.5992 -79.870808)
		(end 120.5992 -78.599284)
		(width 0.127)
		(layer "B.Cu")
		(net "BMC_EXP_SPARE_0_R_LS")
	)
	(segment
		(start 120.774714 -81.412588)
		(end 120.774714 -82.72653)
		(width 0.127)
		(layer "B.Cu")
		(net "BMC_EXP_SPARE_0_R_LS")
	)
	(segment
		(start 15.1892 -49.1998)
		(end 15.1892 -47.9806)
		(width 0.508)
		(layer "F.Cu")
		(net "MB0_VCC")
	)
	(segment
		(start 15.1892 -49.5046)
		(end 14.694662 -49.999138)
		(width 0.3048)
		(layer "F.Cu")
		(net "MB0_VCC")
	)
	(segment
		(start 16.2814 -47.7139)
		(end 15.4559 -47.7139)
		(width 0.508)
		(layer "F.Cu")
		(net "MB0_VCC")
	)
	(segment
		(start 15.4559 -47.7139)
		(end 15.1892 -47.9806)
		(width 0.508)
		(layer "F.Cu")
		(net "MB0_VCC")
	)
	(segment
		(start 15.1892 -49.1998)
		(end 15.1892 -49.5046)
		(width 0.3048)
		(layer "F.Cu")
		(net "MB0_VCC")
	)
	(segment
		(start 14.694662 -49.999138)
		(end 14.694662 -50.7873)
		(width 0.3048)
		(layer "F.Cu")
		(net "MB0_VCC")
	)
	(via
		(at 15.1892 -49.1998)
		(size 0.6604)
		(drill 0.3302)
		(layers "F.Cu" "B.Cu")
		(net "MB0_VCC")
	)
	(segment
		(start 22.2377 -54.3052)
		(end 23.4188 -54.3052)
		(width 0.508)
		(layer "F.Cu")
		(net "MB0_VCAP_R")
	)
	(segment
		(start 23.4188 -54.3052)
		(end 23.4442 -54.3306)
		(width 0.508)
		(layer "F.Cu")
		(net "MB0_VCAP_R")
	)
	(segment
		(start 22.6187 -49.5046)
		(end 23.4442 -49.5046)
		(width 0.508)
		(layer "F.Cu")
		(net "MB0_VCAP_R")
	)
	(segment
		(start 20.0152 -52.2986)
		(end 20.6502 -52.2986)
		(width 0.508)
		(layer "F.Cu")
		(net "MB0_VCAP_R")
	)
	(segment
		(start 23.4442 -54.3306)
		(end 24.0284 -54.9148)
		(width 0.508)
		(layer "F.Cu")
		(net "MB0_VCAP_R")
	)
	(segment
		(start 18.3134 -51.4096)
		(end 18.3642 -51.4096)
		(width 0.3048)
		(layer "F.Cu")
		(net "MB0_VCAP_R")
	)
	(segment
		(start 16.4211 -52.013866)
		(end 17.709134 -52.013866)
		(width 0.3048)
		(layer "F.Cu")
		(net "MB0_VCAP_R")
	)
	(segment
		(start 21.0312 -51.9176)
		(end 20.5232 -51.4096)
		(width 0.508)
		(layer "F.Cu")
		(net "MB0_VCAP_R")
	)
	(segment
		(start 20.5232 -51.4096)
		(end 19.431 -51.4096)
		(width 0.508)
		(layer "F.Cu")
		(net "MB0_VCAP_R")
	)
	(segment
		(start 24.0284 -57.2643)
		(end 23.5966 -57.6961)
		(width 0.508)
		(layer "F.Cu")
		(net "MB0_VCAP_R")
	)
	(segment
		(start 17.709134 -52.013866)
		(end 18.3134 -51.4096)
		(width 0.3048)
		(layer "F.Cu")
		(net "MB0_VCAP_R")
	)
	(segment
		(start 18.3642 -51.4096)
		(end 19.431 -51.4096)
		(width 0.508)
		(layer "F.Cu")
		(net "MB0_VCAP_R")
	)
	(segment
		(start 24.0284 -54.9148)
		(end 24.0284 -57.2643)
		(width 0.508)
		(layer "F.Cu")
		(net "MB0_VCAP_R")
	)
	(segment
		(start 23.5966 -57.6961)
		(end 23.1902 -57.6961)
		(width 0.508)
		(layer "F.Cu")
		(net "MB0_VCAP_R")
	)
	(segment
		(start 20.6502 -52.2986)
		(end 21.0312 -51.9176)
		(width 0.508)
		(layer "F.Cu")
		(net "MB0_VCAP_R")
	)
	(via
		(at 23.4442 -54.3306)
		(size 0.508)
		(drill 0.254)
		(layers "F.Cu" "B.Cu")
		(net "MB0_VCAP_R")
	)
	(via
		(at 19.431 -51.4096)
		(size 0.6604)
		(drill 0.3302)
		(layers "F.Cu" "B.Cu")
		(net "MB0_VCAP_R")
	)
	(via
		(at 20.0152 -52.2986)
		(size 0.508)
		(drill 0.254)
		(layers "F.Cu" "B.Cu")
		(net "MB0_VCAP_R")
	)
	(via
		(at 23.4442 -49.5046)
		(size 0.508)
		(drill 0.254)
		(layers "F.Cu" "B.Cu")
		(net "MB0_VCAP_R")
	)
	(segment
		(start 19.96948 -52.34432)
		(end 19.96948 -53.41112)
		(width 0.508)
		(layer "B.Cu")
		(net "MB0_VCAP_R")
	)
	(segment
		(start 20.0152 -50.718974)
		(end 20.0152 -52.2986)
		(width 0.508)
		(layer "B.Cu")
		(net "MB0_VCAP_R")
	)
	(segment
		(start 20.0152 -52.2986)
		(end 19.96948 -52.34432)
		(width 0.508)
		(layer "B.Cu")
		(net "MB0_VCAP_R")
	)
	(segment
		(start 23.4442 -49.5046)
		(end 21.229574 -49.5046)
		(width 0.508)
		(layer "B.Cu")
		(net "MB0_VCAP_R")
	)
	(segment
		(start 21.229574 -49.5046)
		(end 20.0152 -50.718974)
		(width 0.508)
		(layer "B.Cu")
		(net "MB0_VCAP_R")
	)
	(segment
		(start 19.96948 -53.41112)
		(end 20.88896 -54.3306)
		(width 0.508)
		(layer "B.Cu")
		(net "MB0_VCAP_R")
	)
	(segment
		(start 20.88896 -54.3306)
		(end 23.4442 -54.3306)
		(width 0.508)
		(layer "B.Cu")
		(net "MB0_VCAP_R")
	)
	(segment
		(start 16.988536 -53.513736)
		(end 18.2499 -54.7751)
		(width 0.254)
		(layer "F.Cu")
		(net "MB0_TIME_R")
	)
	(segment
		(start 16.4211 -53.513736)
		(end 16.988536 -53.513736)
		(width 0.254)
		(layer "F.Cu")
		(net "MB0_TIME_R")
	)
	(segment
		(start 18.2499 -56.134)
		(end 18.2499 -54.8894)
		(width 0.254)
		(layer "F.Cu")
		(net "MB0_TIME_R")
	)
	(segment
		(start 18.2499 -54.7751)
		(end 18.2499 -54.8894)
		(width 0.254)
		(layer "F.Cu")
		(net "MB0_TIME_R")
	)
	(via
		(at 18.2499 -54.8894)
		(size 0.6604)
		(drill 0.3302)
		(layers "F.Cu" "B.Cu")
		(net "MB0_TIME_R")
	)
	(segment
		(start 9.194546 -48.771302)
		(end 9.216644 -48.7934)
		(width 0.254)
		(layer "F.Cu")
		(net "MB0_TEMP")
	)
	(segment
		(start 12.19454 -50.49774)
		(end 12.19454 -50.7111)
		(width 0.254)
		(layer "F.Cu")
		(net "MB0_TEMP")
	)
	(segment
		(start 9.216644 -48.7934)
		(end 10.2616 -48.7934)
		(width 0.254)
		(layer "F.Cu")
		(net "MB0_TEMP")
	)
	(segment
		(start 10.4902 -48.7934)
		(end 12.19454 -50.49774)
		(width 0.254)
		(layer "F.Cu")
		(net "MB0_TEMP")
	)
	(segment
		(start 9.24687 -48.064674)
		(end 9.24687 -47.692818)
		(width 0.254)
		(layer "F.Cu")
		(net "MB0_TEMP")
	)
	(segment
		(start 9.194546 -48.116998)
		(end 9.24687 -48.064674)
		(width 0.254)
		(layer "F.Cu")
		(net "MB0_TEMP")
	)
	(segment
		(start 10.2616 -48.7934)
		(end 10.4902 -48.7934)
		(width 0.254)
		(layer "F.Cu")
		(net "MB0_TEMP")
	)
	(segment
		(start 9.194546 -48.653192)
		(end 9.194546 -48.116998)
		(width 0.254)
		(layer "F.Cu")
		(net "MB0_TEMP")
	)
	(segment
		(start 9.194546 -48.653192)
		(end 9.194546 -48.771302)
		(width 0.254)
		(layer "F.Cu")
		(net "MB0_TEMP")
	)
	(via
		(at 10.2616 -48.7934)
		(size 0.6604)
		(drill 0.3302)
		(layers "F.Cu" "B.Cu")
		(net "MB0_TEMP")
	)
	(segment
		(start 15.69466 -57.102502)
		(end 16.054324 -57.462166)
		(width 0.254)
		(layer "F.Cu")
		(net "MB0_SPISS_PD")
	)
	(segment
		(start 16.637 -58.6867)
		(end 16.637 -58.044842)
		(width 0.254)
		(layer "F.Cu")
		(net "MB0_SPISS_PD")
	)
	(segment
		(start 16.637 -58.044842)
		(end 16.054324 -57.462166)
		(width 0.254)
		(layer "F.Cu")
		(net "MB0_SPISS_PD")
	)
	(segment
		(start 15.69466 -55.8165)
		(end 15.69466 -57.102502)
		(width 0.254)
		(layer "F.Cu")
		(net "MB0_SPISS_PD")
	)
	(via
		(at 16.054324 -57.462166)
		(size 0.6604)
		(drill 0.3302)
		(layers "F.Cu" "B.Cu")
		(net "MB0_SPISS_PD")
	)
	(segment
		(start 10.291318 -55.774082)
		(end 11.05154 -55.01386)
		(width 0.254)
		(layer "F.Cu")
		(net "MB0_RETRY_R")
	)
	(segment
		(start 9.6139 -56.7563)
		(end 9.8679 -56.5023)
		(width 0.254)
		(layer "F.Cu")
		(net "MB0_RETRY_R")
	)
	(segment
		(start 10.291318 -56.078882)
		(end 10.291318 -55.774082)
		(width 0.254)
		(layer "F.Cu")
		(net "MB0_RETRY_R")
	)
	(segment
		(start 11.05154 -55.01386)
		(end 11.3919 -55.01386)
		(width 0.254)
		(layer "F.Cu")
		(net "MB0_RETRY_R")
	)
	(segment
		(start 8.5598 -56.7563)
		(end 9.6139 -56.7563)
		(width 0.254)
		(layer "F.Cu")
		(net "MB0_RETRY_R")
	)
	(segment
		(start 9.8679 -56.5023)
		(end 10.291318 -56.078882)
		(width 0.254)
		(layer "F.Cu")
		(net "MB0_RETRY_R")
	)
	(via
		(at 9.8679 -56.5023)
		(size 0.6604)
		(drill 0.3302)
		(layers "F.Cu" "B.Cu")
		(net "MB0_RETRY_R")
	)
	(segment
		(start 18.7452 -50.6222)
		(end 18.03654 -50.6222)
		(width 0.254)
		(layer "F.Cu")
		(net "MB0_PSET_R")
	)
	(segment
		(start 18.03654 -50.6222)
		(end 17.145 -51.51374)
		(width 0.254)
		(layer "F.Cu")
		(net "MB0_PSET_R")
	)
	(segment
		(start 17.145 -51.51374)
		(end 16.4973 -51.51374)
		(width 0.254)
		(layer "F.Cu")
		(net "MB0_PSET_R")
	)
	(segment
		(start 19.6596 -50.038)
		(end 19.3294 -50.038)
		(width 0.254)
		(layer "F.Cu")
		(net "MB0_PSET_R")
	)
	(segment
		(start 21.0312 -50.6476)
		(end 20.2692 -50.6476)
		(width 0.254)
		(layer "F.Cu")
		(net "MB0_PSET_R")
	)
	(segment
		(start 21.7297 -48.4886)
		(end 21.7297 -49.5046)
		(width 0.254)
		(layer "F.Cu")
		(net "MB0_PSET_R")
	)
	(segment
		(start 20.2692 -50.6476)
		(end 19.6596 -50.038)
		(width 0.254)
		(layer "F.Cu")
		(net "MB0_PSET_R")
	)
	(segment
		(start 21.7297 -49.5046)
		(end 21.7297 -49.9491)
		(width 0.254)
		(layer "F.Cu")
		(net "MB0_PSET_R")
	)
	(segment
		(start 21.7297 -49.9491)
		(end 21.0312 -50.6476)
		(width 0.254)
		(layer "F.Cu")
		(net "MB0_PSET_R")
	)
	(segment
		(start 19.3294 -50.038)
		(end 18.7452 -50.6222)
		(width 0.254)
		(layer "F.Cu")
		(net "MB0_PSET_R")
	)
	(via
		(at 19.3294 -50.038)
		(size 0.6604)
		(drill 0.3302)
		(layers "F.Cu" "B.Cu")
		(net "MB0_PSET_R")
	)
	(segment
		(start 9.365234 -52.6796)
		(end 8.9408 -52.6796)
		(width 0.254)
		(layer "F.Cu")
		(net "MB0_P12V_PWGIN_R")
	)
	(segment
		(start 8.9408 -52.6796)
		(end 8.177276 -52.6796)
		(width 0.254)
		(layer "F.Cu")
		(net "MB0_P12V_PWGIN_R")
	)
	(segment
		(start 7.5946 -52.5907)
		(end 6.5786 -52.5907)
		(width 0.254)
		(layer "F.Cu")
		(net "MB0_P12V_PWGIN_R")
	)
	(segment
		(start 11.4681 -53.013864)
		(end 9.699498 -53.013864)
		(width 0.254)
		(layer "F.Cu")
		(net "MB0_P12V_PWGIN_R")
	)
	(segment
		(start 9.699498 -53.013864)
		(end 9.365234 -52.6796)
		(width 0.254)
		(layer "F.Cu")
		(net "MB0_P12V_PWGIN_R")
	)
	(segment
		(start 8.177276 -52.6796)
		(end 8.088376 -52.5907)
		(width 0.254)
		(layer "F.Cu")
		(net "MB0_P12V_PWGIN_R")
	)
	(segment
		(start 8.088376 -52.5907)
		(end 7.5946 -52.5907)
		(width 0.254)
		(layer "F.Cu")
		(net "MB0_P12V_PWGIN_R")
	)
	(via
		(at 8.9408 -52.6796)
		(size 0.6604)
		(drill 0.3302)
		(layers "F.Cu" "B.Cu")
		(net "MB0_P12V_PWGIN_R")
	)
	(via
		(at 14.85138 -30.10408)
		(size 0.6604)
		(drill 0.3302)
		(layers "F.Cu" "B.Cu")
		(net "MB0_P12V_MAIN_R")
	)
	(segment
		(start 21.2725 -56.8071)
		(end 20.9804 -56.515)
		(width 0.254)
		(layer "F.Cu")
		(net "MB0_ISTART_R")
	)
	(segment
		(start 20.9804 -56.0578)
		(end 20.0787 -55.1561)
		(width 0.254)
		(layer "F.Cu")
		(net "MB0_ISTART_R")
	)
	(segment
		(start 17.936464 -53.013864)
		(end 20.0787 -55.1561)
		(width 0.254)
		(layer "F.Cu")
		(net "MB0_ISTART_R")
	)
	(segment
		(start 16.4211 -53.013864)
		(end 17.936464 -53.013864)
		(width 0.254)
		(layer "F.Cu")
		(net "MB0_ISTART_R")
	)
	(segment
		(start 22.1742 -56.8071)
		(end 21.2725 -56.8071)
		(width 0.254)
		(layer "F.Cu")
		(net "MB0_ISTART_R")
	)
	(segment
		(start 20.9804 -56.515)
		(end 20.9804 -56.0578)
		(width 0.254)
		(layer "F.Cu")
		(net "MB0_ISTART_R")
	)
	(segment
		(start 23.1902 -56.8071)
		(end 22.1742 -56.8071)
		(width 0.254)
		(layer "F.Cu")
		(net "MB0_ISTART_R")
	)
	(via
		(at 20.0787 -55.1561)
		(size 0.6604)
		(drill 0.3302)
		(layers "F.Cu" "B.Cu")
		(net "MB0_ISTART_R")
	)
	(segment
		(start 21.3487 -53.5051)
		(end 21.0312 -53.1876)
		(width 0.254)
		(layer "F.Cu")
		(net "MB0_ISET_R")
	)
	(segment
		(start 18.274538 -52.513738)
		(end 19.2786 -53.5178)
		(width 0.254)
		(layer "F.Cu")
		(net "MB0_ISET_R")
	)
	(segment
		(start 21.0312 -53.1876)
		(end 20.0406 -53.1876)
		(width 0.254)
		(layer "F.Cu")
		(net "MB0_ISET_R")
	)
	(segment
		(start 19.2786 -53.5178)
		(end 19.7104 -53.5178)
		(width 0.254)
		(layer "F.Cu")
		(net "MB0_ISET_R")
	)
	(segment
		(start 21.3487 -55.3466)
		(end 21.3487 -54.3052)
		(width 0.254)
		(layer "F.Cu")
		(net "MB0_ISET_R")
	)
	(segment
		(start 21.3487 -54.3052)
		(end 21.3487 -53.5051)
		(width 0.254)
		(layer "F.Cu")
		(net "MB0_ISET_R")
	)
	(segment
		(start 16.4211 -52.513738)
		(end 18.274538 -52.513738)
		(width 0.254)
		(layer "F.Cu")
		(net "MB0_ISET_R")
	)
	(segment
		(start 20.0406 -53.1876)
		(end 19.7104 -53.5178)
		(width 0.254)
		(layer "F.Cu")
		(net "MB0_ISET_R")
	)
	(via
		(at 19.7104 -53.5178)
		(size 0.6604)
		(drill 0.3302)
		(layers "F.Cu" "B.Cu")
		(net "MB0_ISET_R")
	)
	(segment
		(start 13.3096 -58.4454)
		(end 14.1732 -57.5818)
		(width 0.254)
		(layer "F.Cu")
		(net "MB0_HS_ENABLE")
	)
	(segment
		(start 14.1732 -57.5818)
		(end 14.1732 -57.4294)
		(width 0.254)
		(layer "F.Cu")
		(net "MB0_HS_ENABLE")
	)
	(segment
		(start 16.161004 -62.490604)
		(end 16.161004 -63.535306)
		(width 0.254)
		(layer "F.Cu")
		(net "MB0_HS_ENABLE")
	)
	(segment
		(start 13.3096 -58.6867)
		(end 13.3096 -58.4454)
		(width 0.254)
		(layer "F.Cu")
		(net "MB0_HS_ENABLE")
	)
	(segment
		(start 15.701518 -61.552582)
		(end 15.701518 -62.031118)
		(width 0.254)
		(layer "F.Cu")
		(net "MB0_HS_ENABLE")
	)
	(segment
		(start 15.701518 -61.552582)
		(end 15.701518 -59.338972)
		(width 0.254)
		(layer "F.Cu")
		(net "MB0_HS_ENABLE")
	)
	(segment
		(start 15.04569 -58.683144)
		(end 14.361414 -58.683144)
		(width 0.254)
		(layer "F.Cu")
		(net "MB0_HS_ENABLE")
	)
	(segment
		(start 15.701518 -59.338972)
		(end 15.04569 -58.683144)
		(width 0.254)
		(layer "F.Cu")
		(net "MB0_HS_ENABLE")
	)
	(segment
		(start 13.3096 -58.6867)
		(end 14.357858 -58.6867)
		(width 0.254)
		(layer "F.Cu")
		(net "MB0_HS_ENABLE")
	)
	(segment
		(start 14.194536 -57.408064)
		(end 14.1732 -57.4294)
		(width 0.254)
		(layer "F.Cu")
		(net "MB0_HS_ENABLE")
	)
	(segment
		(start 14.194536 -55.7403)
		(end 14.194536 -57.408064)
		(width 0.254)
		(layer "F.Cu")
		(net "MB0_HS_ENABLE")
	)
	(segment
		(start 15.701518 -62.031118)
		(end 16.161004 -62.490604)
		(width 0.254)
		(layer "F.Cu")
		(net "MB0_HS_ENABLE")
	)
	(segment
		(start 14.357858 -58.6867)
		(end 14.361414 -58.683144)
		(width 0.254)
		(layer "F.Cu")
		(net "MB0_HS_ENABLE")
	)
	(via
		(at 14.1732 -57.4294)
		(size 0.6604)
		(drill 0.3302)
		(layers "F.Cu" "B.Cu")
		(net "MB0_HS_ENABLE")
	)
	(segment
		(start 8.8519 -53.8226)
		(end 9.160764 -53.513736)
		(width 0.254)
		(layer "F.Cu")
		(net "MB0_CM_VOUT_R")
	)
	(segment
		(start 9.98728 -54.311042)
		(end 9.340342 -54.311042)
		(width 0.254)
		(layer "F.Cu")
		(net "MB0_CM_VOUT_R")
	)
	(segment
		(start 14.3637 -38.608)
		(end 15.1384 -38.608)
		(width 0.508)
		(layer "F.Cu")
		(net "MB0_CM_VOUT_R")
	)
	(segment
		(start 9.160764 -53.513736)
		(end 11.4681 -53.513736)
		(width 0.254)
		(layer "F.Cu")
		(net "MB0_CM_VOUT_R")
	)
	(segment
		(start 9.340342 -54.311042)
		(end 8.8519 -53.8226)
		(width 0.254)
		(layer "F.Cu")
		(net "MB0_CM_VOUT_R")
	)
	(via
		(at 9.98728 -54.311042)
		(size 0.508)
		(drill 0.254)
		(layers "F.Cu" "B.Cu")
		(net "MB0_CM_VOUT_R")
	)
	(via
		(at 15.1384 -38.608)
		(size 0.508)
		(drill 0.254)
		(layers "F.Cu" "B.Cu")
		(net "MB0_CM_VOUT_R")
	)
	(via
		(at 8.780018 -52.09286)
		(size 0.6096)
		(drill 0.3048)
		(layers "F.Cu" "B.Cu")
		(net "MB0_CM_VOUT_R")
	)
	(segment
		(start 8.780018 -52.09286)
		(end 8.780018 -53.10378)
		(width 0.508)
		(layer "B.Cu")
		(net "MB0_CM_VOUT_R")
	)
	(segment
		(start 8.780018 -53.10378)
		(end 9.98728 -54.311042)
		(width 0.508)
		(layer "B.Cu")
		(net "MB0_CM_VOUT_R")
	)
	(segment
		(start 15.1384 -38.608)
		(end 15.1384 -39.728648)
		(width 0.508)
		(layer "B.Cu")
		(net "MB0_CM_VOUT_R")
	)
	(segment
		(start 15.1384 -39.728648)
		(end 8.780018 -46.08703)
		(width 0.508)
		(layer "B.Cu")
		(net "MB0_CM_VOUT_R")
	)
	(segment
		(start 8.780018 -46.08703)
		(end 8.780018 -52.09286)
		(width 0.508)
		(layer "B.Cu")
		(net "MB0_CM_VOUT_R")
	)
	(segment
		(start 17.3736 -49.1236)
		(end 16.764 -49.1236)
		(width 0.254)
		(layer "F.Cu")
		(net "MB0_CM_UV_R")
	)
	(segment
		(start 17.6911 -47.4091)
		(end 17.3736 -47.7266)
		(width 0.254)
		(layer "F.Cu")
		(net "MB0_CM_UV_R")
	)
	(segment
		(start 15.9766 -49.911)
		(end 15.5194 -49.911)
		(width 0.254)
		(layer "F.Cu")
		(net "MB0_CM_UV_R")
	)
	(segment
		(start 16.764 -49.1236)
		(end 15.9766 -49.911)
		(width 0.254)
		(layer "F.Cu")
		(net "MB0_CM_UV_R")
	)
	(segment
		(start 15.5194 -49.911)
		(end 15.194534 -50.235866)
		(width 0.254)
		(layer "F.Cu")
		(net "MB0_CM_UV_R")
	)
	(segment
		(start 15.194534 -50.235866)
		(end 15.194534 -50.7873)
		(width 0.254)
		(layer "F.Cu")
		(net "MB0_CM_UV_R")
	)
	(segment
		(start 18.4912 -47.4091)
		(end 17.6911 -47.4091)
		(width 0.254)
		(layer "F.Cu")
		(net "MB0_CM_UV_R")
	)
	(segment
		(start 19.5072 -47.4091)
		(end 18.4912 -47.4091)
		(width 0.254)
		(layer "F.Cu")
		(net "MB0_CM_UV_R")
	)
	(segment
		(start 17.3736 -47.7266)
		(end 17.3736 -49.1236)
		(width 0.254)
		(layer "F.Cu")
		(net "MB0_CM_UV_R")
	)
	(via
		(at 17.3736 -49.1236)
		(size 0.6604)
		(drill 0.3302)
		(layers "F.Cu" "B.Cu")
		(net "MB0_CM_UV_R")
	)
	(segment
		(start 14.378178 -42.748708)
		(end 14.378178 -42.509186)
		(width 0.254)
		(layer "F.Cu")
		(net "MB0_CM_SENSE_R1_P")
	)
	(segment
		(start 12.827 -45.755814)
		(end 12.827 -46.5963)
		(width 0.254)
		(layer "F.Cu")
		(net "MB0_CM_SENSE_R1_P")
	)
	(segment
		(start 16.866362 -35.801808)
		(end 16.474948 -36.193222)
		(width 0.254)
		(layer "F.Cu")
		(net "MB0_CM_SENSE_R1_P")
	)
	(segment
		(start 16.474948 -36.193222)
		(end 16.474948 -38.66007)
		(width 0.254)
		(layer "F.Cu")
		(net "MB0_CM_SENSE_R1_P")
	)
	(segment
		(start 14.378178 -42.509186)
		(end 14.909038 -41.978326)
		(width 0.254)
		(layer "F.Cu")
		(net "MB0_CM_SENSE_R1_P")
	)
	(segment
		(start 12.749276 -45.67809)
		(end 12.827 -45.755814)
		(width 0.254)
		(layer "F.Cu")
		(net "MB0_CM_SENSE_R1_P")
	)
	(segment
		(start 16.474948 -40.412416)
		(end 16.474948 -38.66007)
		(width 0.254)
		(layer "F.Cu")
		(net "MB0_CM_SENSE_R1_P")
	)
	(segment
		(start 14.909038 -41.978326)
		(end 16.474948 -40.412416)
		(width 0.254)
		(layer "F.Cu")
		(net "MB0_CM_SENSE_R1_P")
	)
	(via
		(at 12.749276 -45.67809)
		(size 0.508)
		(drill 0.254)
		(layers "F.Cu" "B.Cu")
		(net "MB0_CM_SENSE_R1_P")
	)
	(via
		(at 14.909038 -41.978326)
		(size 0.508)
		(drill 0.254)
		(layers "F.Cu" "B.Cu")
		(net "MB0_CM_SENSE_R1_P")
	)
	(via
		(at 16.474948 -38.66007)
		(size 0.6604)
		(drill 0.3302)
		(layers "F.Cu" "B.Cu")
		(net "MB0_CM_SENSE_R1_P")
	)
	(segment
		(start 12.749276 -44.138088)
		(end 12.749276 -45.67809)
		(width 0.254)
		(layer "B.Cu")
		(net "MB0_CM_SENSE_R1_P")
	)
	(segment
		(start 14.909038 -41.978326)
		(end 12.749276 -44.138088)
		(width 0.254)
		(layer "B.Cu")
		(net "MB0_CM_SENSE_R1_P")
	)
	(segment
		(start 15.8242 -40.047418)
		(end 14.976348 -40.89527)
		(width 0.254)
		(layer "F.Cu")
		(net "MB0_CM_SENSE_R1_N")
	)
	(segment
		(start 15.8242 -36.38677)
		(end 15.8242 -40.047418)
		(width 0.254)
		(layer "F.Cu")
		(net "MB0_CM_SENSE_R1_N")
	)
	(segment
		(start 14.976348 -40.89527)
		(end 13.893292 -41.978326)
		(width 0.254)
		(layer "F.Cu")
		(net "MB0_CM_SENSE_R1_N")
	)
	(segment
		(start 13.362178 -42.748708)
		(end 13.362178 -42.509186)
		(width 0.254)
		(layer "F.Cu")
		(net "MB0_CM_SENSE_R1_N")
	)
	(segment
		(start 13.893292 -41.978326)
		(end 13.893038 -41.978326)
		(width 0.254)
		(layer "F.Cu")
		(net "MB0_CM_SENSE_R1_N")
	)
	(segment
		(start 13.362178 -42.509186)
		(end 13.893038 -41.978326)
		(width 0.254)
		(layer "F.Cu")
		(net "MB0_CM_SENSE_R1_N")
	)
	(segment
		(start 11.811 -45.755814)
		(end 11.811 -46.5963)
		(width 0.254)
		(layer "F.Cu")
		(net "MB0_CM_SENSE_R1_N")
	)
	(segment
		(start 11.733276 -45.67809)
		(end 11.811 -45.755814)
		(width 0.254)
		(layer "F.Cu")
		(net "MB0_CM_SENSE_R1_N")
	)
	(segment
		(start 15.239238 -35.801808)
		(end 15.8242 -36.38677)
		(width 0.254)
		(layer "F.Cu")
		(net "MB0_CM_SENSE_R1_N")
	)
	(via
		(at 14.976348 -40.89527)
		(size 0.6604)
		(drill 0.3302)
		(layers "F.Cu" "B.Cu")
		(net "MB0_CM_SENSE_R1_N")
	)
	(via
		(at 11.733276 -45.67809)
		(size 0.508)
		(drill 0.254)
		(layers "F.Cu" "B.Cu")
		(net "MB0_CM_SENSE_R1_N")
	)
	(via
		(at 13.893038 -41.978326)
		(size 0.508)
		(drill 0.254)
		(layers "F.Cu" "B.Cu")
		(net "MB0_CM_SENSE_R1_N")
	)
	(segment
		(start 11.733276 -44.138088)
		(end 13.893038 -41.978326)
		(width 0.254)
		(layer "B.Cu")
		(net "MB0_CM_SENSE_R1_N")
	)
	(segment
		(start 11.733276 -45.67809)
		(end 11.733276 -44.138088)
		(width 0.254)
		(layer "B.Cu")
		(net "MB0_CM_SENSE_R1_N")
	)
	(segment
		(start 14.340078 -43.675808)
		(end 14.378178 -43.637708)
		(width 0.254)
		(layer "F.Cu")
		(net "MB0_CM_SENSE_P")
	)
	(segment
		(start 13.80998 -48.550576)
		(end 13.80998 -45.902372)
		(width 0.254)
		(layer "F.Cu")
		(net "MB0_CM_SENSE_P")
	)
	(segment
		(start 13.80998 -45.351954)
		(end 14.340078 -44.821856)
		(width 0.254)
		(layer "F.Cu")
		(net "MB0_CM_SENSE_P")
	)
	(segment
		(start 14.194536 -50.7873)
		(end 14.194536 -48.935132)
		(width 0.254)
		(layer "F.Cu")
		(net "MB0_CM_SENSE_P")
	)
	(segment
		(start 14.194536 -48.935132)
		(end 13.80998 -48.550576)
		(width 0.254)
		(layer "F.Cu")
		(net "MB0_CM_SENSE_P")
	)
	(segment
		(start 14.340078 -44.821856)
		(end 14.340078 -44.590208)
		(width 0.254)
		(layer "F.Cu")
		(net "MB0_CM_SENSE_P")
	)
	(segment
		(start 13.80998 -45.902372)
		(end 13.80998 -45.351954)
		(width 0.254)
		(layer "F.Cu")
		(net "MB0_CM_SENSE_P")
	)
	(segment
		(start 14.340078 -44.590208)
		(end 14.340078 -43.675808)
		(width 0.254)
		(layer "F.Cu")
		(net "MB0_CM_SENSE_P")
	)
	(via
		(at 13.80998 -45.902372)
		(size 0.6604)
		(drill 0.3302)
		(layers "F.Cu" "B.Cu")
		(net "MB0_CM_SENSE_P")
	)
	(segment
		(start 12.694666 -50.194464)
		(end 12.694666 -50.7873)
		(width 0.254)
		(layer "F.Cu")
		(net "MB0_CM_SENSE_N")
	)
	(segment
		(start 13.451078 -44.590208)
		(end 13.451078 -43.726608)
		(width 0.254)
		(layer "F.Cu")
		(net "MB0_CM_SENSE_N")
	)
	(segment
		(start 11.339576 -45.137324)
		(end 10.570718 -45.906182)
		(width 0.254)
		(layer "F.Cu")
		(net "MB0_CM_SENSE_N")
	)
	(segment
		(start 10.570718 -46.58487)
		(end 10.570718 -48.070516)
		(width 0.254)
		(layer "F.Cu")
		(net "MB0_CM_SENSE_N")
	)
	(segment
		(start 12.903962 -45.137324)
		(end 11.339576 -45.137324)
		(width 0.254)
		(layer "F.Cu")
		(net "MB0_CM_SENSE_N")
	)
	(segment
		(start 10.570718 -45.906182)
		(end 10.570718 -46.58487)
		(width 0.254)
		(layer "F.Cu")
		(net "MB0_CM_SENSE_N")
	)
	(segment
		(start 10.570718 -48.070516)
		(end 12.694666 -50.194464)
		(width 0.254)
		(layer "F.Cu")
		(net "MB0_CM_SENSE_N")
	)
	(segment
		(start 13.451078 -43.726608)
		(end 13.362178 -43.637708)
		(width 0.254)
		(layer "F.Cu")
		(net "MB0_CM_SENSE_N")
	)
	(segment
		(start 13.451078 -44.590208)
		(end 12.903962 -45.137324)
		(width 0.254)
		(layer "F.Cu")
		(net "MB0_CM_SENSE_N")
	)
	(via
		(at 10.570718 -46.58487)
		(size 0.6604)
		(drill 0.3302)
		(layers "F.Cu" "B.Cu")
		(net "MB0_CM_SENSE_N")
	)
	(segment
		(start 19.41195 -48.6156)
		(end 17.98955 -50.038)
		(width 0.254)
		(layer "F.Cu")
		(net "MB0_CM_OV_R")
	)
	(segment
		(start 17.1958 -50.038)
		(end 16.5227 -50.7111)
		(width 0.254)
		(layer "F.Cu")
		(net "MB0_CM_OV_R")
	)
	(segment
		(start 20.9423 -47.4599)
		(end 20.6502 -47.752)
		(width 0.254)
		(layer "F.Cu")
		(net "MB0_CM_OV_R")
	)
	(segment
		(start 20.6502 -47.752)
		(end 20.27555 -47.752)
		(width 0.254)
		(layer "F.Cu")
		(net "MB0_CM_OV_R")
	)
	(segment
		(start 17.98955 -50.038)
		(end 17.1958 -50.038)
		(width 0.254)
		(layer "F.Cu")
		(net "MB0_CM_OV_R")
	)
	(segment
		(start 21.7678 -47.4599)
		(end 20.9423 -47.4599)
		(width 0.254)
		(layer "F.Cu")
		(net "MB0_CM_OV_R")
	)
	(segment
		(start 20.27555 -47.752)
		(end 19.41195 -48.6156)
		(width 0.254)
		(layer "F.Cu")
		(net "MB0_CM_OV_R")
	)
	(segment
		(start 22.8092 -47.4599)
		(end 21.7678 -47.4599)
		(width 0.254)
		(layer "F.Cu")
		(net "MB0_CM_OV_R")
	)
	(segment
		(start 16.5227 -50.7111)
		(end 15.69466 -50.7111)
		(width 0.254)
		(layer "F.Cu")
		(net "MB0_CM_OV_R")
	)
	(via
		(at 19.41195 -48.6156)
		(size 0.6604)
		(drill 0.3302)
		(layers "F.Cu" "B.Cu")
		(net "MB0_CM_OV_R")
	)
	(via
		(at 8.89 -42.037)
		(size 0.6604)
		(drill 0.3302)
		(layers "F.Cu" "B.Cu")
		(net "MB0_CM_GATE_R")
	)
	(via
		(at 5.957062 -45.967142)
		(size 0.6604)
		(drill 0.3302)
		(layers "F.Cu" "B.Cu")
		(net "MB0_CM_GATE")
	)
	(segment
		(start 17.907 -58.6867)
		(end 17.907 -57.8358)
		(width 0.254)
		(layer "F.Cu")
		(net "MB0_CM_ADR2_R")
	)
	(segment
		(start 16.4973 -55.01386)
		(end 16.4973 -56.4261)
		(width 0.254)
		(layer "F.Cu")
		(net "MB0_CM_ADR2_R")
	)
	(segment
		(start 16.4973 -56.4261)
		(end 17.526 -57.4548)
		(width 0.254)
		(layer "F.Cu")
		(net "MB0_CM_ADR2_R")
	)
	(segment
		(start 17.907 -57.8358)
		(end 17.526 -57.4548)
		(width 0.254)
		(layer "F.Cu")
		(net "MB0_CM_ADR2_R")
	)
	(via
		(at 17.526 -57.4548)
		(size 0.6604)
		(drill 0.3302)
		(layers "F.Cu" "B.Cu")
		(net "MB0_CM_ADR2_R")
	)
	(segment
		(start 17.2212 -56.107076)
		(end 18.594324 -57.4802)
		(width 0.254)
		(layer "F.Cu")
		(net "MB0_CM_ADR1_R")
	)
	(segment
		(start 19.177 -58.6867)
		(end 19.177 -57.6834)
		(width 0.254)
		(layer "F.Cu")
		(net "MB0_CM_ADR1_R")
	)
	(segment
		(start 17.023334 -54.513734)
		(end 17.2212 -54.7116)
		(width 0.254)
		(layer "F.Cu")
		(net "MB0_CM_ADR1_R")
	)
	(segment
		(start 18.594324 -57.4802)
		(end 18.9738 -57.4802)
		(width 0.254)
		(layer "F.Cu")
		(net "MB0_CM_ADR1_R")
	)
	(segment
		(start 16.4211 -54.513734)
		(end 17.023334 -54.513734)
		(width 0.254)
		(layer "F.Cu")
		(net "MB0_CM_ADR1_R")
	)
	(segment
		(start 17.2212 -54.7116)
		(end 17.2212 -56.107076)
		(width 0.254)
		(layer "F.Cu")
		(net "MB0_CM_ADR1_R")
	)
	(segment
		(start 19.177 -57.6834)
		(end 18.9738 -57.4802)
		(width 0.254)
		(layer "F.Cu")
		(net "MB0_CM_ADR1_R")
	)
	(via
		(at 18.9738 -57.4802)
		(size 0.6604)
		(drill 0.3302)
		(layers "F.Cu" "B.Cu")
		(net "MB0_CM_ADR1_R")
	)
	(via
		(at 6.765036 -38.143434)
		(size 0.6604)
		(drill 0.3302)
		(layers "F.Cu" "B.Cu")
		(net "MB0_12V_CTRL_GATE1")
	)
	(segment
		(start 15.1892 -46.4566)
		(end 15.1892 -45.3898)
		(width 0.508)
		(layer "F.Cu")
		(net "AGND_CURRENT_MON")
	)
	(segment
		(start 10.044938 -52.513738)
		(end 10.011664 -52.480464)
		(width 0.3048)
		(layer "F.Cu")
		(net "AGND_CURRENT_MON")
	)
	(segment
		(start 15.1892 -45.3898)
		(end 15.1638 -45.3644)
		(width 0.508)
		(layer "F.Cu")
		(net "AGND_CURRENT_MON")
	)
	(segment
		(start 19.1389 -56.134)
		(end 20.0279 -56.134)
		(width 0.508)
		(layer "F.Cu")
		(net "AGND_CURRENT_MON")
	)
	(segment
		(start 22.1742 -57.6961)
		(end 22.1742 -58.5851)
		(width 0.508)
		(layer "F.Cu")
		(net "AGND_CURRENT_MON")
	)
	(segment
		(start 8.253222 -51.608482)
		(end 8.73252 -51.608482)
		(width 0.3048)
		(layer "F.Cu")
		(net "AGND_CURRENT_MON")
	)
	(segment
		(start 9.139936 -51.608482)
		(end 10.011664 -52.48021)
		(width 0.3048)
		(layer "F.Cu")
		(net "AGND_CURRENT_MON")
	)
	(segment
		(start 19.177 -59.5757)
		(end 19.177 -60.4012)
		(width 0.508)
		(layer "F.Cu")
		(net "AGND_CURRENT_MON")
	)
	(segment
		(start 22.5552 -51.9176)
		(end 23.4442 -51.9176)
		(width 0.508)
		(layer "F.Cu")
		(net "AGND_CURRENT_MON")
	)
	(segment
		(start 7.5946 -51.7017)
		(end 8.160004 -51.7017)
		(width 0.3048)
		(layer "F.Cu")
		(net "AGND_CURRENT_MON")
	)
	(segment
		(start 19.5072 -46.5201)
		(end 19.5072 -45.2628)
		(width 0.508)
		(layer "F.Cu")
		(net "AGND_CURRENT_MON")
	)
	(segment
		(start 8.160004 -51.7017)
		(end 8.253222 -51.608482)
		(width 0.3048)
		(layer "F.Cu")
		(net "AGND_CURRENT_MON")
	)
	(segment
		(start 20.6502 -46.228)
		(end 20.6502 -45.2247)
		(width 0.508)
		(layer "F.Cu")
		(net "AGND_CURRENT_MON")
	)
	(segment
		(start 22.2377 -55.3466)
		(end 23.0632 -55.3466)
		(width 0.508)
		(layer "F.Cu")
		(net "AGND_CURRENT_MON")
	)
	(segment
		(start 17.907 -59.5757)
		(end 17.907 -60.4012)
		(width 0.508)
		(layer "F.Cu")
		(net "AGND_CURRENT_MON")
	)
	(segment
		(start 22.5552 -53.1876)
		(end 23.4442 -53.1876)
		(width 0.508)
		(layer "F.Cu")
		(net "AGND_CURRENT_MON")
	)
	(segment
		(start 8.73252 -51.608482)
		(end 9.139936 -51.608482)
		(width 0.3048)
		(layer "F.Cu")
		(net "AGND_CURRENT_MON")
	)
	(segment
		(start 22.6187 -48.4886)
		(end 23.4442 -48.4886)
		(width 0.508)
		(layer "F.Cu")
		(net "AGND_CURRENT_MON")
	)
	(segment
		(start 21.7678 -46.5709)
		(end 21.7678 -45.212)
		(width 0.508)
		(layer "F.Cu")
		(net "AGND_CURRENT_MON")
	)
	(segment
		(start 11.4681 -52.513738)
		(end 10.044938 -52.513738)
		(width 0.3048)
		(layer "F.Cu")
		(net "AGND_CURRENT_MON")
	)
	(segment
		(start 16.637 -59.5757)
		(end 16.637 -60.4012)
		(width 0.508)
		(layer "F.Cu")
		(net "AGND_CURRENT_MON")
	)
	(segment
		(start 20.9804 -58.039)
		(end 20.9804 -58.928)
		(width 0.508)
		(layer "F.Cu")
		(net "AGND_CURRENT_MON")
	)
	(segment
		(start 22.5552 -50.6476)
		(end 23.4442 -50.6476)
		(width 0.508)
		(layer "F.Cu")
		(net "AGND_CURRENT_MON")
	)
	(segment
		(start 10.011664 -52.48021)
		(end 10.011664 -52.480464)
		(width 0.3048)
		(layer "F.Cu")
		(net "AGND_CURRENT_MON")
	)
	(segment
		(start 17.3736 -46.2026)
		(end 17.3736 -45.1993)
		(width 0.508)
		(layer "F.Cu")
		(net "AGND_CURRENT_MON")
	)
	(via
		(at 13.9446 -51.9938)
		(size 0.5588)
		(drill 0.3048)
		(layers "F.Cu" "B.Cu")
		(net "AGND_CURRENT_MON")
	)
	(via
		(at 23.4442 -53.1876)
		(size 0.508)
		(drill 0.254)
		(layers "F.Cu" "B.Cu")
		(net "AGND_CURRENT_MON")
	)
	(via
		(at 23.4442 -48.4886)
		(size 0.508)
		(drill 0.254)
		(layers "F.Cu" "B.Cu")
		(net "AGND_CURRENT_MON")
	)
	(via
		(at 23.4442 -50.6476)
		(size 0.508)
		(drill 0.254)
		(layers "F.Cu" "B.Cu")
		(net "AGND_CURRENT_MON")
	)
	(via
		(at 17.3736 -45.1993)
		(size 0.508)
		(drill 0.254)
		(layers "F.Cu" "B.Cu")
		(net "AGND_CURRENT_MON")
	)
	(via
		(at 6.0452 -53.6448)
		(size 0.508)
		(drill 0.254)
		(layers "F.Cu" "B.Cu")
		(net "AGND_CURRENT_MON")
	)
	(via
		(at 16.637 -60.4012)
		(size 0.508)
		(drill 0.254)
		(layers "F.Cu" "B.Cu")
		(net "AGND_CURRENT_MON")
	)
	(via
		(at 20.0279 -56.134)
		(size 0.508)
		(drill 0.254)
		(layers "F.Cu" "B.Cu")
		(net "AGND_CURRENT_MON")
	)
	(via
		(at 19.5072 -45.2628)
		(size 0.508)
		(drill 0.254)
		(layers "F.Cu" "B.Cu")
		(net "AGND_CURRENT_MON")
	)
	(via
		(at 12.6746 -53.2638)
		(size 0.5588)
		(drill 0.3048)
		(layers "F.Cu" "B.Cu")
		(net "AGND_CURRENT_MON")
	)
	(via
		(at 13.9446 -54.5338)
		(size 0.5588)
		(drill 0.3048)
		(layers "F.Cu" "B.Cu")
		(net "AGND_CURRENT_MON")
	)
	(via
		(at 23.4442 -51.9176)
		(size 0.508)
		(drill 0.254)
		(layers "F.Cu" "B.Cu")
		(net "AGND_CURRENT_MON")
	)
	(via
		(at 8.73252 -51.608482)
		(size 0.6604)
		(drill 0.3302)
		(layers "F.Cu" "B.Cu")
		(net "AGND_CURRENT_MON")
	)
	(via
		(at 22.1742 -58.5851)
		(size 0.508)
		(drill 0.254)
		(layers "F.Cu" "B.Cu")
		(net "AGND_CURRENT_MON")
	)
	(via
		(at 10.011664 -52.480464)
		(size 0.508)
		(drill 0.254)
		(layers "F.Cu" "B.Cu")
		(net "AGND_CURRENT_MON")
	)
	(via
		(at 20.6502 -45.2247)
		(size 0.508)
		(drill 0.254)
		(layers "F.Cu" "B.Cu")
		(net "AGND_CURRENT_MON")
	)
	(via
		(at 15.2146 -53.2638)
		(size 0.5588)
		(drill 0.3048)
		(layers "F.Cu" "B.Cu")
		(net "AGND_CURRENT_MON")
	)
	(via
		(at 19.177 -60.4012)
		(size 0.508)
		(drill 0.254)
		(layers "F.Cu" "B.Cu")
		(net "AGND_CURRENT_MON")
	)
	(via
		(at 6.985 -53.6448)
		(size 0.508)
		(drill 0.254)
		(layers "F.Cu" "B.Cu")
		(net "AGND_CURRENT_MON")
	)
	(via
		(at 21.7678 -45.212)
		(size 0.508)
		(drill 0.254)
		(layers "F.Cu" "B.Cu")
		(net "AGND_CURRENT_MON")
	)
	(via
		(at 13.9446 -53.2638)
		(size 0.5588)
		(drill 0.3048)
		(layers "F.Cu" "B.Cu")
		(net "AGND_CURRENT_MON")
	)
	(via
		(at 17.907 -60.4012)
		(size 0.508)
		(drill 0.254)
		(layers "F.Cu" "B.Cu")
		(net "AGND_CURRENT_MON")
	)
	(via
		(at 20.9804 -58.928)
		(size 0.508)
		(drill 0.254)
		(layers "F.Cu" "B.Cu")
		(net "AGND_CURRENT_MON")
	)
	(via
		(at 23.0632 -55.3466)
		(size 0.508)
		(drill 0.254)
		(layers "F.Cu" "B.Cu")
		(net "AGND_CURRENT_MON")
	)
	(via
		(at 15.1638 -45.3644)
		(size 0.508)
		(drill 0.254)
		(layers "F.Cu" "B.Cu")
		(net "AGND_CURRENT_MON")
	)
	(segment
		(start 111.652812 -109.252766)
		(end 107.249976 -104.84993)
		(width 0.127)
		(layer "F.Cu")
		(net "INT_D2_CONN1")
	)
	(segment
		(start 124.000514 -109.252766)
		(end 111.652812 -109.252766)
		(width 0.127)
		(layer "F.Cu")
		(net "INT_D2_CONN1")
	)
	(segment
		(start 124.6632 -108.59008)
		(end 124.000514 -109.252766)
		(width 0.127)
		(layer "F.Cu")
		(net "INT_D2_CONN1")
	)
	(segment
		(start 123.317 -108.59008)
		(end 113.139982 -108.59008)
		(width 0.127)
		(layer "F.Cu")
		(net "INT_D1_CONN1")
	)
	(segment
		(start 113.139982 -108.59008)
		(end 108.000038 -103.450136)
		(width 0.127)
		(layer "F.Cu")
		(net "INT_D1_CONN1")
	)
	(segment
		(start 124.0409 -110.55858)
		(end 124.6632 -109.93628)
		(width 0.127)
		(layer "F.Cu")
		(net "INT_C2_CONN1")
	)
	(segment
		(start 107.249976 -108.650024)
		(end 109.158532 -110.55858)
		(width 0.127)
		(layer "F.Cu")
		(net "INT_C2_CONN1")
	)
	(segment
		(start 109.158532 -110.55858)
		(end 124.0409 -110.55858)
		(width 0.127)
		(layer "F.Cu")
		(net "INT_C2_CONN1")
	)
	(segment
		(start 110.686342 -109.93628)
		(end 108.000038 -107.249976)
		(width 0.127)
		(layer "F.Cu")
		(net "INT_C1_CONN1")
	)
	(segment
		(start 123.317 -109.93628)
		(end 110.686342 -109.93628)
		(width 0.127)
		(layer "F.Cu")
		(net "INT_C1_CONN1")
	)
	(segment
		(start 124.05868 -111.887)
		(end 124.6632 -111.28248)
		(width 0.127)
		(layer "F.Cu")
		(net "INT_B2_CONN1")
	)
	(segment
		(start 107.813094 -111.887)
		(end 124.05868 -111.887)
		(width 0.127)
		(layer "F.Cu")
		(net "INT_B2_CONN1")
	)
	(segment
		(start 107.249976 -112.450118)
		(end 107.813094 -111.887)
		(width 0.127)
		(layer "F.Cu")
		(net "INT_B2_CONN1")
	)
	(segment
		(start 108.232448 -111.28248)
		(end 123.317 -111.28248)
		(width 0.127)
		(layer "F.Cu")
		(net "INT_B1_CONN1")
	)
	(segment
		(start 108.000038 -111.05007)
		(end 108.232448 -111.28248)
		(width 0.127)
		(layer "F.Cu")
		(net "INT_B1_CONN1")
	)
	(segment
		(start 109.30382 -112.62868)
		(end 107.249976 -114.682524)
		(width 0.127)
		(layer "F.Cu")
		(net "INT_A2_CONN1")
	)
	(segment
		(start 123.317 -112.62868)
		(end 109.30382 -112.62868)
		(width 0.127)
		(layer "F.Cu")
		(net "INT_A2_CONN1")
	)
	(segment
		(start 107.249976 -114.682524)
		(end 107.249976 -116.249958)
		(width 0.127)
		(layer "F.Cu")
		(net "INT_A2_CONN1")
	)
	(segment
		(start 108.000038 -114.84991)
		(end 109.667548 -113.1824)
		(width 0.127)
		(layer "F.Cu")
		(net "INT_A1_CONN1")
	)
	(segment
		(start 124.10948 -113.1824)
		(end 124.6632 -112.62868)
		(width 0.127)
		(layer "F.Cu")
		(net "INT_A1_CONN1")
	)
	(segment
		(start 109.667548 -113.1824)
		(end 124.10948 -113.1824)
		(width 0.127)
		(layer "F.Cu")
		(net "INT_A1_CONN1")
	)
	(segment
		(start 165.492684 -97.609406)
		(end 165.863778 -97.238312)
		(width 0.254)
		(layer "F.Cu")
		(net "AGND_P0V975")
	)
	(segment
		(start 166.816278 -96.285812)
		(end 167.52443 -96.285812)
		(width 0.254)
		(layer "F.Cu")
		(net "AGND_P0V975")
	)
	(segment
		(start 165.863778 -97.238312)
		(end 166.816278 -96.285812)
		(width 0.254)
		(layer "F.Cu")
		(net "AGND_P0V975")
	)
	(segment
		(start 164.496242 -97.609406)
		(end 165.492684 -97.609406)
		(width 0.254)
		(layer "F.Cu")
		(net "AGND_P0V975")
	)
	(segment
		(start 163.298378 -97.609406)
		(end 164.496242 -97.609406)
		(width 0.254)
		(layer "F.Cu")
		(net "AGND_P0V975")
	)
	(via
		(at 165.23462 -96.443546)
		(size 0.6096)
		(drill 0.3048)
		(layers "F.Cu" "B.Cu")
		(net "AGND_P0V975")
	)
	(via
		(at 165.863778 -97.238312)
		(size 0.508)
		(drill 0.254)
		(layers "F.Cu" "B.Cu")
		(net "AGND_P0V975")
	)
	(segment
		(start 168.028874 -95.664782)
		(end 166.885874 -95.664782)
		(width 0.508)
		(layer "B.Cu")
		(net "AGND_P0V975")
	)
	(segment
		(start 165.863778 -97.238312)
		(end 165.526212 -97.238312)
		(width 0.254)
		(layer "B.Cu")
		(net "AGND_P0V975")
	)
	(segment
		(start 166.885874 -95.369126)
		(end 167.259 -94.996)
		(width 0.254)
		(layer "B.Cu")
		(net "AGND_P0V975")
	)
	(segment
		(start 169.171874 -95.664782)
		(end 168.028874 -95.664782)
		(width 0.508)
		(layer "B.Cu")
		(net "AGND_P0V975")
	)
	(segment
		(start 167.259 -94.996)
		(end 167.259 -94.5134)
		(width 0.254)
		(layer "B.Cu")
		(net "AGND_P0V975")
	)
	(segment
		(start 166.885874 -95.664782)
		(end 165.533324 -95.664782)
		(width 0.254)
		(layer "B.Cu")
		(net "AGND_P0V975")
	)
	(segment
		(start 165.533324 -95.664782)
		(end 165.23462 -95.963486)
		(width 0.254)
		(layer "B.Cu")
		(net "AGND_P0V975")
	)
	(segment
		(start 165.23462 -96.94672)
		(end 165.23462 -96.443546)
		(width 0.254)
		(layer "B.Cu")
		(net "AGND_P0V975")
	)
	(segment
		(start 166.885874 -95.664782)
		(end 166.885874 -95.369126)
		(width 0.254)
		(layer "B.Cu")
		(net "AGND_P0V975")
	)
	(segment
		(start 165.23462 -95.963486)
		(end 165.23462 -96.443546)
		(width 0.254)
		(layer "B.Cu")
		(net "AGND_P0V975")
	)
	(segment
		(start 165.526212 -97.238312)
		(end 165.23462 -96.94672)
		(width 0.254)
		(layer "B.Cu")
		(net "AGND_P0V975")
	)
	(via
		(at 173.1772 -93.0148)
		(size 0.6604)
		(drill 0.3302)
		(layers "F.Cu" "B.Cu")
		(net "VT235_VX")
	)
	(segment
		(start 170.616118 -100.629974)
		(end 170.616118 -99.687126)
		(width 0.254)
		(layer "F.Cu")
		(net "VT235_VREF")
	)
	(segment
		(start 172.45838 -101.74224)
		(end 172.02404 -101.74224)
		(width 0.254)
		(layer "F.Cu")
		(net "VT235_VREF")
	)
	(segment
		(start 170.616118 -100.629974)
		(end 171.636182 -100.629974)
		(width 0.254)
		(layer "F.Cu")
		(net "VT235_VREF")
	)
	(segment
		(start 170.606974 -99.677982)
		(end 170.606974 -98.527362)
		(width 0.254)
		(layer "F.Cu")
		(net "VT235_VREF")
	)
	(segment
		(start 171.636182 -100.629974)
		(end 171.661074 -100.605082)
		(width 0.254)
		(layer "F.Cu")
		(net "VT235_VREF")
	)
	(segment
		(start 172.5676 -101.74224)
		(end 172.45838 -101.74224)
		(width 0.254)
		(layer "F.Cu")
		(net "VT235_VREF")
	)
	(segment
		(start 170.606974 -98.527362)
		(end 170.410124 -98.330512)
		(width 0.254)
		(layer "F.Cu")
		(net "VT235_VREF")
	)
	(segment
		(start 173.680374 -100.629466)
		(end 172.5676 -101.74224)
		(width 0.254)
		(layer "F.Cu")
		(net "VT235_VREF")
	)
	(segment
		(start 173.680374 -100.554282)
		(end 173.680374 -100.629466)
		(width 0.254)
		(layer "F.Cu")
		(net "VT235_VREF")
	)
	(segment
		(start 170.616118 -99.687126)
		(end 170.606974 -99.677982)
		(width 0.254)
		(layer "F.Cu")
		(net "VT235_VREF")
	)
	(segment
		(start 171.661074 -101.379274)
		(end 171.661074 -100.605082)
		(width 0.254)
		(layer "F.Cu")
		(net "VT235_VREF")
	)
	(segment
		(start 172.02404 -101.74224)
		(end 171.661074 -101.379274)
		(width 0.254)
		(layer "F.Cu")
		(net "VT235_VREF")
	)
	(segment
		(start 170.410124 -98.330512)
		(end 170.410124 -97.17151)
		(width 0.254)
		(layer "F.Cu")
		(net "VT235_VREF")
	)
	(via
		(at 172.45838 -101.74224)
		(size 0.6604)
		(drill 0.3302)
		(layers "F.Cu" "B.Cu")
		(net "VT235_VREF")
	)
	(segment
		(start 175.387 -97.0407)
		(end 175.5902 -97.0407)
		(width 0.254)
		(layer "F.Cu")
		(net "VT235_VFB")
	)
	(segment
		(start 172.054012 -96.285812)
		(end 171.795694 -96.285812)
		(width 0.254)
		(layer "F.Cu")
		(net "VT235_VFB")
	)
	(segment
		(start 173.7614 -97.0407)
		(end 172.8089 -97.0407)
		(width 0.254)
		(layer "F.Cu")
		(net "VT235_VFB")
	)
	(segment
		(start 176.5554 -96.0755)
		(end 177.8508 -96.0755)
		(width 0.254)
		(layer "F.Cu")
		(net "VT235_VFB")
	)
	(segment
		(start 175.5902 -97.0407)
		(end 176.5554 -96.0755)
		(width 0.254)
		(layer "F.Cu")
		(net "VT235_VFB")
	)
	(segment
		(start 175.387 -97.0407)
		(end 173.7614 -97.0407)
		(width 0.254)
		(layer "F.Cu")
		(net "VT235_VFB")
	)
	(segment
		(start 172.8089 -97.0407)
		(end 172.054012 -96.285812)
		(width 0.254)
		(layer "F.Cu")
		(net "VT235_VFB")
	)
	(via
		(at 173.7614 -97.0407)
		(size 0.6604)
		(drill 0.3302)
		(layers "F.Cu" "B.Cu")
		(net "VT235_VFB")
	)
	(segment
		(start 168.571418 -101.325426)
		(end 168.892474 -101.646482)
		(width 0.254)
		(layer "F.Cu")
		(net "VT235_VDES_RR")
	)
	(segment
		(start 169.066718 -99.677982)
		(end 169.717974 -99.677982)
		(width 0.254)
		(layer "F.Cu")
		(net "VT235_VDES_RR")
	)
	(segment
		(start 168.571418 -100.5078)
		(end 168.571418 -100.173282)
		(width 0.254)
		(layer "F.Cu")
		(net "VT235_VDES_RR")
	)
	(segment
		(start 168.571418 -100.173282)
		(end 169.066718 -99.677982)
		(width 0.254)
		(layer "F.Cu")
		(net "VT235_VDES_RR")
	)
	(segment
		(start 168.571418 -100.5078)
		(end 168.571418 -101.325426)
		(width 0.254)
		(layer "F.Cu")
		(net "VT235_VDES_RR")
	)
	(via
		(at 168.571418 -100.5078)
		(size 0.6604)
		(drill 0.3302)
		(layers "F.Cu" "B.Cu")
		(net "VT235_VDES_RR")
	)
	(segment
		(start 176.7078 -100.5967)
		(end 177.5206 -100.5967)
		(width 0.254)
		(layer "F.Cu")
		(net "VT235_VDES_RCC")
	)
	(segment
		(start 175.6156 -100.2411)
		(end 176.3522 -100.2411)
		(width 0.254)
		(layer "F.Cu")
		(net "VT235_VDES_RCC")
	)
	(segment
		(start 177.5206 -100.5967)
		(end 177.8508 -100.2665)
		(width 0.254)
		(layer "F.Cu")
		(net "VT235_VDES_RCC")
	)
	(segment
		(start 175.6156 -100.2411)
		(end 175.6156 -101.4095)
		(width 0.254)
		(layer "F.Cu")
		(net "VT235_VDES_RCC")
	)
	(segment
		(start 169.727118 -101.592126)
		(end 169.781474 -101.646482)
		(width 0.254)
		(layer "F.Cu")
		(net "VT235_VDES_RCC")
	)
	(segment
		(start 170.658028 -101.646482)
		(end 169.781474 -101.646482)
		(width 0.254)
		(layer "F.Cu")
		(net "VT235_VDES_RCC")
	)
	(segment
		(start 169.727118 -100.629974)
		(end 169.727118 -101.592126)
		(width 0.254)
		(layer "F.Cu")
		(net "VT235_VDES_RCC")
	)
	(segment
		(start 171.589446 -102.5779)
		(end 170.658028 -101.646482)
		(width 0.254)
		(layer "F.Cu")
		(net "VT235_VDES_RCC")
	)
	(segment
		(start 174.4472 -102.5779)
		(end 171.589446 -102.5779)
		(width 0.254)
		(layer "F.Cu")
		(net "VT235_VDES_RCC")
	)
	(segment
		(start 175.6156 -101.4095)
		(end 175.2092 -101.8159)
		(width 0.254)
		(layer "F.Cu")
		(net "VT235_VDES_RCC")
	)
	(segment
		(start 175.2092 -101.8159)
		(end 174.4472 -102.5779)
		(width 0.254)
		(layer "F.Cu")
		(net "VT235_VDES_RCC")
	)
	(segment
		(start 176.3522 -100.2411)
		(end 176.7078 -100.5967)
		(width 0.254)
		(layer "F.Cu")
		(net "VT235_VDES_RCC")
	)
	(via
		(at 175.2092 -101.8159)
		(size 0.6604)
		(drill 0.3302)
		(layers "F.Cu" "B.Cu")
		(net "VT235_VDES_RCC")
	)
	(segment
		(start 176.7078 -97.4344)
		(end 176.7078 -97.97796)
		(width 0.254)
		(layer "F.Cu")
		(net "VT235_VDES_RC")
	)
	(segment
		(start 176.5554 -96.9645)
		(end 176.5554 -97.282)
		(width 0.254)
		(layer "F.Cu")
		(net "VT235_VDES_RC")
	)
	(segment
		(start 176.7078 -97.97796)
		(end 176.7078 -99.0727)
		(width 0.254)
		(layer "F.Cu")
		(net "VT235_VDES_RC")
	)
	(segment
		(start 176.5554 -97.282)
		(end 176.7078 -97.4344)
		(width 0.254)
		(layer "F.Cu")
		(net "VT235_VDES_RC")
	)
	(via
		(at 176.7078 -97.97796)
		(size 0.6604)
		(drill 0.3302)
		(layers "F.Cu" "B.Cu")
		(net "VT235_VDES_RC")
	)
	(segment
		(start 171.457874 -98.509074)
		(end 170.909996 -97.961196)
		(width 0.254)
		(layer "F.Cu")
		(net "VT235_VDES")
	)
	(segment
		(start 174.5361 -97.9297)
		(end 175.387 -97.9297)
		(width 0.254)
		(layer "F.Cu")
		(net "VT235_VDES")
	)
	(segment
		(start 171.661074 -99.716082)
		(end 171.661074 -99.106482)
		(width 0.254)
		(layer "F.Cu")
		(net "VT235_VDES")
	)
	(segment
		(start 175.6156 -98.1583)
		(end 175.387 -97.9297)
		(width 0.254)
		(layer "F.Cu")
		(net "VT235_VDES")
	)
	(segment
		(start 170.909996 -97.961196)
		(end 170.909996 -97.17151)
		(width 0.254)
		(layer "F.Cu")
		(net "VT235_VDES")
	)
	(segment
		(start 171.661074 -99.106482)
		(end 171.457874 -98.903282)
		(width 0.254)
		(layer "F.Cu")
		(net "VT235_VDES")
	)
	(segment
		(start 175.6156 -99.3521)
		(end 175.6156 -98.1583)
		(width 0.254)
		(layer "F.Cu")
		(net "VT235_VDES")
	)
	(segment
		(start 171.457874 -98.903282)
		(end 171.457874 -98.509074)
		(width 0.254)
		(layer "F.Cu")
		(net "VT235_VDES")
	)
	(via
		(at 174.5361 -97.9297)
		(size 0.508)
		(drill 0.254)
		(layers "F.Cu" "B.Cu")
		(net "VT235_VDES")
	)
	(via
		(at 171.457874 -98.903282)
		(size 0.508)
		(drill 0.254)
		(layers "F.Cu" "B.Cu")
		(net "VT235_VDES")
	)
	(via
		(at 173.740318 -98.903282)
		(size 0.6096)
		(drill 0.3048)
		(layers "F.Cu" "B.Cu")
		(net "VT235_VDES")
	)
	(segment
		(start 174.5361 -97.9297)
		(end 174.5361 -98.45929)
		(width 0.254)
		(layer "B.Cu")
		(net "VT235_VDES")
	)
	(segment
		(start 170.721274 -98.204782)
		(end 170.759374 -98.204782)
		(width 0.254)
		(layer "B.Cu")
		(net "VT235_VDES")
	)
	(segment
		(start 170.759374 -98.204782)
		(end 171.457874 -98.903282)
		(width 0.254)
		(layer "B.Cu")
		(net "VT235_VDES")
	)
	(segment
		(start 171.457874 -98.903282)
		(end 173.740318 -98.903282)
		(width 0.254)
		(layer "B.Cu")
		(net "VT235_VDES")
	)
	(segment
		(start 174.5361 -98.45929)
		(end 174.092108 -98.903282)
		(width 0.254)
		(layer "B.Cu")
		(net "VT235_VDES")
	)
	(segment
		(start 174.092108 -98.903282)
		(end 173.740318 -98.903282)
		(width 0.254)
		(layer "B.Cu")
		(net "VT235_VDES")
	)
	(segment
		(start 171.795694 -95.285814)
		(end 173.441614 -95.285814)
		(width 0.254)
		(layer "F.Cu")
		(net "VT235_VDDL")
	)
	(segment
		(start 173.6852 -96.0628)
		(end 173.863 -95.885)
		(width 0.254)
		(layer "F.Cu")
		(net "VT235_VDDL")
	)
	(segment
		(start 173.863 -95.7072)
		(end 173.863 -95.885)
		(width 0.254)
		(layer "F.Cu")
		(net "VT235_VDDL")
	)
	(segment
		(start 172.8978 -96.0628)
		(end 173.6852 -96.0628)
		(width 0.254)
		(layer "F.Cu")
		(net "VT235_VDDL")
	)
	(segment
		(start 173.441614 -95.285814)
		(end 173.863 -95.7072)
		(width 0.254)
		(layer "F.Cu")
		(net "VT235_VDDL")
	)
	(via
		(at 172.8978 -96.0628)
		(size 0.508)
		(drill 0.254)
		(layers "F.Cu" "B.Cu")
		(net "VT235_VDDL")
	)
	(via
		(at 172.8978 -94.935802)
		(size 0.6096)
		(drill 0.3048)
		(layers "F.Cu" "B.Cu")
		(net "VT235_VDDL")
	)
	(segment
		(start 172.8978 -94.935802)
		(end 172.8978 -93.161866)
		(width 0.254)
		(layer "B.Cu")
		(net "VT235_VDDL")
	)
	(segment
		(start 172.8724 -94.961202)
		(end 172.8978 -94.935802)
		(width 0.254)
		(layer "B.Cu")
		(net "VT235_VDDL")
	)
	(segment
		(start 172.8978 -96.0628)
		(end 172.8724 -96.0374)
		(width 0.254)
		(layer "B.Cu")
		(net "VT235_VDDL")
	)
	(segment
		(start 172.8724 -96.0374)
		(end 172.8724 -94.961202)
		(width 0.254)
		(layer "B.Cu")
		(net "VT235_VDDL")
	)
	(segment
		(start 172.333412 -98.484182)
		(end 173.625002 -98.484182)
		(width 0.254)
		(layer "F.Cu")
		(net "VT235_PGIN")
	)
	(segment
		(start 174.645574 -99.504754)
		(end 173.625002 -98.484182)
		(width 0.254)
		(layer "F.Cu")
		(net "VT235_PGIN")
	)
	(segment
		(start 174.645574 -99.665282)
		(end 174.645574 -99.504754)
		(width 0.254)
		(layer "F.Cu")
		(net "VT235_PGIN")
	)
	(segment
		(start 171.410122 -97.17151)
		(end 171.410122 -97.560892)
		(width 0.254)
		(layer "F.Cu")
		(net "VT235_PGIN")
	)
	(segment
		(start 171.410122 -97.560892)
		(end 172.333412 -98.484182)
		(width 0.254)
		(layer "F.Cu")
		(net "VT235_PGIN")
	)
	(segment
		(start 174.645574 -99.665282)
		(end 173.680374 -99.665282)
		(width 0.254)
		(layer "F.Cu")
		(net "VT235_PGIN")
	)
	(via
		(at 173.625002 -98.484182)
		(size 0.6604)
		(drill 0.3302)
		(layers "F.Cu" "B.Cu")
		(net "VT235_PGIN")
	)
	(segment
		(start 165.95344 -98.09734)
		(end 166.46906 -98.09734)
		(width 0.254)
		(layer "F.Cu")
		(net "VT235_IRIP")
	)
	(segment
		(start 167.39489 -97.17151)
		(end 167.910002 -97.17151)
		(width 0.254)
		(layer "F.Cu")
		(net "VT235_IRIP")
	)
	(segment
		(start 166.46906 -98.09734)
		(end 167.39489 -97.17151)
		(width 0.254)
		(layer "F.Cu")
		(net "VT235_IRIP")
	)
	(via
		(at 166.885874 -97.7646)
		(size 0.6096)
		(drill 0.3048)
		(layers "F.Cu" "B.Cu")
		(net "VT235_IRIP")
	)
	(via
		(at 165.95344 -98.09734)
		(size 0.508)
		(drill 0.254)
		(layers "F.Cu" "B.Cu")
		(net "VT235_IRIP")
	)
	(segment
		(start 166.631874 -98.09734)
		(end 166.885874 -97.84334)
		(width 0.254)
		(layer "B.Cu")
		(net "VT235_IRIP")
	)
	(segment
		(start 166.885874 -97.7646)
		(end 166.885874 -96.553782)
		(width 0.254)
		(layer "B.Cu")
		(net "VT235_IRIP")
	)
	(segment
		(start 166.885874 -97.84334)
		(end 166.885874 -97.7646)
		(width 0.254)
		(layer "B.Cu")
		(net "VT235_IRIP")
	)
	(segment
		(start 165.95344 -98.09734)
		(end 166.631874 -98.09734)
		(width 0.254)
		(layer "B.Cu")
		(net "VT235_IRIP")
	)
	(segment
		(start 169.410126 -98.15703)
		(end 169.410126 -97.17151)
		(width 0.254)
		(layer "F.Cu")
		(net "VT235_IMAX")
	)
	(segment
		(start 168.917874 -98.649282)
		(end 169.410126 -98.15703)
		(width 0.254)
		(layer "F.Cu")
		(net "VT235_IMAX")
	)
	(via
		(at 168.917874 -98.649282)
		(size 0.508)
		(drill 0.254)
		(layers "F.Cu" "B.Cu")
		(net "VT235_IMAX")
	)
	(via
		(at 168.155366 -97.720658)
		(size 0.6096)
		(drill 0.3048)
		(layers "F.Cu" "B.Cu")
		(net "VT235_IMAX")
	)
	(segment
		(start 168.028874 -96.553782)
		(end 168.028874 -97.594166)
		(width 0.254)
		(layer "B.Cu")
		(net "VT235_IMAX")
	)
	(segment
		(start 168.917874 -98.483166)
		(end 168.155366 -97.720658)
		(width 0.254)
		(layer "B.Cu")
		(net "VT235_IMAX")
	)
	(segment
		(start 168.917874 -98.649282)
		(end 168.917874 -98.483166)
		(width 0.254)
		(layer "B.Cu")
		(net "VT235_IMAX")
	)
	(segment
		(start 168.028874 -97.594166)
		(end 168.155366 -97.720658)
		(width 0.254)
		(layer "B.Cu")
		(net "VT235_IMAX")
	)
	(segment
		(start 166.533322 -98.889312)
		(end 166.837614 -98.58502)
		(width 0.254)
		(layer "F.Cu")
		(net "VT235_EN")
	)
	(segment
		(start 167.458136 -98.58502)
		(end 168.410128 -97.633028)
		(width 0.254)
		(layer "F.Cu")
		(net "VT235_EN")
	)
	(segment
		(start 166.154354 -99.26828)
		(end 164.96284 -99.26828)
		(width 0.254)
		(layer "F.Cu")
		(net "VT235_EN")
	)
	(segment
		(start 164.96538 -100.4062)
		(end 164.96538 -99.27082)
		(width 0.254)
		(layer "F.Cu")
		(net "VT235_EN")
	)
	(segment
		(start 164.96538 -99.27082)
		(end 164.96284 -99.26828)
		(width 0.254)
		(layer "F.Cu")
		(net "VT235_EN")
	)
	(segment
		(start 168.410128 -97.633028)
		(end 168.410128 -97.17151)
		(width 0.254)
		(layer "F.Cu")
		(net "VT235_EN")
	)
	(segment
		(start 166.837614 -98.58502)
		(end 167.458136 -98.58502)
		(width 0.254)
		(layer "F.Cu")
		(net "VT235_EN")
	)
	(segment
		(start 166.533322 -98.889312)
		(end 166.154354 -99.26828)
		(width 0.254)
		(layer "F.Cu")
		(net "VT235_EN")
	)
	(via
		(at 166.533322 -98.889312)
		(size 0.6604)
		(drill 0.3302)
		(layers "F.Cu" "B.Cu")
		(net "VT235_EN")
	)
	(segment
		(start 173.44644 -94.3102)
		(end 173.228 -94.52864)
		(width 0.508)
		(layer "F.Cu")
		(net "VT235_BST")
	)
	(segment
		(start 173.080426 -94.676214)
		(end 173.228 -94.52864)
		(width 0.3556)
		(layer "F.Cu")
		(net "VT235_BST")
	)
	(segment
		(start 172.586142 -94.785942)
		(end 172.69587 -94.676214)
		(width 0.3556)
		(layer "F.Cu")
		(net "VT235_BST")
	)
	(segment
		(start 174.3202 -94.3102)
		(end 173.44644 -94.3102)
		(width 0.508)
		(layer "F.Cu")
		(net "VT235_BST")
	)
	(segment
		(start 172.69587 -94.676214)
		(end 173.080426 -94.676214)
		(width 0.3556)
		(layer "F.Cu")
		(net "VT235_BST")
	)
	(segment
		(start 171.795694 -94.785942)
		(end 172.586142 -94.785942)
		(width 0.3556)
		(layer "F.Cu")
		(net "VT235_BST")
	)
	(via
		(at 173.228 -94.52864)
		(size 0.6604)
		(drill 0.3302)
		(layers "F.Cu" "B.Cu")
		(net "VT235_BST")
	)
	(segment
		(start 169.909998 -98.625406)
		(end 169.909998 -97.17151)
		(width 0.254)
		(layer "F.Cu")
		(net "VT235_BIAS")
	)
	(segment
		(start 169.933874 -98.649282)
		(end 169.909998 -98.625406)
		(width 0.254)
		(layer "F.Cu")
		(net "VT235_BIAS")
	)
	(via
		(at 169.933874 -98.649282)
		(size 0.508)
		(drill 0.254)
		(layers "F.Cu" "B.Cu")
		(net "VT235_BIAS")
	)
	(via
		(at 169.5196 -97.7138)
		(size 0.6096)
		(drill 0.3048)
		(layers "F.Cu" "B.Cu")
		(net "VT235_BIAS")
	)
	(segment
		(start 169.933874 -98.128074)
		(end 169.5196 -97.7138)
		(width 0.254)
		(layer "B.Cu")
		(net "VT235_BIAS")
	)
	(segment
		(start 169.933874 -98.649282)
		(end 169.933874 -98.128074)
		(width 0.254)
		(layer "B.Cu")
		(net "VT235_BIAS")
	)
	(segment
		(start 169.171874 -97.366074)
		(end 169.5196 -97.7138)
		(width 0.254)
		(layer "B.Cu")
		(net "VT235_BIAS")
	)
	(segment
		(start 169.171874 -96.553782)
		(end 169.171874 -97.366074)
		(width 0.254)
		(layer "B.Cu")
		(net "VT235_BIAS")
	)
	(segment
		(start 165.787832 -96.218248)
		(end 164.629084 -96.218248)
		(width 0.254)
		(layer "F.Cu")
		(net "VT235_AVDD")
	)
	(segment
		(start 166.758874 -95.474282)
		(end 166.758366 -95.474282)
		(width 0.254)
		(layer "F.Cu")
		(net "VT235_AVDD")
	)
	(segment
		(start 168.475406 -95.285814)
		(end 167.52443 -95.285814)
		(width 0.254)
		(layer "F.Cu")
		(net "VT235_AVDD")
	)
	(segment
		(start 171.273216 -95.78594)
		(end 171.088558 -95.601282)
		(width 0.254)
		(layer "F.Cu")
		(net "VT235_AVDD")
	)
	(segment
		(start 166.947342 -95.285814)
		(end 166.758874 -95.474282)
		(width 0.254)
		(layer "F.Cu")
		(net "VT235_AVDD")
	)
	(segment
		(start 171.795694 -95.78594)
		(end 171.273216 -95.78594)
		(width 0.254)
		(layer "F.Cu")
		(net "VT235_AVDD")
	)
	(segment
		(start 166.758366 -95.474282)
		(end 166.0144 -96.218248)
		(width 0.254)
		(layer "F.Cu")
		(net "VT235_AVDD")
	)
	(segment
		(start 166.0144 -96.218248)
		(end 165.787832 -96.218248)
		(width 0.254)
		(layer "F.Cu")
		(net "VT235_AVDD")
	)
	(segment
		(start 164.629084 -96.218248)
		(end 164.496242 -96.085406)
		(width 0.254)
		(layer "F.Cu")
		(net "VT235_AVDD")
	)
	(segment
		(start 171.088558 -95.601282)
		(end 168.790874 -95.601282)
		(width 0.254)
		(layer "F.Cu")
		(net "VT235_AVDD")
	)
	(segment
		(start 164.496242 -96.085406)
		(end 163.298378 -96.085406)
		(width 0.254)
		(layer "F.Cu")
		(net "VT235_AVDD")
	)
	(segment
		(start 168.790874 -95.601282)
		(end 168.475406 -95.285814)
		(width 0.254)
		(layer "F.Cu")
		(net "VT235_AVDD")
	)
	(segment
		(start 167.52443 -95.285814)
		(end 166.947342 -95.285814)
		(width 0.254)
		(layer "F.Cu")
		(net "VT235_AVDD")
	)
	(via
		(at 165.787832 -96.218248)
		(size 0.6604)
		(drill 0.3302)
		(layers "F.Cu" "B.Cu")
		(net "VT235_AVDD")
	)
	(segment
		(start 170.599862 -32.399986)
		(end 170.200066 -32.00019)
		(width 0.3048)
		(layer "F.Cu")
		(net "PCE_VDDH")
	)
	(segment
		(start 174.599854 -29.999686)
		(end 174.599854 -29.99994)
		(width 0.3048)
		(layer "F.Cu")
		(net "PCE_VDDH")
	)
	(segment
		(start 176.431956 -31.999936)
		(end 176.614582 -31.81731)
		(width 0.2032)
		(layer "F.Cu")
		(net "PCE_VDDH")
	)
	(segment
		(start 173.800008 -32.399986)
		(end 173.400212 -32.00019)
		(width 0.3048)
		(layer "F.Cu")
		(net "PCE_VDDH")
	)
	(segment
		(start 175.800004 -31.999936)
		(end 176.431956 -31.999936)
		(width 0.2032)
		(layer "F.Cu")
		(net "PCE_VDDH")
	)
	(segment
		(start 168.999916 -32.399986)
		(end 168.60012 -32.00019)
		(width 0.3048)
		(layer "F.Cu")
		(net "PCE_VDDH")
	)
	(segment
		(start 176.614582 -31.81731)
		(end 176.614582 -31.185358)
		(width 0.2032)
		(layer "F.Cu")
		(net "PCE_VDDH")
	)
	(segment
		(start 175.399954 -32.399986)
		(end 175.000158 -32.00019)
		(width 0.3048)
		(layer "F.Cu")
		(net "PCE_VDDH")
	)
	(segment
		(start 169.800016 -30.80004)
		(end 169.399966 -30.39999)
		(width 0.254)
		(layer "F.Cu")
		(net "PCE_VDDH")
	)
	(segment
		(start 172.199808 -30.80004)
		(end 171.800012 -30.400244)
		(width 0.3048)
		(layer "F.Cu")
		(net "PCE_VDDH")
	)
	(segment
		(start 174.200058 -29.59989)
		(end 174.599854 -29.999686)
		(width 0.3048)
		(layer "F.Cu")
		(net "PCE_VDDH")
	)
	(segment
		(start 172.199808 -32.399986)
		(end 171.800012 -32.00019)
		(width 0.3048)
		(layer "F.Cu")
		(net "PCE_VDDH")
	)
	(segment
		(start 176.614582 -31.185358)
		(end 176.9999 -30.80004)
		(width 0.2032)
		(layer "F.Cu")
		(net "PCE_VDDH")
	)
	(via
		(at 171.800012 -30.400244)
		(size 0.508)
		(drill 0.254)
		(layers "F.Cu" "B.Cu")
		(net "PCE_VDDH")
	)
	(via
		(at 168.60012 -32.00019)
		(size 0.508)
		(drill 0.254)
		(layers "F.Cu" "B.Cu")
		(net "PCE_VDDH")
	)
	(via
		(at 195.0974 -27.8638)
		(size 0.508)
		(drill 0.254)
		(layers "F.Cu" "B.Cu")
		(net "PCE_VDDH")
	)
	(via
		(at 195.1355 -27.0002)
		(size 0.508)
		(drill 0.254)
		(layers "F.Cu" "B.Cu")
		(net "PCE_VDDH")
	)
	(via
		(at 175.000158 -32.00019)
		(size 0.508)
		(drill 0.254)
		(layers "F.Cu" "B.Cu")
		(net "PCE_VDDH")
	)
	(via
		(at 175.800004 -31.999936)
		(size 0.508)
		(drill 0.254)
		(layers "F.Cu" "B.Cu")
		(net "PCE_VDDH")
	)
	(via
		(at 169.399966 -30.39999)
		(size 0.508)
		(drill 0.254)
		(layers "F.Cu" "B.Cu")
		(net "PCE_VDDH")
	)
	(via
		(at 170.200066 -32.00019)
		(size 0.508)
		(drill 0.254)
		(layers "F.Cu" "B.Cu")
		(net "PCE_VDDH")
	)
	(via
		(at 173.400212 -32.00019)
		(size 0.508)
		(drill 0.254)
		(layers "F.Cu" "B.Cu")
		(net "PCE_VDDH")
	)
	(via
		(at 194.8688 -28.8544)
		(size 0.6096)
		(drill 0.3048)
		(layers "F.Cu" "B.Cu")
		(net "PCE_VDDH")
	)
	(via
		(at 171.800012 -32.00019)
		(size 0.508)
		(drill 0.254)
		(layers "F.Cu" "B.Cu")
		(net "PCE_VDDH")
	)
	(via
		(at 174.200058 -29.59989)
		(size 0.508)
		(drill 0.254)
		(layers "F.Cu" "B.Cu")
		(net "PCE_VDDH")
	)
	(segment
		(start 173.7995 -32.6898)
		(end 173.400212 -32.290512)
		(width 0.508)
		(layer "B.Cu")
		(net "PCE_VDDH")
	)
	(segment
		(start 168.6941 -32.6771)
		(end 168.6941 -32.09417)
		(width 0.508)
		(layer "B.Cu")
		(net "PCE_VDDH")
	)
	(segment
		(start 168.6941 -32.09417)
		(end 168.60012 -32.00019)
		(width 0.508)
		(layer "B.Cu")
		(net "PCE_VDDH")
	)
	(segment
		(start 169.399966 -30.39999)
		(end 169.399966 -31.20009)
		(width 0.3048)
		(layer "B.Cu")
		(net "PCE_VDDH")
	)
	(segment
		(start 173.400212 -32.290512)
		(end 173.400212 -32.00019)
		(width 0.508)
		(layer "B.Cu")
		(net "PCE_VDDH")
	)
	(segment
		(start 171.800012 -32.634174)
		(end 171.800012 -32.00019)
		(width 0.508)
		(layer "B.Cu")
		(net "PCE_VDDH")
	)
	(segment
		(start 171.864528 -32.69869)
		(end 171.800012 -32.634174)
		(width 0.508)
		(layer "B.Cu")
		(net "PCE_VDDH")
	)
	(segment
		(start 169.399966 -31.20009)
		(end 170.200066 -32.00019)
		(width 0.3048)
		(layer "B.Cu")
		(net "PCE_VDDH")
	)
	(segment
		(start 71.882 -103.9495)
		(end 70.866 -103.9495)
		(width 0.254)
		(layer "F.Cu")
		(net "P3V3_VFB_R")
	)
	(segment
		(start 71.8947 -105.6513)
		(end 71.9074 -105.664)
		(width 0.254)
		(layer "F.Cu")
		(net "P3V3_VFB_R")
	)
	(segment
		(start 71.8947 -103.9622)
		(end 71.882 -103.9495)
		(width 0.254)
		(layer "F.Cu")
		(net "P3V3_VFB_R")
	)
	(segment
		(start 71.9074 -105.664)
		(end 71.9074 -106.2736)
		(width 0.254)
		(layer "F.Cu")
		(net "P3V3_VFB_R")
	)
	(segment
		(start 71.8947 -105.0544)
		(end 71.8947 -105.6513)
		(width 0.254)
		(layer "F.Cu")
		(net "P3V3_VFB_R")
	)
	(segment
		(start 71.8947 -105.0544)
		(end 71.8947 -103.9622)
		(width 0.254)
		(layer "F.Cu")
		(net "P3V3_VFB_R")
	)
	(via
		(at 71.8947 -105.0544)
		(size 0.6604)
		(drill 0.3302)
		(layers "F.Cu" "B.Cu")
		(net "P3V3_VFB_R")
	)
	(segment
		(start 71.374 -102.0445)
		(end 71.882 -102.5525)
		(width 0.254)
		(layer "F.Cu")
		(net "P3V3_VFB")
	)
	(segment
		(start 67.77355 -102.35946)
		(end 68.568316 -102.35946)
		(width 0.254)
		(layer "F.Cu")
		(net "P3V3_VFB")
	)
	(segment
		(start 68.568316 -102.35946)
		(end 69.269356 -103.0605)
		(width 0.254)
		(layer "F.Cu")
		(net "P3V3_VFB")
	)
	(segment
		(start 69.269356 -103.0605)
		(end 69.977 -103.0605)
		(width 0.254)
		(layer "F.Cu")
		(net "P3V3_VFB")
	)
	(segment
		(start 71.882 -102.5525)
		(end 71.882 -103.0605)
		(width 0.254)
		(layer "F.Cu")
		(net "P3V3_VFB")
	)
	(segment
		(start 66.475102 -102.949502)
		(end 67.183508 -102.949502)
		(width 0.254)
		(layer "F.Cu")
		(net "P3V3_VFB")
	)
	(segment
		(start 70.866 -102.0445)
		(end 71.374 -102.0445)
		(width 0.254)
		(layer "F.Cu")
		(net "P3V3_VFB")
	)
	(segment
		(start 70.866 -103.0605)
		(end 69.977 -103.0605)
		(width 0.254)
		(layer "F.Cu")
		(net "P3V3_VFB")
	)
	(segment
		(start 67.183508 -102.949502)
		(end 67.77355 -102.35946)
		(width 0.254)
		(layer "F.Cu")
		(net "P3V3_VFB")
	)
	(segment
		(start 71.882 -103.0605)
		(end 70.866 -103.0605)
		(width 0.254)
		(layer "F.Cu")
		(net "P3V3_VFB")
	)
	(via
		(at 68.568316 -102.35946)
		(size 0.6604)
		(drill 0.3302)
		(layers "F.Cu" "B.Cu")
		(net "P3V3_VFB")
	)
	(segment
		(start 65.1891 -105.8926)
		(end 64.7065 -105.41)
		(width 0.508)
		(layer "B.Cu")
		(net "P3V3_VBST_RC")
	)
	(segment
		(start 66.7004 -105.8926)
		(end 65.1891 -105.8926)
		(width 0.508)
		(layer "B.Cu")
		(net "P3V3_VBST_RC")
	)
	(segment
		(start 65.067688 -104.02062)
		(end 64.974978 -103.92791)
		(width 0.254)
		(layer "F.Cu")
		(net "P3V3_VBST")
	)
	(segment
		(start 64.974978 -103.92791)
		(end 64.974978 -102.949502)
		(width 0.254)
		(layer "F.Cu")
		(net "P3V3_VBST")
	)
	(via
		(at 65.819528 -103.114348)
		(size 0.6096)
		(drill 0.3048)
		(layers "F.Cu" "B.Cu")
		(net "P3V3_VBST")
	)
	(via
		(at 65.067688 -104.02062)
		(size 0.508)
		(drill 0.254)
		(layers "F.Cu" "B.Cu")
		(net "P3V3_VBST")
	)
	(segment
		(start 66.7004 -103.464106)
		(end 66.350642 -103.114348)
		(width 0.508)
		(layer "B.Cu")
		(net "P3V3_VBST")
	)
	(segment
		(start 65.409064 -103.114348)
		(end 65.819528 -103.114348)
		(width 0.508)
		(layer "B.Cu")
		(net "P3V3_VBST")
	)
	(segment
		(start 65.067688 -103.455724)
		(end 65.409064 -103.114348)
		(width 0.508)
		(layer "B.Cu")
		(net "P3V3_VBST")
	)
	(segment
		(start 65.067688 -104.02062)
		(end 65.067688 -103.455724)
		(width 0.508)
		(layer "B.Cu")
		(net "P3V3_VBST")
	)
	(segment
		(start 66.350642 -103.114348)
		(end 65.819528 -103.114348)
		(width 0.508)
		(layer "B.Cu")
		(net "P3V3_VBST")
	)
	(segment
		(start 66.7004 -104.3686)
		(end 66.7004 -103.464106)
		(width 0.508)
		(layer "B.Cu")
		(net "P3V3_VBST")
	)
	(segment
		(start 57.5818 -100.318316)
		(end 57.5818 -100.965)
		(width 0.508)
		(layer "F.Cu")
		(net "P3V3_SNB")
	)
	(segment
		(start 57.5818 -100.965)
		(end 57.4548 -101.092)
		(width 0.508)
		(layer "F.Cu")
		(net "P3V3_SNB")
	)
	(segment
		(start 57.4548 -101.7524)
		(end 57.4548 -102.7811)
		(width 0.508)
		(layer "F.Cu")
		(net "P3V3_SNB")
	)
	(segment
		(start 57.4548 -101.092)
		(end 57.4548 -101.7524)
		(width 0.508)
		(layer "F.Cu")
		(net "P3V3_SNB")
	)
	(via
		(at 57.4548 -101.7524)
		(size 0.6604)
		(drill 0.3302)
		(layers "F.Cu" "B.Cu")
		(net "P3V3_SNB")
	)
	(segment
		(start 60.733686 -109.21238)
		(end 64.191388 -109.21238)
		(width 0.254)
		(layer "F.Cu")
		(net "P3V3_OUT")
	)
	(segment
		(start 63.0174 -120.8532)
		(end 64.2874 -120.8532)
		(width 0.381)
		(layer "F.Cu")
		(net "P3V3_OUT")
	)
	(segment
		(start 60.15228 -109.793786)
		(end 60.733686 -109.21238)
		(width 0.254)
		(layer "F.Cu")
		(net "P3V3_OUT")
	)
	(segment
		(start 71.9074 -107.7976)
		(end 71.9074 -108.739178)
		(width 0.381)
		(layer "F.Cu")
		(net "P3V3_OUT")
	)
	(segment
		(start 66.718688 -118.421912)
		(end 66.718688 -117.046502)
		(width 0.381)
		(layer "F.Cu")
		(net "P3V3_OUT")
	)
	(segment
		(start 64.453008 -109.474)
		(end 65.024 -109.474)
		(width 0.254)
		(layer "F.Cu")
		(net "P3V3_OUT")
	)
	(segment
		(start 64.191388 -109.21238)
		(end 64.453008 -109.474)
		(width 0.254)
		(layer "F.Cu")
		(net "P3V3_OUT")
	)
	(segment
		(start 71.9074 -108.739178)
		(end 66.718688 -113.92789)
		(width 0.381)
		(layer "F.Cu")
		(net "P3V3_OUT")
	)
	(segment
		(start 64.2874 -120.8532)
		(end 66.718688 -118.421912)
		(width 0.381)
		(layer "F.Cu")
		(net "P3V3_OUT")
	)
	(segment
		(start 66.718688 -113.92789)
		(end 66.718688 -117.046502)
		(width 0.381)
		(layer "F.Cu")
		(net "P3V3_OUT")
	)
	(segment
		(start 60.15228 -111.577374)
		(end 60.15228 -109.793786)
		(width 0.254)
		(layer "F.Cu")
		(net "P3V3_OUT")
	)
	(via
		(at 66.718688 -117.046502)
		(size 0.6604)
		(drill 0.3302)
		(layers "F.Cu" "B.Cu")
		(net "P3V3_OUT")
	)
	(segment
		(start 66.548 -109.474)
		(end 68.8975 -109.474)
		(width 0.254)
		(layer "F.Cu")
		(net "P3V3_LL_R")
	)
	(segment
		(start 66.548 -108.966)
		(end 66.548 -109.474)
		(width 0.254)
		(layer "F.Cu")
		(net "P3V3_LL_R")
	)
	(segment
		(start 69.977 -103.9495)
		(end 69.977 -105.1052)
		(width 0.254)
		(layer "F.Cu")
		(net "P3V3_LL_R")
	)
	(segment
		(start 65.913 -108.331)
		(end 66.548 -108.966)
		(width 0.254)
		(layer "F.Cu")
		(net "P3V3_LL_R")
	)
	(segment
		(start 69.977 -108.3945)
		(end 69.977 -105.1052)
		(width 0.254)
		(layer "F.Cu")
		(net "P3V3_LL_R")
	)
	(segment
		(start 68.8975 -109.474)
		(end 69.977 -108.3945)
		(width 0.254)
		(layer "F.Cu")
		(net "P3V3_LL_R")
	)
	(via
		(at 69.977 -105.1052)
		(size 0.6604)
		(drill 0.3302)
		(layers "F.Cu" "B.Cu")
		(net "P3V3_LL_R")
	)
	(segment
		(start 68.453 -105.8545)
		(end 68.453 -104.0384)
		(width 0.254)
		(layer "F.Cu")
		(net "P3V3_EN")
	)
	(segment
		(start 68.453 -104.0384)
		(end 68.3006 -103.886)
		(width 0.254)
		(layer "F.Cu")
		(net "P3V3_EN")
	)
	(segment
		(start 66.31051 -103.886)
		(end 65.974976 -103.550466)
		(width 0.254)
		(layer "F.Cu")
		(net "P3V3_EN")
	)
	(segment
		(start 65.974976 -103.550466)
		(end 65.974976 -102.949502)
		(width 0.254)
		(layer "F.Cu")
		(net "P3V3_EN")
	)
	(segment
		(start 68.3006 -103.886)
		(end 66.31051 -103.886)
		(width 0.254)
		(layer "F.Cu")
		(net "P3V3_EN")
	)
	(via
		(at 68.453 -104.0384)
		(size 0.6604)
		(drill 0.3302)
		(layers "F.Cu" "B.Cu")
		(net "P3V3_EN")
	)
	(segment
		(start 178.0286 -112.8776)
		(end 178.0286 -112.21339)
		(width 0.254)
		(layer "F.Cu")
		(net "P1V8_E_SS")
	)
	(segment
		(start 177.70602 -113.20018)
		(end 178.0286 -112.8776)
		(width 0.254)
		(layer "F.Cu")
		(net "P1V8_E_SS")
	)
	(segment
		(start 178.0286 -112.21339)
		(end 178.08448 -112.15751)
		(width 0.254)
		(layer "F.Cu")
		(net "P1V8_E_SS")
	)
	(segment
		(start 178.08448 -112.15751)
		(end 178.08448 -111.09198)
		(width 0.254)
		(layer "F.Cu")
		(net "P1V8_E_SS")
	)
	(segment
		(start 177.70602 -113.672112)
		(end 177.70602 -113.20018)
		(width 0.254)
		(layer "F.Cu")
		(net "P1V8_E_SS")
	)
	(via
		(at 178.0286 -112.21339)
		(size 0.6604)
		(drill 0.3302)
		(layers "F.Cu" "B.Cu")
		(net "P1V8_E_SS")
	)
	(segment
		(start 151.7015 -84.9249)
		(end 151.7015 -84.012024)
		(width 0.127)
		(layer "F.Cu")
		(net "P1V8_E_SENSE")
	)
	(segment
		(start 152.4635 -84.775802)
		(end 153.67508 -84.775802)
		(width 0.127)
		(layer "F.Cu")
		(net "P1V8_E_SENSE")
	)
	(segment
		(start 151.544274 -83.854798)
		(end 150.561802 -83.854798)
		(width 0.127)
		(layer "F.Cu")
		(net "P1V8_E_SENSE")
	)
	(segment
		(start 151.7015 -84.9249)
		(end 152.314402 -84.9249)
		(width 0.127)
		(layer "F.Cu")
		(net "P1V8_E_SENSE")
	)
	(segment
		(start 150.561802 -83.854798)
		(end 150.4696 -83.947)
		(width 0.127)
		(layer "F.Cu")
		(net "P1V8_E_SENSE")
	)
	(segment
		(start 150.4696 -83.947)
		(end 149.9489 -83.947)
		(width 0.127)
		(layer "F.Cu")
		(net "P1V8_E_SENSE")
	)
	(segment
		(start 151.7015 -84.012024)
		(end 151.544274 -83.854798)
		(width 0.127)
		(layer "F.Cu")
		(net "P1V8_E_SENSE")
	)
	(segment
		(start 152.314402 -84.9249)
		(end 152.4635 -84.775802)
		(width 0.127)
		(layer "F.Cu")
		(net "P1V8_E_SENSE")
	)
	(via
		(at 151.544274 -83.854798)
		(size 0.6604)
		(drill 0.3302)
		(layers "F.Cu" "B.Cu")
		(net "P1V8_E_SENSE")
	)
	(segment
		(start 171.54652 -115.42014)
		(end 172.60824 -115.42014)
		(width 0.254)
		(layer "F.Cu")
		(net "P1V8_E_PG")
	)
	(segment
		(start 148.04517 -121.10593)
		(end 147.6375 -121.5136)
		(width 0.254)
		(layer "F.Cu")
		(net "P1V8_E_PG")
	)
	(segment
		(start 149.02688 -121.01322)
		(end 148.13788 -121.01322)
		(width 0.254)
		(layer "F.Cu")
		(net "P1V8_E_PG")
	)
	(segment
		(start 148.13788 -121.01322)
		(end 148.04517 -121.10593)
		(width 0.254)
		(layer "F.Cu")
		(net "P1V8_E_PG")
	)
	(segment
		(start 147.6375 -121.5136)
		(end 147.6375 -122.0597)
		(width 0.254)
		(layer "F.Cu")
		(net "P1V8_E_PG")
	)
	(segment
		(start 172.684948 -115.496848)
		(end 173.931326 -115.496848)
		(width 0.254)
		(layer "F.Cu")
		(net "P1V8_E_PG")
	)
	(segment
		(start 171.54652 -115.42014)
		(end 170.59656 -115.42014)
		(width 0.254)
		(layer "F.Cu")
		(net "P1V8_E_PG")
	)
	(segment
		(start 172.60824 -115.42014)
		(end 172.684948 -115.496848)
		(width 0.254)
		(layer "F.Cu")
		(net "P1V8_E_PG")
	)
	(via
		(at 148.04517 -121.10593)
		(size 0.6604)
		(drill 0.3302)
		(layers "F.Cu" "B.Cu")
		(net "P1V8_E_PG")
	)
	(via
		(at 147.6375 -122.0597)
		(size 0.508)
		(drill 0.254)
		(layers "F.Cu" "B.Cu")
		(net "P1V8_E_PG")
	)
	(via
		(at 170.59656 -115.42014)
		(size 0.508)
		(drill 0.254)
		(layers "F.Cu" "B.Cu")
		(net "P1V8_E_PG")
	)
	(segment
		(start 147.6375 -122.0597)
		(end 148.44522 -122.86742)
		(width 0.254)
		(layer "In5.Cu")
		(net "P1V8_E_PG")
	)
	(segment
		(start 170.36034 -115.42014)
		(end 170.59656 -115.42014)
		(width 0.254)
		(layer "In5.Cu")
		(net "P1V8_E_PG")
	)
	(segment
		(start 162.91306 -122.86742)
		(end 170.36034 -115.42014)
		(width 0.254)
		(layer "In5.Cu")
		(net "P1V8_E_PG")
	)
	(segment
		(start 148.44522 -122.86742)
		(end 162.91306 -122.86742)
		(width 0.254)
		(layer "In5.Cu")
		(net "P1V8_E_PG")
	)
	(via
		(at 178.90236 -118.887748)
		(size 0.7112)
		(drill 0.4064)
		(layers "F.Cu" "B.Cu")
		(net "P1V8_E_OUT")
	)
	(via
		(at 180.695854 -121.359676)
		(size 0.6096)
		(drill 0.3048)
		(layers "F.Cu" "B.Cu")
		(net "P1V8_E_OUT")
	)
	(via
		(at 179.1716 -121.2596)
		(size 0.7112)
		(drill 0.4064)
		(layers "F.Cu" "B.Cu")
		(net "P1V8_E_OUT")
	)
	(segment
		(start 179.9717 -114.5413)
		(end 179.666138 -114.846862)
		(width 0.254)
		(layer "F.Cu")
		(net "P1V8_E_FB")
	)
	(segment
		(start 181.1401 -114.1476)
		(end 181.5084 -113.7793)
		(width 0.254)
		(layer "F.Cu")
		(net "P1V8_E_FB")
	)
	(segment
		(start 182.1561 -114.36223)
		(end 181.1401 -114.36223)
		(width 0.254)
		(layer "F.Cu")
		(net "P1V8_E_FB")
	)
	(segment
		(start 181.5084 -113.7793)
		(end 181.5084 -113.34242)
		(width 0.254)
		(layer "F.Cu")
		(net "P1V8_E_FB")
	)
	(segment
		(start 180.827426 -113.34242)
		(end 181.5084 -113.34242)
		(width 0.254)
		(layer "F.Cu")
		(net "P1V8_E_FB")
	)
	(segment
		(start 180.782976 -113.29797)
		(end 180.827426 -113.34242)
		(width 0.254)
		(layer "F.Cu")
		(net "P1V8_E_FB")
	)
	(segment
		(start 180.408072 -113.29797)
		(end 179.9717 -113.734342)
		(width 0.254)
		(layer "F.Cu")
		(net "P1V8_E_FB")
	)
	(segment
		(start 179.666138 -114.846862)
		(end 178.88077 -114.846862)
		(width 0.254)
		(layer "F.Cu")
		(net "P1V8_E_FB")
	)
	(segment
		(start 180.408072 -113.29797)
		(end 180.782976 -113.29797)
		(width 0.254)
		(layer "F.Cu")
		(net "P1V8_E_FB")
	)
	(segment
		(start 181.1401 -114.36223)
		(end 181.1401 -114.1476)
		(width 0.254)
		(layer "F.Cu")
		(net "P1V8_E_FB")
	)
	(segment
		(start 179.9717 -113.734342)
		(end 179.9717 -114.5413)
		(width 0.254)
		(layer "F.Cu")
		(net "P1V8_E_FB")
	)
	(via
		(at 180.408072 -113.29797)
		(size 0.6604)
		(drill 0.3302)
		(layers "F.Cu" "B.Cu")
		(net "P1V8_E_FB")
	)
	(segment
		(start 175.25619 -112.625886)
		(end 175.106076 -112.776)
		(width 0.254)
		(layer "F.Cu")
		(net "P1V8_E_EN")
	)
	(segment
		(start 175.25619 -112.063784)
		(end 174.268384 -112.063784)
		(width 0.254)
		(layer "F.Cu")
		(net "P1V8_E_EN")
	)
	(segment
		(start 174.268384 -112.063784)
		(end 174.2059 -112.0013)
		(width 0.254)
		(layer "F.Cu")
		(net "P1V8_E_EN")
	)
	(segment
		(start 175.26 -110.998)
		(end 175.26 -110.2614)
		(width 0.254)
		(layer "F.Cu")
		(net "P1V8_E_EN")
	)
	(segment
		(start 175.0568 -110.0582)
		(end 174.4345 -110.0582)
		(width 0.254)
		(layer "F.Cu")
		(net "P1V8_E_EN")
	)
	(segment
		(start 175.26 -110.2614)
		(end 175.0568 -110.0582)
		(width 0.254)
		(layer "F.Cu")
		(net "P1V8_E_EN")
	)
	(segment
		(start 174.2059 -111.305848)
		(end 174.2059 -112.0013)
		(width 0.254)
		(layer "F.Cu")
		(net "P1V8_E_EN")
	)
	(segment
		(start 175.106076 -112.776)
		(end 175.106076 -113.672112)
		(width 0.254)
		(layer "F.Cu")
		(net "P1V8_E_EN")
	)
	(segment
		(start 175.26 -110.998)
		(end 174.513748 -110.998)
		(width 0.254)
		(layer "F.Cu")
		(net "P1V8_E_EN")
	)
	(segment
		(start 174.513748 -110.998)
		(end 174.2059 -111.305848)
		(width 0.254)
		(layer "F.Cu")
		(net "P1V8_E_EN")
	)
	(segment
		(start 175.25619 -112.063784)
		(end 175.25619 -112.625886)
		(width 0.254)
		(layer "F.Cu")
		(net "P1V8_E_EN")
	)
	(via
		(at 175.26 -110.998)
		(size 0.6604)
		(drill 0.3302)
		(layers "F.Cu" "B.Cu")
		(net "P1V8_E_EN")
	)
	(segment
		(start 170.0911 -113.8936)
		(end 170.8912 -113.8936)
		(width 0.254)
		(layer "F.Cu")
		(net "P1V8_E_BIAS")
	)
	(segment
		(start 172.95241 -114.846862)
		(end 172.182028 -114.07648)
		(width 0.254)
		(layer "F.Cu")
		(net "P1V8_E_BIAS")
	)
	(segment
		(start 170.8912 -113.8936)
		(end 171.999148 -113.8936)
		(width 0.254)
		(layer "F.Cu")
		(net "P1V8_E_BIAS")
	)
	(segment
		(start 173.931326 -114.846862)
		(end 172.95241 -114.846862)
		(width 0.254)
		(layer "F.Cu")
		(net "P1V8_E_BIAS")
	)
	(segment
		(start 171.999148 -113.8936)
		(end 172.182028 -114.07648)
		(width 0.254)
		(layer "F.Cu")
		(net "P1V8_E_BIAS")
	)
	(segment
		(start 169.6466 -113.4491)
		(end 170.0911 -113.8936)
		(width 0.254)
		(layer "F.Cu")
		(net "P1V8_E_BIAS")
	)
	(via
		(at 172.182028 -114.07648)
		(size 0.6604)
		(drill 0.3302)
		(layers "F.Cu" "B.Cu")
		(net "P1V8_E_BIAS")
	)
	(segment
		(start 152.5143 -73.8378)
		(end 152.977342 -73.374758)
		(width 0.127)
		(layer "F.Cu")
		(net "P1V8_C_SENSE")
	)
	(segment
		(start 152.977342 -72.517762)
		(end 152.977342 -73.319894)
		(width 0.127)
		(layer "F.Cu")
		(net "P1V8_C_SENSE")
	)
	(segment
		(start 152.705816 -75.019916)
		(end 152.5143 -74.8284)
		(width 0.127)
		(layer "F.Cu")
		(net "P1V8_C_SENSE")
	)
	(segment
		(start 152.977342 -73.374758)
		(end 152.977342 -73.319894)
		(width 0.127)
		(layer "F.Cu")
		(net "P1V8_C_SENSE")
	)
	(segment
		(start 153.67508 -75.019916)
		(end 152.705816 -75.019916)
		(width 0.127)
		(layer "F.Cu")
		(net "P1V8_C_SENSE")
	)
	(segment
		(start 152.599898 -72.140318)
		(end 152.977342 -72.517762)
		(width 0.127)
		(layer "F.Cu")
		(net "P1V8_C_SENSE")
	)
	(segment
		(start 152.599898 -71.124318)
		(end 152.599898 -72.140318)
		(width 0.127)
		(layer "F.Cu")
		(net "P1V8_C_SENSE")
	)
	(segment
		(start 152.5143 -74.8284)
		(end 152.5143 -73.8378)
		(width 0.127)
		(layer "F.Cu")
		(net "P1V8_C_SENSE")
	)
	(via
		(at 152.977342 -73.319894)
		(size 0.6604)
		(drill 0.3302)
		(layers "F.Cu" "B.Cu")
		(net "P1V8_C_SENSE")
	)
	(segment
		(start 144.80032 -119.65178)
		(end 145.8595 -118.5926)
		(width 0.254)
		(layer "F.Cu")
		(net "P1V8_C_PG")
	)
	(segment
		(start 142.86484 -119.65178)
		(end 144.80032 -119.65178)
		(width 0.254)
		(layer "F.Cu")
		(net "P1V8_C_PG")
	)
	(segment
		(start 179.35448 -111.24692)
		(end 179.35448 -112.11814)
		(width 0.254)
		(layer "F.Cu")
		(net "P1V8_C_PG")
	)
	(via
		(at 145.8595 -118.5926)
		(size 0.508)
		(drill 0.254)
		(layers "F.Cu" "B.Cu")
		(net "P1V8_C_PG")
	)
	(via
		(at 144.949926 -118.343172)
		(size 0.6096)
		(drill 0.3048)
		(layers "F.Cu" "B.Cu")
		(net "P1V8_C_PG")
	)
	(via
		(at 179.35448 -112.11814)
		(size 0.508)
		(drill 0.254)
		(layers "F.Cu" "B.Cu")
		(net "P1V8_C_PG")
	)
	(segment
		(start 145.199354 -118.5926)
		(end 145.8595 -118.5926)
		(width 0.254)
		(layer "B.Cu")
		(net "P1V8_C_PG")
	)
	(segment
		(start 144.777206 -118.170452)
		(end 144.949926 -118.343172)
		(width 0.254)
		(layer "B.Cu")
		(net "P1V8_C_PG")
	)
	(segment
		(start 144.777206 -117.160294)
		(end 144.777206 -118.170452)
		(width 0.254)
		(layer "B.Cu")
		(net "P1V8_C_PG")
	)
	(segment
		(start 144.949926 -118.343172)
		(end 145.199354 -118.5926)
		(width 0.254)
		(layer "B.Cu")
		(net "P1V8_C_PG")
	)
	(segment
		(start 152.20696 -120.64746)
		(end 162.60318 -120.64746)
		(width 0.254)
		(layer "In5.Cu")
		(net "P1V8_C_PG")
	)
	(segment
		(start 162.60318 -120.64746)
		(end 169.94251 -113.30813)
		(width 0.254)
		(layer "In5.Cu")
		(net "P1V8_C_PG")
	)
	(segment
		(start 145.8595 -118.5926)
		(end 150.1521 -118.5926)
		(width 0.254)
		(layer "In5.Cu")
		(net "P1V8_C_PG")
	)
	(segment
		(start 178.16449 -113.30813)
		(end 179.35448 -112.11814)
		(width 0.254)
		(layer "In5.Cu")
		(net "P1V8_C_PG")
	)
	(segment
		(start 169.94251 -113.30813)
		(end 178.16449 -113.30813)
		(width 0.254)
		(layer "In5.Cu")
		(net "P1V8_C_PG")
	)
	(segment
		(start 150.1521 -118.5926)
		(end 152.20696 -120.64746)
		(width 0.254)
		(layer "In5.Cu")
		(net "P1V8_C_PG")
	)
	(segment
		(start 148.9837 -123.6091)
		(end 148.9837 -124.5616)
		(width 0.254)
		(layer "F.Cu")
		(net "P1V5_E_VFB_R")
	)
	(segment
		(start 146.3802 -124.3838)
		(end 147.701 -124.3838)
		(width 0.254)
		(layer "F.Cu")
		(net "P1V5_E_VFB_R")
	)
	(segment
		(start 148.209 -124.3838)
		(end 147.701 -124.3838)
		(width 0.254)
		(layer "F.Cu")
		(net "P1V5_E_VFB_R")
	)
	(segment
		(start 148.9837 -124.5616)
		(end 148.3868 -124.5616)
		(width 0.254)
		(layer "F.Cu")
		(net "P1V5_E_VFB_R")
	)
	(segment
		(start 148.3868 -124.5616)
		(end 148.209 -124.3838)
		(width 0.254)
		(layer "F.Cu")
		(net "P1V5_E_VFB_R")
	)
	(via
		(at 147.701 -124.3838)
		(size 0.6604)
		(drill 0.3302)
		(layers "F.Cu" "B.Cu")
		(net "P1V5_E_VFB_R")
	)
	(segment
		(start 151.068278 -119.000778)
		(end 151.67356 -119.60606)
		(width 0.254)
		(layer "F.Cu")
		(net "P1V5_E_VFB")
	)
	(segment
		(start 149.8727 -123.6091)
		(end 149.8727 -122.6693)
		(width 0.254)
		(layer "F.Cu")
		(net "P1V5_E_VFB")
	)
	(segment
		(start 151.67356 -120.29186)
		(end 151.04872 -120.9167)
		(width 0.254)
		(layer "F.Cu")
		(net "P1V5_E_VFB")
	)
	(segment
		(start 150.1013 -121.41073)
		(end 150.1013 -121.6914)
		(width 0.254)
		(layer "F.Cu")
		(net "P1V5_E_VFB")
	)
	(segment
		(start 150.59533 -120.9167)
		(end 150.1013 -121.41073)
		(width 0.254)
		(layer "F.Cu")
		(net "P1V5_E_VFB")
	)
	(segment
		(start 149.8727 -122.6693)
		(end 149.8854 -122.6566)
		(width 0.254)
		(layer "F.Cu")
		(net "P1V5_E_VFB")
	)
	(segment
		(start 149.8727 -124.5616)
		(end 149.8727 -123.6091)
		(width 0.254)
		(layer "F.Cu")
		(net "P1V5_E_VFB")
	)
	(segment
		(start 151.068278 -118.349522)
		(end 151.068278 -119.000778)
		(width 0.254)
		(layer "F.Cu")
		(net "P1V5_E_VFB")
	)
	(segment
		(start 149.8854 -122.6566)
		(end 149.8854 -121.9073)
		(width 0.254)
		(layer "F.Cu")
		(net "P1V5_E_VFB")
	)
	(segment
		(start 149.8854 -121.9073)
		(end 150.1013 -121.6914)
		(width 0.254)
		(layer "F.Cu")
		(net "P1V5_E_VFB")
	)
	(segment
		(start 151.04872 -120.9167)
		(end 150.59533 -120.9167)
		(width 0.254)
		(layer "F.Cu")
		(net "P1V5_E_VFB")
	)
	(segment
		(start 151.67356 -119.60606)
		(end 151.67356 -120.29186)
		(width 0.254)
		(layer "F.Cu")
		(net "P1V5_E_VFB")
	)
	(via
		(at 151.67356 -120.29186)
		(size 0.6604)
		(drill 0.3302)
		(layers "F.Cu" "B.Cu")
		(net "P1V5_E_VFB")
	)
	(segment
		(start 151.068278 -116.849398)
		(end 149.520402 -116.849398)
		(width 0.3048)
		(layer "F.Cu")
		(net "P1V5_E_VBST")
	)
	(via
		(at 149.1615 -117.7925)
		(size 0.6096)
		(drill 0.3048)
		(layers "F.Cu" "B.Cu")
		(net "P1V5_E_VBST")
	)
	(via
		(at 149.520402 -116.849398)
		(size 0.508)
		(drill 0.254)
		(layers "F.Cu" "B.Cu")
		(net "P1V5_E_VBST")
	)
	(segment
		(start 149.520402 -117.433598)
		(end 149.1615 -117.7925)
		(width 0.508)
		(layer "B.Cu")
		(net "P1V5_E_VBST")
	)
	(segment
		(start 148.844 -118.11)
		(end 149.1615 -117.7925)
		(width 0.508)
		(layer "B.Cu")
		(net "P1V5_E_VBST")
	)
	(segment
		(start 147.701 -118.11)
		(end 148.844 -118.11)
		(width 0.508)
		(layer "B.Cu")
		(net "P1V5_E_VBST")
	)
	(segment
		(start 149.520402 -116.849398)
		(end 149.520402 -117.433598)
		(width 0.508)
		(layer "B.Cu")
		(net "P1V5_E_VBST")
	)
	(via
		(at 152.5524 -109.398054)
		(size 0.6604)
		(drill 0.3302)
		(layers "F.Cu" "B.Cu")
		(net "P1V5_E_SNB")
	)
	(segment
		(start 158.8135 -83.224116)
		(end 158.8135 -82.293968)
		(width 0.127)
		(layer "F.Cu")
		(net "P1V5_E_SENSE")
	)
	(segment
		(start 158.8135 -84.5185)
		(end 158.556198 -84.775802)
		(width 0.127)
		(layer "F.Cu")
		(net "P1V5_E_SENSE")
	)
	(segment
		(start 158.8135 -82.293968)
		(end 158.523432 -82.0039)
		(width 0.127)
		(layer "F.Cu")
		(net "P1V5_E_SENSE")
	)
	(segment
		(start 158.556198 -84.775802)
		(end 157.81528 -84.775802)
		(width 0.127)
		(layer "F.Cu")
		(net "P1V5_E_SENSE")
	)
	(segment
		(start 158.8135 -83.224116)
		(end 158.8135 -84.5185)
		(width 0.127)
		(layer "F.Cu")
		(net "P1V5_E_SENSE")
	)
	(segment
		(start 158.523432 -82.0039)
		(end 157.2006 -82.0039)
		(width 0.127)
		(layer "F.Cu")
		(net "P1V5_E_SENSE")
	)
	(via
		(at 158.523432 -82.0039)
		(size 0.6604)
		(drill 0.3302)
		(layers "F.Cu" "B.Cu")
		(net "P1V5_E_SENSE")
	)
	(segment
		(start 36.97859 -33.642554)
		(end 37.176964 -33.44418)
		(width 0.254)
		(layer "F.Cu")
		(net "P1V5_E_PG")
	)
	(segment
		(start 148.46808 -119.00662)
		(end 148.46808 -118.00332)
		(width 0.254)
		(layer "F.Cu")
		(net "P1V5_E_PG")
	)
	(segment
		(start 149.4536 -119.2403)
		(end 149.21992 -119.00662)
		(width 0.254)
		(layer "F.Cu")
		(net "P1V5_E_PG")
	)
	(segment
		(start 149.21992 -119.00662)
		(end 148.46808 -119.00662)
		(width 0.254)
		(layer "F.Cu")
		(net "P1V5_E_PG")
	)
	(segment
		(start 159.97428 -118.98122)
		(end 160.85312 -118.98122)
		(width 0.254)
		(layer "F.Cu")
		(net "P1V5_E_PG")
	)
	(segment
		(start 148.46808 -118.00332)
		(end 149.121876 -117.349524)
		(width 0.254)
		(layer "F.Cu")
		(net "P1V5_E_PG")
	)
	(segment
		(start 37.176964 -33.44418)
		(end 38.531038 -33.44418)
		(width 0.254)
		(layer "F.Cu")
		(net "P1V5_E_PG")
	)
	(segment
		(start 160.85312 -118.98122)
		(end 161.0487 -119.1768)
		(width 0.254)
		(layer "F.Cu")
		(net "P1V5_E_PG")
	)
	(segment
		(start 38.531038 -33.44418)
		(end 39.52748 -33.44418)
		(width 0.254)
		(layer "F.Cu")
		(net "P1V5_E_PG")
	)
	(segment
		(start 149.121876 -117.349524)
		(end 151.068278 -117.349524)
		(width 0.254)
		(layer "F.Cu")
		(net "P1V5_E_PG")
	)
	(segment
		(start 39.52748 -33.44418)
		(end 39.8018 -33.7185)
		(width 0.254)
		(layer "F.Cu")
		(net "P1V5_E_PG")
	)
	(via
		(at 38.531038 -33.44418)
		(size 0.6604)
		(drill 0.3302)
		(layers "F.Cu" "B.Cu")
		(net "P1V5_E_PG")
	)
	(via
		(at 36.97859 -33.642554)
		(size 0.508)
		(drill 0.254)
		(layers "F.Cu" "B.Cu")
		(net "P1V5_E_PG")
	)
	(via
		(at 161.0487 -119.1768)
		(size 0.508)
		(drill 0.254)
		(layers "F.Cu" "B.Cu")
		(net "P1V5_E_PG")
	)
	(via
		(at 93.3069 -103.23957)
		(size 0.508)
		(drill 0.254)
		(layers "F.Cu" "B.Cu")
		(net "P1V5_E_PG")
	)
	(via
		(at 149.4536 -119.2403)
		(size 0.508)
		(drill 0.254)
		(layers "F.Cu" "B.Cu")
		(net "P1V5_E_PG")
	)
	(via
		(at 114.935 -107.569)
		(size 0.508)
		(drill 0.254)
		(layers "F.Cu" "B.Cu")
		(net "P1V5_E_PG")
	)
	(segment
		(start 109.983778 -97.722436)
		(end 109.944408 -97.722436)
		(width 0.254)
		(layer "B.Cu")
		(net "P1V5_E_PG")
	)
	(segment
		(start 160.500568 -119.724932)
		(end 149.938232 -119.724932)
		(width 0.254)
		(layer "B.Cu")
		(net "P1V5_E_PG")
	)
	(segment
		(start 114.935 -107.569)
		(end 114.935 -102.673658)
		(width 0.254)
		(layer "B.Cu")
		(net "P1V5_E_PG")
	)
	(segment
		(start 109.944408 -97.722436)
		(end 109.919008 -97.697036)
		(width 0.254)
		(layer "B.Cu")
		(net "P1V5_E_PG")
	)
	(segment
		(start 161.0487 -119.1768)
		(end 160.500568 -119.724932)
		(width 0.254)
		(layer "B.Cu")
		(net "P1V5_E_PG")
	)
	(segment
		(start 109.919008 -97.697036)
		(end 98.849434 -97.697036)
		(width 0.254)
		(layer "B.Cu")
		(net "P1V5_E_PG")
	)
	(segment
		(start 98.849434 -97.697036)
		(end 93.3069 -103.23957)
		(width 0.254)
		(layer "B.Cu")
		(net "P1V5_E_PG")
	)
	(segment
		(start 149.938232 -119.724932)
		(end 149.4536 -119.2403)
		(width 0.254)
		(layer "B.Cu")
		(net "P1V5_E_PG")
	)
	(segment
		(start 114.935 -102.673658)
		(end 109.983778 -97.722436)
		(width 0.254)
		(layer "B.Cu")
		(net "P1V5_E_PG")
	)
	(segment
		(start 91.22537 -105.3211)
		(end 93.3069 -103.23957)
		(width 0.254)
		(layer "In2.Cu")
		(net "P1V5_E_PG")
	)
	(segment
		(start 35.244024 -35.37712)
		(end 35.244024 -46.134274)
		(width 0.254)
		(layer "In2.Cu")
		(net "P1V5_E_PG")
	)
	(segment
		(start 73.269602 -105.3211)
		(end 91.22537 -105.3211)
		(width 0.254)
		(layer "In2.Cu")
		(net "P1V5_E_PG")
	)
	(segment
		(start 32.385 -74.58456)
		(end 56.42356 -98.62312)
		(width 0.254)
		(layer "In2.Cu")
		(net "P1V5_E_PG")
	)
	(segment
		(start 32.385 -48.993298)
		(end 32.385 -74.58456)
		(width 0.254)
		(layer "In2.Cu")
		(net "P1V5_E_PG")
	)
	(segment
		(start 36.97859 -33.642554)
		(end 35.244024 -35.37712)
		(width 0.254)
		(layer "In2.Cu")
		(net "P1V5_E_PG")
	)
	(segment
		(start 66.571622 -98.62312)
		(end 73.269602 -105.3211)
		(width 0.254)
		(layer "In2.Cu")
		(net "P1V5_E_PG")
	)
	(segment
		(start 35.244024 -46.134274)
		(end 32.385 -48.993298)
		(width 0.254)
		(layer "In2.Cu")
		(net "P1V5_E_PG")
	)
	(segment
		(start 56.42356 -98.62312)
		(end 66.571622 -98.62312)
		(width 0.254)
		(layer "In2.Cu")
		(net "P1V5_E_PG")
	)
	(segment
		(start 149.4536 -119.2403)
		(end 142.61084 -119.2403)
		(width 0.254)
		(layer "In5.Cu")
		(net "P1V5_E_PG")
	)
	(segment
		(start 127.216662 -116.31549)
		(end 125.975872 -115.0747)
		(width 0.254)
		(layer "In5.Cu")
		(net "P1V5_E_PG")
	)
	(segment
		(start 115.450874 -107.569)
		(end 114.935 -107.569)
		(width 0.254)
		(layer "In5.Cu")
		(net "P1V5_E_PG")
	)
	(segment
		(start 122.956574 -115.0747)
		(end 115.450874 -107.569)
		(width 0.254)
		(layer "In5.Cu")
		(net "P1V5_E_PG")
	)
	(segment
		(start 139.68603 -116.31549)
		(end 127.216662 -116.31549)
		(width 0.254)
		(layer "In5.Cu")
		(net "P1V5_E_PG")
	)
	(segment
		(start 142.61084 -119.2403)
		(end 139.68603 -116.31549)
		(width 0.254)
		(layer "In5.Cu")
		(net "P1V5_E_PG")
	)
	(segment
		(start 125.975872 -115.0747)
		(end 122.956574 -115.0747)
		(width 0.254)
		(layer "In5.Cu")
		(net "P1V5_E_PG")
	)
	(segment
		(start 142.20698 -118.42242)
		(end 144.54378 -118.42242)
		(width 0.254)
		(layer "F.Cu")
		(net "P1V5_E_LL_R")
	)
	(segment
		(start 148.9964 -122.6566)
		(end 143.267684 -122.6566)
		(width 0.254)
		(layer "F.Cu")
		(net "P1V5_E_LL_R")
	)
	(segment
		(start 142.683484 -122.0724)
		(end 141.86662 -121.255536)
		(width 0.254)
		(layer "F.Cu")
		(net "P1V5_E_LL_R")
	)
	(segment
		(start 145.68678 -117.78742)
		(end 145.05178 -118.42242)
		(width 0.254)
		(layer "F.Cu")
		(net "P1V5_E_LL_R")
	)
	(segment
		(start 143.267684 -122.6566)
		(end 142.683484 -122.0724)
		(width 0.254)
		(layer "F.Cu")
		(net "P1V5_E_LL_R")
	)
	(segment
		(start 141.86662 -118.76278)
		(end 142.20698 -118.42242)
		(width 0.254)
		(layer "F.Cu")
		(net "P1V5_E_LL_R")
	)
	(segment
		(start 145.05178 -118.42242)
		(end 144.54378 -118.42242)
		(width 0.254)
		(layer "F.Cu")
		(net "P1V5_E_LL_R")
	)
	(segment
		(start 141.86662 -121.255536)
		(end 141.86662 -118.76278)
		(width 0.254)
		(layer "F.Cu")
		(net "P1V5_E_LL_R")
	)
	(via
		(at 142.683484 -122.0724)
		(size 0.6604)
		(drill 0.3302)
		(layers "F.Cu" "B.Cu")
		(net "P1V5_E_LL_R")
	)
	(segment
		(start 150.15591 -118.19509)
		(end 150.501604 -117.849396)
		(width 0.254)
		(layer "F.Cu")
		(net "P1V5_E_EN")
	)
	(segment
		(start 149.93874 -120.12422)
		(end 149.02688 -120.12422)
		(width 0.254)
		(layer "F.Cu")
		(net "P1V5_E_EN")
	)
	(segment
		(start 150.02256 -120.0404)
		(end 149.93874 -120.12422)
		(width 0.254)
		(layer "F.Cu")
		(net "P1V5_E_EN")
	)
	(segment
		(start 150.501604 -117.849396)
		(end 151.068278 -117.849396)
		(width 0.254)
		(layer "F.Cu")
		(net "P1V5_E_EN")
	)
	(segment
		(start 150.26894 -119.79402)
		(end 150.26894 -118.83644)
		(width 0.254)
		(layer "F.Cu")
		(net "P1V5_E_EN")
	)
	(segment
		(start 150.26894 -118.83644)
		(end 150.15591 -118.72341)
		(width 0.254)
		(layer "F.Cu")
		(net "P1V5_E_EN")
	)
	(segment
		(start 150.02256 -120.0404)
		(end 150.26894 -119.79402)
		(width 0.254)
		(layer "F.Cu")
		(net "P1V5_E_EN")
	)
	(segment
		(start 150.15591 -118.72341)
		(end 150.15591 -118.19509)
		(width 0.254)
		(layer "F.Cu")
		(net "P1V5_E_EN")
	)
	(via
		(at 150.02256 -120.0404)
		(size 0.6604)
		(drill 0.3302)
		(layers "F.Cu" "B.Cu")
		(net "P1V5_E_EN")
	)
	(segment
		(start 159.1437 -73.67143)
		(end 158.8135 -73.34123)
		(width 0.127)
		(layer "F.Cu")
		(net "P1V5_C_SENSE")
	)
	(segment
		(start 158.8135 -70.80123)
		(end 158.8135 -72.152764)
		(width 0.127)
		(layer "F.Cu")
		(net "P1V5_C_SENSE")
	)
	(segment
		(start 158.825184 -75.019916)
		(end 159.1437 -74.7014)
		(width 0.127)
		(layer "F.Cu")
		(net "P1V5_C_SENSE")
	)
	(segment
		(start 157.81528 -75.019916)
		(end 158.825184 -75.019916)
		(width 0.127)
		(layer "F.Cu")
		(net "P1V5_C_SENSE")
	)
	(segment
		(start 159.1437 -74.7014)
		(end 159.1437 -73.67143)
		(width 0.127)
		(layer "F.Cu")
		(net "P1V5_C_SENSE")
	)
	(segment
		(start 158.8135 -72.152764)
		(end 158.8135 -73.34123)
		(width 0.127)
		(layer "F.Cu")
		(net "P1V5_C_SENSE")
	)
	(via
		(at 158.8135 -72.152764)
		(size 0.6604)
		(drill 0.3302)
		(layers "F.Cu" "B.Cu")
		(net "P1V5_C_SENSE")
	)
	(segment
		(start 164.07638 -100.4062)
		(end 164.07638 -101.37902)
		(width 0.254)
		(layer "F.Cu")
		(net "P1V5_C_PG")
	)
	(via
		(at 164.07638 -101.37902)
		(size 0.508)
		(drill 0.254)
		(layers "F.Cu" "B.Cu")
		(net "P1V5_C_PG")
	)
	(via
		(at 154.881072 -123.9266)
		(size 0.6096)
		(drill 0.3048)
		(layers "F.Cu" "B.Cu")
		(net "P1V5_C_PG")
	)
	(segment
		(start 161.026348 -123.9266)
		(end 164.07638 -120.876568)
		(width 0.254)
		(layer "B.Cu")
		(net "P1V5_C_PG")
	)
	(segment
		(start 164.07638 -120.876568)
		(end 164.07638 -101.37902)
		(width 0.254)
		(layer "B.Cu")
		(net "P1V5_C_PG")
	)
	(segment
		(start 146.6977 -123.9266)
		(end 154.881072 -123.9266)
		(width 0.254)
		(layer "B.Cu")
		(net "P1V5_C_PG")
	)
	(segment
		(start 154.881072 -123.9266)
		(end 161.026348 -123.9266)
		(width 0.254)
		(layer "B.Cu")
		(net "P1V5_C_PG")
	)
	(segment
		(start 17.73047 -72.82053)
		(end 17.6276 -72.9234)
		(width 0.127)
		(layer "F.Cu")
		(net "EEPROM_WP")
	)
	(segment
		(start 18.807684 -72.82053)
		(end 17.73047 -72.82053)
		(width 0.127)
		(layer "F.Cu")
		(net "EEPROM_WP")
	)
	(segment
		(start 15.875 -72.9488)
		(end 17.6022 -72.9488)
		(width 0.127)
		(layer "F.Cu")
		(net "EEPROM_WP")
	)
	(segment
		(start 17.6022 -72.9488)
		(end 17.6276 -72.9234)
		(width 0.127)
		(layer "F.Cu")
		(net "EEPROM_WP")
	)
	(via
		(at 17.6276 -72.9234)
		(size 0.6604)
		(drill 0.3302)
		(layers "F.Cu" "B.Cu")
		(net "EEPROM_WP")
	)
	(segment
		(start 18.807684 -70.28053)
		(end 17.65427 -70.28053)
		(width 0.127)
		(layer "F.Cu")
		(net "EEPROM_SDA")
	)
	(segment
		(start 17.65427 -70.28053)
		(end 17.653 -70.2818)
		(width 0.127)
		(layer "F.Cu")
		(net "EEPROM_SDA")
	)
	(segment
		(start 17.526 -70.4088)
		(end 17.653 -70.2818)
		(width 0.127)
		(layer "F.Cu")
		(net "EEPROM_SDA")
	)
	(segment
		(start 15.875 -70.4088)
		(end 17.526 -70.4088)
		(width 0.127)
		(layer "F.Cu")
		(net "EEPROM_SDA")
	)
	(via
		(at 17.653 -70.2818)
		(size 0.6604)
		(drill 0.3302)
		(layers "F.Cu" "B.Cu")
		(net "EEPROM_SDA")
	)
	(segment
		(start 17.628362 -71.55053)
		(end 17.627346 -71.551546)
		(width 0.127)
		(layer "F.Cu")
		(net "EEPROM_SCL")
	)
	(segment
		(start 15.875 -71.6788)
		(end 17.500092 -71.6788)
		(width 0.127)
		(layer "F.Cu")
		(net "EEPROM_SCL")
	)
	(segment
		(start 17.500092 -71.6788)
		(end 17.627346 -71.551546)
		(width 0.127)
		(layer "F.Cu")
		(net "EEPROM_SCL")
	)
	(segment
		(start 18.807684 -71.55053)
		(end 17.628362 -71.55053)
		(width 0.127)
		(layer "F.Cu")
		(net "EEPROM_SCL")
	)
	(via
		(at 17.627346 -71.551546)
		(size 0.6604)
		(drill 0.3302)
		(layers "F.Cu" "B.Cu")
		(net "EEPROM_SCL")
	)
	(segment
		(start 147.5613 -116.9162)
		(end 146.6342 -116.9162)
		(width 0.508)
		(layer "F.Cu")
		(net "AGND_P1V5_E")
	)
	(via
		(at 154.305 -123.825)
		(size 0.6604)
		(drill 0.3302)
		(layers "F.Cu" "B.Cu")
		(net "AGND_P1V5_E")
	)
	(via
		(at 158.724092 -123.575572)
		(size 0.6604)
		(drill 0.3302)
		(layers "F.Cu" "B.Cu")
		(net "AGND_P1V5_E")
	)
	(via
		(at 146.6342 -116.9162)
		(size 0.508)
		(drill 0.254)
		(layers "F.Cu" "B.Cu")
		(net "AGND_P1V5_E")
	)
	(via
		(at 153.805636 -121.926858)
		(size 0.7112)
		(drill 0.4064)
		(layers "F.Cu" "B.Cu")
		(net "AGND_P1V5_E")
	)
	(via
		(at 152.273 -121.92)
		(size 0.6604)
		(drill 0.3302)
		(layers "F.Cu" "B.Cu")
		(net "AGND_P1V5_E")
	)
	(via
		(at 155.702 -122.936)
		(size 0.6604)
		(drill 0.3302)
		(layers "F.Cu" "B.Cu")
		(net "AGND_P1V5_E")
	)
	(segment
		(start 148.147024 -118.971314)
		(end 151.102568 -121.926858)
		(width 0.508)
		(layer "In2.Cu")
		(net "AGND_P1V5_E")
	)
	(segment
		(start 146.6342 -116.9162)
		(end 148.147024 -118.429024)
		(width 0.508)
		(layer "In2.Cu")
		(net "AGND_P1V5_E")
	)
	(segment
		(start 148.147024 -118.429024)
		(end 148.147024 -118.971314)
		(width 0.508)
		(layer "In2.Cu")
		(net "AGND_P1V5_E")
	)
	(segment
		(start 151.102568 -121.926858)
		(end 153.805636 -121.926858)
		(width 0.508)
		(layer "In2.Cu")
		(net "AGND_P1V5_E")
	)
	(segment
		(start 101.499924 -57.500012)
		(end 101.000052 -57.00014)
		(width 0.4572)
		(layer "F.Cu")
		(net "XTAL_VDDA18")
	)
	(via
		(at 98.986086 -62.426088)
		(size 0.6096)
		(drill 0.3048)
		(layers "F.Cu" "B.Cu")
		(net "XTAL_VDDA18")
	)
	(via
		(at 101.000052 -57.00014)
		(size 0.4572)
		(drill 0.2032)
		(layers "F.Cu" "B.Cu")
		(net "XTAL_VDDA18")
	)
	(segment
		(start 92.15374 -64.80556)
		(end 91.324176 -64.80556)
		(width 0.508)
		(layer "B.Cu")
		(net "XTAL_VDDA18")
	)
	(segment
		(start 100.101908 -62.426088)
		(end 100.216716 -62.540896)
		(width 0.254)
		(layer "B.Cu")
		(net "XTAL_VDDA18")
	)
	(segment
		(start 101.500432 -62.273942)
		(end 101.500432 -57.558432)
		(width 0.254)
		(layer "B.Cu")
		(net "XTAL_VDDA18")
	)
	(segment
		(start 100.6348 -57.365392)
		(end 100.6348 -57.4802)
		(width 0.254)
		(layer "B.Cu")
		(net "XTAL_VDDA18")
	)
	(segment
		(start 92.45854 -64.50076)
		(end 92.15374 -64.80556)
		(width 0.508)
		(layer "B.Cu")
		(net "XTAL_VDDA18")
	)
	(segment
		(start 101.500432 -57.558432)
		(end 101.4476 -57.5056)
		(width 0.254)
		(layer "B.Cu")
		(net "XTAL_VDDA18")
	)
	(segment
		(start 93.323918 -64.481202)
		(end 93.30436 -64.50076)
		(width 0.508)
		(layer "B.Cu")
		(net "XTAL_VDDA18")
	)
	(segment
		(start 101.4476 -57.5056)
		(end 101.4222 -57.4802)
		(width 0.254)
		(layer "B.Cu")
		(net "XTAL_VDDA18")
	)
	(segment
		(start 100.6094 -57.4802)
		(end 100.6348 -57.4802)
		(width 0.254)
		(layer "B.Cu")
		(net "XTAL_VDDA18")
	)
	(segment
		(start 101.4222 -57.4802)
		(end 100.6348 -57.4802)
		(width 0.254)
		(layer "B.Cu")
		(net "XTAL_VDDA18")
	)
	(segment
		(start 93.30436 -64.50076)
		(end 92.45854 -64.50076)
		(width 0.508)
		(layer "B.Cu")
		(net "XTAL_VDDA18")
	)
	(segment
		(start 97.885758 -62.426088)
		(end 95.830644 -64.481202)
		(width 0.508)
		(layer "B.Cu")
		(net "XTAL_VDDA18")
	)
	(segment
		(start 101.233478 -62.540896)
		(end 101.500432 -62.273942)
		(width 0.254)
		(layer "B.Cu")
		(net "XTAL_VDDA18")
	)
	(segment
		(start 95.830644 -64.481202)
		(end 93.323918 -64.481202)
		(width 0.508)
		(layer "B.Cu")
		(net "XTAL_VDDA18")
	)
	(segment
		(start 98.986086 -62.426088)
		(end 97.885758 -62.426088)
		(width 0.508)
		(layer "B.Cu")
		(net "XTAL_VDDA18")
	)
	(segment
		(start 91.324176 -64.80556)
		(end 91.007692 -64.489076)
		(width 0.508)
		(layer "B.Cu")
		(net "XTAL_VDDA18")
	)
	(segment
		(start 98.986086 -62.426088)
		(end 99.519994 -62.426088)
		(width 0.508)
		(layer "B.Cu")
		(net "XTAL_VDDA18")
	)
	(segment
		(start 89.46642 -64.864234)
		(end 90.632534 -64.864234)
		(width 0.508)
		(layer "B.Cu")
		(net "XTAL_VDDA18")
	)
	(segment
		(start 90.632534 -64.864234)
		(end 91.007692 -64.489076)
		(width 0.508)
		(layer "B.Cu")
		(net "XTAL_VDDA18")
	)
	(segment
		(start 99.519994 -62.426088)
		(end 100.101908 -62.426088)
		(width 0.254)
		(layer "B.Cu")
		(net "XTAL_VDDA18")
	)
	(segment
		(start 100.216716 -62.540896)
		(end 101.233478 -62.540896)
		(width 0.254)
		(layer "B.Cu")
		(net "XTAL_VDDA18")
	)
	(segment
		(start 101.000052 -57.00014)
		(end 100.6348 -57.365392)
		(width 0.254)
		(layer "B.Cu")
		(net "XTAL_VDDA18")
	)
	(segment
		(start 108.49991 -63.5)
		(end 109.000036 -64.000126)
		(width 0.4572)
		(layer "F.Cu")
		(net "XTAL_VDDA09")
	)
	(via
		(at 97.993962 -66.078354)
		(size 0.6096)
		(drill 0.3048)
		(layers "F.Cu" "B.Cu")
		(net "XTAL_VDDA09")
	)
	(via
		(at 109.000036 -64.000126)
		(size 0.4572)
		(drill 0.2032)
		(layers "F.Cu" "B.Cu")
		(net "XTAL_VDDA09")
	)
	(segment
		(start 107.498642 -64.3128)
		(end 107.498642 -65.487804)
		(width 0.254)
		(layer "B.Cu")
		(net "XTAL_VDDA09")
	)
	(segment
		(start 98.580956 -65.49136)
		(end 106.48696 -65.49136)
		(width 0.254)
		(layer "B.Cu")
		(net "XTAL_VDDA09")
	)
	(segment
		(start 97.993962 -66.078354)
		(end 98.420174 -65.652142)
		(width 0.508)
		(layer "B.Cu")
		(net "XTAL_VDDA09")
	)
	(segment
		(start 90.315288 -73.645014)
		(end 89.464388 -73.645014)
		(width 0.508)
		(layer "B.Cu")
		(net "XTAL_VDDA09")
	)
	(segment
		(start 109.000036 -64.000126)
		(end 107.811316 -64.000126)
		(width 0.254)
		(layer "B.Cu")
		(net "XTAL_VDDA09")
	)
	(segment
		(start 93.951806 -72.926194)
		(end 93.951806 -74.330814)
		(width 0.508)
		(layer "B.Cu")
		(net "XTAL_VDDA09")
	)
	(segment
		(start 97.677986 -66.39433)
		(end 97.677986 -71.011542)
		(width 0.508)
		(layer "B.Cu")
		(net "XTAL_VDDA09")
	)
	(segment
		(start 97.993962 -66.078354)
		(end 97.677986 -66.39433)
		(width 0.508)
		(layer "B.Cu")
		(net "XTAL_VDDA09")
	)
	(segment
		(start 92.123006 -74.000614)
		(end 91.988386 -74.000614)
		(width 0.508)
		(layer "B.Cu")
		(net "XTAL_VDDA09")
	)
	(segment
		(start 96.155764 -72.533764)
		(end 94.344236 -72.533764)
		(width 0.508)
		(layer "B.Cu")
		(net "XTAL_VDDA09")
	)
	(segment
		(start 97.677986 -71.011542)
		(end 96.155764 -72.533764)
		(width 0.508)
		(layer "B.Cu")
		(net "XTAL_VDDA09")
	)
	(segment
		(start 90.988388 -74.318114)
		(end 90.315288 -73.645014)
		(width 0.508)
		(layer "B.Cu")
		(net "XTAL_VDDA09")
	)
	(segment
		(start 92.583 -74.330814)
		(end 92.2528 -74.000614)
		(width 0.508)
		(layer "B.Cu")
		(net "XTAL_VDDA09")
	)
	(segment
		(start 98.420174 -65.652142)
		(end 98.580956 -65.49136)
		(width 0.254)
		(layer "B.Cu")
		(net "XTAL_VDDA09")
	)
	(segment
		(start 91.670886 -74.318114)
		(end 90.988388 -74.318114)
		(width 0.508)
		(layer "B.Cu")
		(net "XTAL_VDDA09")
	)
	(segment
		(start 91.988386 -74.000614)
		(end 91.670886 -74.318114)
		(width 0.508)
		(layer "B.Cu")
		(net "XTAL_VDDA09")
	)
	(segment
		(start 92.2528 -74.000614)
		(end 92.123006 -74.000614)
		(width 0.508)
		(layer "B.Cu")
		(net "XTAL_VDDA09")
	)
	(segment
		(start 107.811316 -64.000126)
		(end 107.498642 -64.3128)
		(width 0.254)
		(layer "B.Cu")
		(net "XTAL_VDDA09")
	)
	(segment
		(start 94.344236 -72.533764)
		(end 93.951806 -72.926194)
		(width 0.508)
		(layer "B.Cu")
		(net "XTAL_VDDA09")
	)
	(segment
		(start 93.951806 -74.330814)
		(end 92.583 -74.330814)
		(width 0.508)
		(layer "B.Cu")
		(net "XTAL_VDDA09")
	)
	(segment
		(start 107.498642 -65.487804)
		(end 107.517438 -65.5066)
		(width 0.254)
		(layer "B.Cu")
		(net "XTAL_VDDA09")
	)
	(segment
		(start 106.5022 -65.5066)
		(end 107.517438 -65.5066)
		(width 0.254)
		(layer "B.Cu")
		(net "XTAL_VDDA09")
	)
	(segment
		(start 106.48696 -65.49136)
		(end 106.5022 -65.5066)
		(width 0.254)
		(layer "B.Cu")
		(net "XTAL_VDDA09")
	)
	(segment
		(start 182.45582 -52.113688)
		(end 182.599838 -51.96967)
		(width 0.127)
		(layer "F.Cu")
		(net "XM_WP")
	)
	(segment
		(start 182.599838 -51.96967)
		(end 182.599838 -51.599846)
		(width 0.127)
		(layer "F.Cu")
		(net "XM_WP")
	)
	(via
		(at 182.45582 -52.113688)
		(size 0.508)
		(drill 0.254)
		(layers "F.Cu" "B.Cu")
		(net "XM_WP")
	)
	(segment
		(start 182.45582 -52.113688)
		(end 182.607712 -52.113688)
		(width 0.127)
		(layer "B.Cu")
		(net "XM_WP")
	)
	(segment
		(start 182.607712 -52.113688)
		(end 183.261 -51.4604)
		(width 0.127)
		(layer "B.Cu")
		(net "XM_WP")
	)
	(segment
		(start 181.799992 -51.599846)
		(end 181.399942 -51.199796)
		(width 0.127)
		(layer "F.Cu")
		(net "XM_WE_N")
	)
	(via
		(at 181.399942 -51.199796)
		(size 0.508)
		(drill 0.254)
		(layers "F.Cu" "B.Cu")
		(net "XM_WE_N")
	)
	(via
		(at 178.995832 -64.172338)
		(size 0.508)
		(drill 0.254)
		(layers "F.Cu" "B.Cu")
		(net "XM_WE_N")
	)
	(segment
		(start 182.8038 -54.4957)
		(end 182.360824 -54.052724)
		(width 0.127)
		(layer "B.Cu")
		(net "XM_WE_N")
	)
	(segment
		(start 181.40553 -51.205384)
		(end 181.399942 -51.199796)
		(width 0.127)
		(layer "B.Cu")
		(net "XM_WE_N")
	)
	(segment
		(start 181.40553 -52.155344)
		(end 181.40553 -51.205384)
		(width 0.127)
		(layer "B.Cu")
		(net "XM_WE_N")
	)
	(segment
		(start 180.516022 -64.172338)
		(end 182.870348 -66.526664)
		(width 0.127)
		(layer "B.Cu")
		(net "XM_WE_N")
	)
	(segment
		(start 182.870348 -66.526664)
		(end 183.99252 -66.526664)
		(width 0.127)
		(layer "B.Cu")
		(net "XM_WE_N")
	)
	(segment
		(start 182.360824 -54.052724)
		(end 182.360824 -53.110638)
		(width 0.127)
		(layer "B.Cu")
		(net "XM_WE_N")
	)
	(segment
		(start 178.995832 -64.172338)
		(end 180.516022 -64.172338)
		(width 0.127)
		(layer "B.Cu")
		(net "XM_WE_N")
	)
	(segment
		(start 182.360824 -53.110638)
		(end 181.40553 -52.155344)
		(width 0.127)
		(layer "B.Cu")
		(net "XM_WE_N")
	)
	(segment
		(start 178.995832 -64.172338)
		(end 178.995832 -55.069994)
		(width 0.127)
		(layer "In5.Cu")
		(net "XM_WE_N")
	)
	(segment
		(start 178.995832 -55.069994)
		(end 181.399942 -52.665884)
		(width 0.127)
		(layer "In5.Cu")
		(net "XM_WE_N")
	)
	(segment
		(start 181.399942 -52.665884)
		(end 181.399942 -51.199796)
		(width 0.127)
		(layer "In5.Cu")
		(net "XM_WE_N")
	)
	(segment
		(start 110.499906 -80.50022)
		(end 110.000034 -81.000092)
		(width 0.127)
		(layer "F.Cu")
		(net "XM_WBE_1#_TP")
	)
	(via
		(at 110.000034 -81.000092)
		(size 0.4572)
		(drill 0.2032)
		(layers "F.Cu" "B.Cu")
		(net "XM_WBE_1#_TP")
	)
	(segment
		(start 110.000034 -81.000092)
		(end 110.236 -81.236058)
		(width 0.127)
		(layer "B.Cu")
		(net "XM_WBE_1#_TP")
	)
	(segment
		(start 110.236 -81.236058)
		(end 110.236 -81.8388)
		(width 0.127)
		(layer "B.Cu")
		(net "XM_WBE_1#_TP")
	)
	(segment
		(start 110.5789 -85.9409)
		(end 110.5789 -85.530182)
		(width 0.127)
		(layer "F.Cu")
		(net "XM_WBE_0#_TP")
	)
	(segment
		(start 109.7788 -86.741)
		(end 110.5789 -85.9409)
		(width 0.127)
		(layer "F.Cu")
		(net "XM_WBE_0#_TP")
	)
	(segment
		(start 110.499906 -85.451188)
		(end 110.499906 -82.500216)
		(width 0.127)
		(layer "F.Cu")
		(net "XM_WBE_0#_TP")
	)
	(segment
		(start 110.5789 -85.530182)
		(end 110.499906 -85.451188)
		(width 0.127)
		(layer "F.Cu")
		(net "XM_WBE_0#_TP")
	)
	(segment
		(start 179.578 -55.245)
		(end 179.578 -53.326792)
		(width 0.127)
		(layer "F.Cu")
		(net "XM_RB")
	)
	(segment
		(start 179.578 -53.326792)
		(end 180.199792 -52.705)
		(width 0.127)
		(layer "F.Cu")
		(net "XM_RB")
	)
	(segment
		(start 180.199792 -52.705)
		(end 180.199792 -51.599846)
		(width 0.127)
		(layer "F.Cu")
		(net "XM_RB")
	)
	(segment
		(start 180.7845 -55.245)
		(end 179.578 -55.245)
		(width 0.127)
		(layer "F.Cu")
		(net "XM_RB")
	)
	(segment
		(start 180.67274 -52.07762)
		(end 180.6194 -52.02428)
		(width 0.127)
		(layer "F.Cu")
		(net "XM_OE_N")
	)
	(segment
		(start 180.6194 -51.219608)
		(end 180.199792 -50.8)
		(width 0.127)
		(layer "F.Cu")
		(net "XM_OE_N")
	)
	(segment
		(start 180.67274 -52.583842)
		(end 180.67274 -52.07762)
		(width 0.127)
		(layer "F.Cu")
		(net "XM_OE_N")
	)
	(segment
		(start 180.6194 -52.02428)
		(end 180.6194 -51.219608)
		(width 0.127)
		(layer "F.Cu")
		(net "XM_OE_N")
	)
	(via
		(at 180.67274 -52.583842)
		(size 0.508)
		(drill 0.254)
		(layers "F.Cu" "B.Cu")
		(net "XM_OE_N")
	)
	(via
		(at 198.332598 -69.027294)
		(size 0.508)
		(drill 0.254)
		(layers "F.Cu" "B.Cu")
		(net "XM_OE_N")
	)
	(segment
		(start 200.831958 -71.526654)
		(end 198.332598 -69.027294)
		(width 0.127)
		(layer "B.Cu")
		(net "XM_OE_N")
	)
	(segment
		(start 180.5432 -54.4957)
		(end 180.5432 -52.713382)
		(width 0.127)
		(layer "B.Cu")
		(net "XM_OE_N")
	)
	(segment
		(start 203.22032 -71.526654)
		(end 200.831958 -71.526654)
		(width 0.127)
		(layer "B.Cu")
		(net "XM_OE_N")
	)
	(segment
		(start 180.5432 -52.713382)
		(end 180.67274 -52.583842)
		(width 0.127)
		(layer "B.Cu")
		(net "XM_OE_N")
	)
	(segment
		(start 198.332598 -69.027294)
		(end 196.09689 -69.027294)
		(width 0.127)
		(layer "In2.Cu")
		(net "XM_OE_N")
	)
	(segment
		(start 192.851278 -64.371474)
		(end 191.762126 -63.282322)
		(width 0.127)
		(layer "In2.Cu")
		(net "XM_OE_N")
	)
	(segment
		(start 180.492908 -54.54015)
		(end 180.67274 -54.360318)
		(width 0.127)
		(layer "In2.Cu")
		(net "XM_OE_N")
	)
	(segment
		(start 195.271898 -65.01257)
		(end 194.630802 -64.371474)
		(width 0.127)
		(layer "In2.Cu")
		(net "XM_OE_N")
	)
	(segment
		(start 194.630802 -64.371474)
		(end 192.851278 -64.371474)
		(width 0.127)
		(layer "In2.Cu")
		(net "XM_OE_N")
	)
	(segment
		(start 191.762126 -63.282322)
		(end 191.204088 -63.282322)
		(width 0.127)
		(layer "In2.Cu")
		(net "XM_OE_N")
	)
	(segment
		(start 195.271898 -68.202302)
		(end 195.271898 -65.01257)
		(width 0.127)
		(layer "In2.Cu")
		(net "XM_OE_N")
	)
	(segment
		(start 191.204088 -63.282322)
		(end 190.216282 -62.294516)
		(width 0.127)
		(layer "In2.Cu")
		(net "XM_OE_N")
	)
	(segment
		(start 196.09689 -69.027294)
		(end 195.271898 -68.202302)
		(width 0.127)
		(layer "In2.Cu")
		(net "XM_OE_N")
	)
	(segment
		(start 180.67274 -54.360318)
		(end 180.67274 -52.583842)
		(width 0.127)
		(layer "In2.Cu")
		(net "XM_OE_N")
	)
	(segment
		(start 180.492908 -58.524902)
		(end 180.492908 -54.54015)
		(width 0.127)
		(layer "In2.Cu")
		(net "XM_OE_N")
	)
	(segment
		(start 184.262522 -62.294516)
		(end 180.492908 -58.524902)
		(width 0.127)
		(layer "In2.Cu")
		(net "XM_OE_N")
	)
	(segment
		(start 190.216282 -62.294516)
		(end 184.262522 -62.294516)
		(width 0.127)
		(layer "In2.Cu")
		(net "XM_OE_N")
	)
	(segment
		(start 179.155344 -52.942998)
		(end 178.949858 -52.737512)
		(width 0.127)
		(layer "F.Cu")
		(net "XM_NOR_CS_N")
	)
	(segment
		(start 201.634598 -73.074784)
		(end 203.691236 -73.074784)
		(width 0.127)
		(layer "F.Cu")
		(net "XM_NOR_CS_N")
	)
	(segment
		(start 178.949858 -52.049934)
		(end 179.399946 -51.599846)
		(width 0.127)
		(layer "F.Cu")
		(net "XM_NOR_CS_N")
	)
	(segment
		(start 178.949858 -52.737512)
		(end 178.949858 -52.049934)
		(width 0.127)
		(layer "F.Cu")
		(net "XM_NOR_CS_N")
	)
	(via
		(at 179.155344 -52.942998)
		(size 0.508)
		(drill 0.254)
		(layers "F.Cu" "B.Cu")
		(net "XM_NOR_CS_N")
	)
	(via
		(at 201.634598 -73.074784)
		(size 0.508)
		(drill 0.254)
		(layers "F.Cu" "B.Cu")
		(net "XM_NOR_CS_N")
	)
	(segment
		(start 201.634598 -73.074784)
		(end 202.181968 -72.527414)
		(width 0.127)
		(layer "B.Cu")
		(net "XM_NOR_CS_N")
	)
	(segment
		(start 202.181968 -72.527414)
		(end 203.22032 -72.527414)
		(width 0.127)
		(layer "B.Cu")
		(net "XM_NOR_CS_N")
	)
	(segment
		(start 192.89141 -66.54038)
		(end 192.89141 -66.149982)
		(width 0.127)
		(layer "In2.Cu")
		(net "XM_NOR_CS_N")
	)
	(segment
		(start 192.89141 -66.149982)
		(end 191.167258 -64.42583)
		(width 0.127)
		(layer "In2.Cu")
		(net "XM_NOR_CS_N")
	)
	(segment
		(start 201.538078 -73.074784)
		(end 198.461376 -69.998082)
		(width 0.127)
		(layer "In2.Cu")
		(net "XM_NOR_CS_N")
	)
	(segment
		(start 198.461376 -69.998082)
		(end 196.349112 -69.998082)
		(width 0.127)
		(layer "In2.Cu")
		(net "XM_NOR_CS_N")
	)
	(segment
		(start 201.634598 -73.074784)
		(end 201.538078 -73.074784)
		(width 0.127)
		(layer "In2.Cu")
		(net "XM_NOR_CS_N")
	)
	(segment
		(start 191.167258 -64.42583)
		(end 184.956704 -64.42583)
		(width 0.127)
		(layer "In2.Cu")
		(net "XM_NOR_CS_N")
	)
	(segment
		(start 179.476908 -55.505096)
		(end 179.155344 -55.183532)
		(width 0.127)
		(layer "In2.Cu")
		(net "XM_NOR_CS_N")
	)
	(segment
		(start 196.349112 -69.998082)
		(end 192.89141 -66.54038)
		(width 0.127)
		(layer "In2.Cu")
		(net "XM_NOR_CS_N")
	)
	(segment
		(start 179.155344 -55.183532)
		(end 179.155344 -52.942998)
		(width 0.127)
		(layer "In2.Cu")
		(net "XM_NOR_CS_N")
	)
	(segment
		(start 179.476908 -58.946034)
		(end 179.476908 -55.505096)
		(width 0.127)
		(layer "In2.Cu")
		(net "XM_NOR_CS_N")
	)
	(segment
		(start 184.956704 -64.42583)
		(end 179.476908 -58.946034)
		(width 0.127)
		(layer "In2.Cu")
		(net "XM_NOR_CS_N")
	)
	(segment
		(start 179.794408 -51.194462)
		(end 179.399946 -50.8)
		(width 0.127)
		(layer "F.Cu")
		(net "XM_NAND_CS_N")
	)
	(segment
		(start 179.511198 -52.19827)
		(end 179.794408 -51.91506)
		(width 0.127)
		(layer "F.Cu")
		(net "XM_NAND_CS_N")
	)
	(segment
		(start 179.794408 -51.91506)
		(end 179.794408 -51.194462)
		(width 0.127)
		(layer "F.Cu")
		(net "XM_NAND_CS_N")
	)
	(via
		(at 179.511198 -52.19827)
		(size 0.508)
		(drill 0.254)
		(layers "F.Cu" "B.Cu")
		(net "XM_NAND_CS_N")
	)
	(via
		(at 178.63566 -52.19827)
		(size 0.6096)
		(drill 0.3048)
		(layers "F.Cu" "B.Cu")
		(net "XM_NAND_CS_N")
	)
	(segment
		(start 177.791872 -52.19827)
		(end 178.63566 -52.19827)
		(width 0.127)
		(layer "B.Cu")
		(net "XM_NAND_CS_N")
	)
	(segment
		(start 177.429414 -51.470306)
		(end 177.429414 -51.835812)
		(width 0.127)
		(layer "B.Cu")
		(net "XM_NAND_CS_N")
	)
	(segment
		(start 178.63566 -52.19827)
		(end 179.511198 -52.19827)
		(width 0.127)
		(layer "B.Cu")
		(net "XM_NAND_CS_N")
	)
	(segment
		(start 177.429414 -51.835812)
		(end 177.791872 -52.19827)
		(width 0.127)
		(layer "B.Cu")
		(net "XM_NAND_CS_N")
	)
	(segment
		(start 111.499904 -77.500226)
		(end 111.000032 -78.000098)
		(width 0.127)
		(layer "F.Cu")
		(net "XM_GP_CS_3#_TP")
	)
	(via
		(at 111.000032 -78.000098)
		(size 0.4572)
		(drill 0.2032)
		(layers "F.Cu" "B.Cu")
		(net "XM_GP_CS_3#_TP")
	)
	(segment
		(start 111.000032 -78.000098)
		(end 111.500158 -77.499972)
		(width 0.127)
		(layer "B.Cu")
		(net "XM_GP_CS_3#_TP")
	)
	(segment
		(start 111.500158 -77.499972)
		(end 112.499902 -77.499972)
		(width 0.127)
		(layer "B.Cu")
		(net "XM_GP_CS_3#_TP")
	)
	(segment
		(start 111.499904 -76.500228)
		(end 111.000032 -77.0001)
		(width 0.127)
		(layer "F.Cu")
		(net "XM_GP_CS_2#_TP")
	)
	(via
		(at 111.000032 -77.0001)
		(size 0.4572)
		(drill 0.2032)
		(layers "F.Cu" "B.Cu")
		(net "XM_GP_CS_2#_TP")
	)
	(segment
		(start 111.000032 -76.999846)
		(end 111.499904 -76.499974)
		(width 0.127)
		(layer "B.Cu")
		(net "XM_GP_CS_2#_TP")
	)
	(segment
		(start 111.000032 -77.0001)
		(end 111.000032 -76.999846)
		(width 0.127)
		(layer "B.Cu")
		(net "XM_GP_CS_2#_TP")
	)
	(segment
		(start 111.499904 -78.500224)
		(end 111.000032 -79.000096)
		(width 0.127)
		(layer "F.Cu")
		(net "XM_GP_CS_1#_TP")
	)
	(via
		(at 111.000032 -79.000096)
		(size 0.4572)
		(drill 0.2032)
		(layers "F.Cu" "B.Cu")
		(net "XM_GP_CS_1#_TP")
	)
	(segment
		(start 111.000032 -78.999842)
		(end 111.499904 -78.49997)
		(width 0.127)
		(layer "B.Cu")
		(net "XM_GP_CS_1#_TP")
	)
	(segment
		(start 111.000032 -79.000096)
		(end 111.000032 -78.999842)
		(width 0.127)
		(layer "B.Cu")
		(net "XM_GP_CS_1#_TP")
	)
	(segment
		(start 178.6001 -50.8)
		(end 178.599846 -50.8)
		(width 0.127)
		(layer "F.Cu")
		(net "XM_F_RST_N")
	)
	(segment
		(start 178.999896 -51.199796)
		(end 178.6001 -50.8)
		(width 0.127)
		(layer "F.Cu")
		(net "XM_F_RST_N")
	)
	(via
		(at 178.995832 -65.188338)
		(size 0.508)
		(drill 0.254)
		(layers "F.Cu" "B.Cu")
		(net "XM_F_RST_N")
	)
	(via
		(at 178.999896 -51.199796)
		(size 0.508)
		(drill 0.254)
		(layers "F.Cu" "B.Cu")
		(net "XM_F_RST_N")
	)
	(segment
		(start 181.512464 -67.027044)
		(end 179.673758 -65.188338)
		(width 0.127)
		(layer "B.Cu")
		(net "XM_F_RST_N")
	)
	(segment
		(start 179.673758 -65.188338)
		(end 178.995832 -65.188338)
		(width 0.127)
		(layer "B.Cu")
		(net "XM_F_RST_N")
	)
	(segment
		(start 183.99252 -67.027044)
		(end 181.512464 -67.027044)
		(width 0.127)
		(layer "B.Cu")
		(net "XM_F_RST_N")
	)
	(segment
		(start 178.456082 -64.648588)
		(end 178.995832 -65.188338)
		(width 0.127)
		(layer "In5.Cu")
		(net "XM_F_RST_N")
	)
	(segment
		(start 179.999132 -52.093368)
		(end 179.999132 -52.740814)
		(width 0.127)
		(layer "In5.Cu")
		(net "XM_F_RST_N")
	)
	(segment
		(start 178.456082 -54.283864)
		(end 178.456082 -64.648588)
		(width 0.127)
		(layer "In5.Cu")
		(net "XM_F_RST_N")
	)
	(segment
		(start 179.10556 -51.199796)
		(end 179.999132 -52.093368)
		(width 0.127)
		(layer "In5.Cu")
		(net "XM_F_RST_N")
	)
	(segment
		(start 179.999132 -52.740814)
		(end 178.456082 -54.283864)
		(width 0.127)
		(layer "In5.Cu")
		(net "XM_F_RST_N")
	)
	(segment
		(start 178.999896 -51.199796)
		(end 179.10556 -51.199796)
		(width 0.127)
		(layer "In5.Cu")
		(net "XM_F_RST_N")
	)
	(segment
		(start 111.499904 -74.500232)
		(end 111.000032 -75.000104)
		(width 0.127)
		(layer "F.Cu")
		(net "XM_DATA9")
	)
	(via
		(at 82.3214 -78.184756)
		(size 0.508)
		(drill 0.254)
		(layers "F.Cu" "B.Cu")
		(net "XM_DATA9")
	)
	(via
		(at 111.000032 -75.000104)
		(size 0.4572)
		(drill 0.2032)
		(layers "F.Cu" "B.Cu")
		(net "XM_DATA9")
	)
	(segment
		(start 82.5754 -77.093064)
		(end 82.5754 -77.930756)
		(width 0.127)
		(layer "B.Cu")
		(net "XM_DATA9")
	)
	(segment
		(start 82.5754 -77.930756)
		(end 82.3214 -78.184756)
		(width 0.127)
		(layer "B.Cu")
		(net "XM_DATA9")
	)
	(segment
		(start 82.76844 -76.900024)
		(end 82.5754 -77.093064)
		(width 0.127)
		(layer "B.Cu")
		(net "XM_DATA9")
	)
	(segment
		(start 82.76844 -75.6031)
		(end 82.76844 -76.900024)
		(width 0.127)
		(layer "B.Cu")
		(net "XM_DATA9")
	)
	(segment
		(start 91.292172 -73.3806)
		(end 91.419172 -73.5076)
		(width 0.127)
		(layer "In2.Cu")
		(net "XM_DATA9")
	)
	(segment
		(start 91.165172 -72.5678)
		(end 91.292172 -72.6948)
		(width 0.127)
		(layer "In2.Cu")
		(net "XM_DATA9")
	)
	(segment
		(start 92.308172 -73.3806)
		(end 92.435172 -73.5076)
		(width 0.127)
		(layer "In2.Cu")
		(net "XM_DATA9")
	)
	(segment
		(start 92.435172 -73.5076)
		(end 93.473778 -73.5076)
		(width 0.127)
		(layer "In2.Cu")
		(net "XM_DATA9")
	)
	(segment
		(start 94.997778 -72.517)
		(end 95.124778 -72.644)
		(width 0.127)
		(layer "In2.Cu")
		(net "XM_DATA9")
	)
	(segment
		(start 96.013778 -72.517)
		(end 96.140778 -72.644)
		(width 0.127)
		(layer "In2.Cu")
		(net "XM_DATA9")
	)
	(segment
		(start 97.44202 -73.5076)
		(end 98.43262 -72.517)
		(width 0.127)
		(layer "In2.Cu")
		(net "XM_DATA9")
	)
	(segment
		(start 82.3214 -78.184756)
		(end 83.224624 -77.281532)
		(width 0.127)
		(layer "In2.Cu")
		(net "XM_DATA9")
	)
	(segment
		(start 91.673172 -73.5076)
		(end 91.800172 -73.3806)
		(width 0.127)
		(layer "In2.Cu")
		(net "XM_DATA9")
	)
	(segment
		(start 95.124778 -72.644)
		(end 95.124778 -73.3806)
		(width 0.127)
		(layer "In2.Cu")
		(net "XM_DATA9")
	)
	(segment
		(start 98.43262 -72.517)
		(end 109.1438 -72.517)
		(width 0.127)
		(layer "In2.Cu")
		(net "XM_DATA9")
	)
	(segment
		(start 93.600778 -72.644)
		(end 93.727778 -72.517)
		(width 0.127)
		(layer "In2.Cu")
		(net "XM_DATA9")
	)
	(segment
		(start 86.937342 -73.472548)
		(end 90.006424 -73.472548)
		(width 0.127)
		(layer "In2.Cu")
		(net "XM_DATA9")
	)
	(segment
		(start 94.616778 -72.644)
		(end 94.743778 -72.517)
		(width 0.127)
		(layer "In2.Cu")
		(net "XM_DATA9")
	)
	(segment
		(start 110.531656 -73.92797)
		(end 110.531656 -74.162666)
		(width 0.127)
		(layer "In2.Cu")
		(net "XM_DATA9")
	)
	(segment
		(start 91.800172 -73.3806)
		(end 91.800172 -72.6948)
		(width 0.127)
		(layer "In2.Cu")
		(net "XM_DATA9")
	)
	(segment
		(start 109.88802 -73.505314)
		(end 110.109 -73.505314)
		(width 0.127)
		(layer "In2.Cu")
		(net "XM_DATA9")
	)
	(segment
		(start 91.419172 -73.5076)
		(end 91.673172 -73.5076)
		(width 0.127)
		(layer "In2.Cu")
		(net "XM_DATA9")
	)
	(segment
		(start 94.489778 -73.5076)
		(end 94.616778 -73.3806)
		(width 0.127)
		(layer "In2.Cu")
		(net "XM_DATA9")
	)
	(segment
		(start 94.108778 -72.644)
		(end 94.108778 -73.3806)
		(width 0.127)
		(layer "In2.Cu")
		(net "XM_DATA9")
	)
	(segment
		(start 90.006424 -73.472548)
		(end 90.911172 -72.5678)
		(width 0.127)
		(layer "In2.Cu")
		(net "XM_DATA9")
	)
	(segment
		(start 95.251778 -73.5076)
		(end 95.505778 -73.5076)
		(width 0.127)
		(layer "In2.Cu")
		(net "XM_DATA9")
	)
	(segment
		(start 94.616778 -73.3806)
		(end 94.616778 -72.644)
		(width 0.127)
		(layer "In2.Cu")
		(net "XM_DATA9")
	)
	(segment
		(start 94.108778 -73.3806)
		(end 94.235778 -73.5076)
		(width 0.127)
		(layer "In2.Cu")
		(net "XM_DATA9")
	)
	(segment
		(start 95.632778 -72.644)
		(end 95.759778 -72.517)
		(width 0.127)
		(layer "In2.Cu")
		(net "XM_DATA9")
	)
	(segment
		(start 95.759778 -72.517)
		(end 96.013778 -72.517)
		(width 0.127)
		(layer "In2.Cu")
		(net "XM_DATA9")
	)
	(segment
		(start 83.224624 -77.281532)
		(end 83.224624 -77.185266)
		(width 0.127)
		(layer "In2.Cu")
		(net "XM_DATA9")
	)
	(segment
		(start 109.481874 -73.099168)
		(end 109.88802 -73.505314)
		(width 0.127)
		(layer "In2.Cu")
		(net "XM_DATA9")
	)
	(segment
		(start 95.505778 -73.5076)
		(end 95.632778 -73.3806)
		(width 0.127)
		(layer "In2.Cu")
		(net "XM_DATA9")
	)
	(segment
		(start 95.124778 -73.3806)
		(end 95.251778 -73.5076)
		(width 0.127)
		(layer "In2.Cu")
		(net "XM_DATA9")
	)
	(segment
		(start 92.181172 -72.5678)
		(end 92.308172 -72.6948)
		(width 0.127)
		(layer "In2.Cu")
		(net "XM_DATA9")
	)
	(segment
		(start 91.800172 -72.6948)
		(end 91.927172 -72.5678)
		(width 0.127)
		(layer "In2.Cu")
		(net "XM_DATA9")
	)
	(segment
		(start 95.632778 -73.3806)
		(end 95.632778 -72.644)
		(width 0.127)
		(layer "In2.Cu")
		(net "XM_DATA9")
	)
	(segment
		(start 110.109 -73.505314)
		(end 110.531656 -73.92797)
		(width 0.127)
		(layer "In2.Cu")
		(net "XM_DATA9")
	)
	(segment
		(start 96.140778 -72.644)
		(end 96.140778 -73.3806)
		(width 0.127)
		(layer "In2.Cu")
		(net "XM_DATA9")
	)
	(segment
		(start 110.531656 -74.162666)
		(end 111.000032 -74.631042)
		(width 0.127)
		(layer "In2.Cu")
		(net "XM_DATA9")
	)
	(segment
		(start 96.267778 -73.5076)
		(end 97.44202 -73.5076)
		(width 0.127)
		(layer "In2.Cu")
		(net "XM_DATA9")
	)
	(segment
		(start 93.981778 -72.517)
		(end 94.108778 -72.644)
		(width 0.127)
		(layer "In2.Cu")
		(net "XM_DATA9")
	)
	(segment
		(start 91.292172 -72.6948)
		(end 91.292172 -73.3806)
		(width 0.127)
		(layer "In2.Cu")
		(net "XM_DATA9")
	)
	(segment
		(start 93.473778 -73.5076)
		(end 93.600778 -73.3806)
		(width 0.127)
		(layer "In2.Cu")
		(net "XM_DATA9")
	)
	(segment
		(start 92.308172 -72.6948)
		(end 92.308172 -73.3806)
		(width 0.127)
		(layer "In2.Cu")
		(net "XM_DATA9")
	)
	(segment
		(start 96.140778 -73.3806)
		(end 96.267778 -73.5076)
		(width 0.127)
		(layer "In2.Cu")
		(net "XM_DATA9")
	)
	(segment
		(start 90.911172 -72.5678)
		(end 91.165172 -72.5678)
		(width 0.127)
		(layer "In2.Cu")
		(net "XM_DATA9")
	)
	(segment
		(start 109.1438 -72.517)
		(end 109.481874 -72.855074)
		(width 0.127)
		(layer "In2.Cu")
		(net "XM_DATA9")
	)
	(segment
		(start 93.727778 -72.517)
		(end 93.981778 -72.517)
		(width 0.127)
		(layer "In2.Cu")
		(net "XM_DATA9")
	)
	(segment
		(start 83.224624 -77.185266)
		(end 86.937342 -73.472548)
		(width 0.127)
		(layer "In2.Cu")
		(net "XM_DATA9")
	)
	(segment
		(start 94.743778 -72.517)
		(end 94.997778 -72.517)
		(width 0.127)
		(layer "In2.Cu")
		(net "XM_DATA9")
	)
	(segment
		(start 91.927172 -72.5678)
		(end 92.181172 -72.5678)
		(width 0.127)
		(layer "In2.Cu")
		(net "XM_DATA9")
	)
	(segment
		(start 111.000032 -74.631042)
		(end 111.000032 -75.000104)
		(width 0.127)
		(layer "In2.Cu")
		(net "XM_DATA9")
	)
	(segment
		(start 94.235778 -73.5076)
		(end 94.489778 -73.5076)
		(width 0.127)
		(layer "In2.Cu")
		(net "XM_DATA9")
	)
	(segment
		(start 93.600778 -73.3806)
		(end 93.600778 -72.644)
		(width 0.127)
		(layer "In2.Cu")
		(net "XM_DATA9")
	)
	(segment
		(start 109.481874 -72.855074)
		(end 109.481874 -73.099168)
		(width 0.127)
		(layer "In2.Cu")
		(net "XM_DATA9")
	)
	(segment
		(start 111.499904 -79.500222)
		(end 111.000032 -80.000094)
		(width 0.127)
		(layer "F.Cu")
		(net "XM_DATA8")
	)
	(via
		(at 111.000032 -80.000094)
		(size 0.4572)
		(drill 0.2032)
		(layers "F.Cu" "B.Cu")
		(net "XM_DATA8")
	)
	(via
		(at 83.658456 -80.505046)
		(size 0.508)
		(drill 0.254)
		(layers "F.Cu" "B.Cu")
		(net "XM_DATA8")
	)
	(segment
		(start 83.76793 -76.409804)
		(end 83.76793 -75.6031)
		(width 0.127)
		(layer "B.Cu")
		(net "XM_DATA8")
	)
	(segment
		(start 83.623912 -76.553822)
		(end 83.76793 -76.409804)
		(width 0.127)
		(layer "B.Cu")
		(net "XM_DATA8")
	)
	(segment
		(start 83.658456 -79.746856)
		(end 83.623912 -79.712312)
		(width 0.127)
		(layer "B.Cu")
		(net "XM_DATA8")
	)
	(segment
		(start 83.658456 -80.505046)
		(end 83.658456 -79.746856)
		(width 0.127)
		(layer "B.Cu")
		(net "XM_DATA8")
	)
	(segment
		(start 83.623912 -79.712312)
		(end 83.623912 -76.553822)
		(width 0.127)
		(layer "B.Cu")
		(net "XM_DATA8")
	)
	(segment
		(start 94.048072 -78.098396)
		(end 93.921072 -77.971396)
		(width 0.127)
		(layer "In2.Cu")
		(net "XM_DATA8")
	)
	(segment
		(start 91.381072 -77.4954)
		(end 91.381072 -77.971396)
		(width 0.127)
		(layer "In2.Cu")
		(net "XM_DATA8")
	)
	(segment
		(start 89.857072 -77.4954)
		(end 89.730072 -77.3684)
		(width 0.127)
		(layer "In2.Cu")
		(net "XM_DATA8")
	)
	(segment
		(start 110.09503 -78.53807)
		(end 109.805216 -78.53807)
		(width 0.127)
		(layer "In2.Cu")
		(net "XM_DATA8")
	)
	(segment
		(start 109.805216 -78.53807)
		(end 109.501432 -78.234286)
		(width 0.127)
		(layer "In2.Cu")
		(net "XM_DATA8")
	)
	(segment
		(start 110.531402 -79.531464)
		(end 110.531402 -78.974442)
		(width 0.127)
		(layer "In2.Cu")
		(net "XM_DATA8")
	)
	(segment
		(start 93.921072 -77.4954)
		(end 93.794072 -77.3684)
		(width 0.127)
		(layer "In2.Cu")
		(net "XM_DATA8")
	)
	(segment
		(start 93.032072 -78.098396)
		(end 92.905072 -77.971396)
		(width 0.127)
		(layer "In2.Cu")
		(net "XM_DATA8")
	)
	(segment
		(start 85.508846 -79.164942)
		(end 84.998306 -79.164942)
		(width 0.127)
		(layer "In2.Cu")
		(net "XM_DATA8")
	)
	(segment
		(start 91.508072 -77.3684)
		(end 91.381072 -77.4954)
		(width 0.127)
		(layer "In2.Cu")
		(net "XM_DATA8")
	)
	(segment
		(start 86.574122 -78.099666)
		(end 85.508846 -79.164942)
		(width 0.127)
		(layer "In2.Cu")
		(net "XM_DATA8")
	)
	(segment
		(start 94.937072 -77.4954)
		(end 94.810072 -77.3684)
		(width 0.127)
		(layer "In2.Cu")
		(net "XM_DATA8")
	)
	(segment
		(start 98.24847 -78.098396)
		(end 95.064072 -78.098396)
		(width 0.127)
		(layer "In2.Cu")
		(net "XM_DATA8")
	)
	(segment
		(start 89.857072 -77.971396)
		(end 89.857072 -77.4954)
		(width 0.127)
		(layer "In2.Cu")
		(net "XM_DATA8")
	)
	(segment
		(start 92.397072 -77.971396)
		(end 92.270072 -78.098396)
		(width 0.127)
		(layer "In2.Cu")
		(net "XM_DATA8")
	)
	(segment
		(start 86.955122 -77.47)
		(end 86.701122 -77.47)
		(width 0.127)
		(layer "In2.Cu")
		(net "XM_DATA8")
	)
	(segment
		(start 89.349072 -77.4954)
		(end 89.349072 -77.971396)
		(width 0.127)
		(layer "In2.Cu")
		(net "XM_DATA8")
	)
	(segment
		(start 109.501432 -77.944472)
		(end 109.02696 -77.47)
		(width 0.127)
		(layer "In2.Cu")
		(net "XM_DATA8")
	)
	(segment
		(start 84.998306 -79.164942)
		(end 83.658456 -80.505046)
		(width 0.127)
		(layer "In2.Cu")
		(net "XM_DATA8")
	)
	(segment
		(start 89.476072 -77.3684)
		(end 89.349072 -77.4954)
		(width 0.127)
		(layer "In2.Cu")
		(net "XM_DATA8")
	)
	(segment
		(start 89.730072 -77.3684)
		(end 89.476072 -77.3684)
		(width 0.127)
		(layer "In2.Cu")
		(net "XM_DATA8")
	)
	(segment
		(start 91.381072 -77.971396)
		(end 91.254072 -78.098396)
		(width 0.127)
		(layer "In2.Cu")
		(net "XM_DATA8")
	)
	(segment
		(start 89.349072 -77.971396)
		(end 89.222072 -78.098396)
		(width 0.127)
		(layer "In2.Cu")
		(net "XM_DATA8")
	)
	(segment
		(start 109.501432 -78.234286)
		(end 109.501432 -77.944472)
		(width 0.127)
		(layer "In2.Cu")
		(net "XM_DATA8")
	)
	(segment
		(start 89.222072 -78.098396)
		(end 87.209122 -78.098396)
		(width 0.127)
		(layer "In2.Cu")
		(net "XM_DATA8")
	)
	(segment
		(start 90.365072 -77.971396)
		(end 90.238072 -78.098396)
		(width 0.127)
		(layer "In2.Cu")
		(net "XM_DATA8")
	)
	(segment
		(start 93.794072 -77.3684)
		(end 93.540072 -77.3684)
		(width 0.127)
		(layer "In2.Cu")
		(net "XM_DATA8")
	)
	(segment
		(start 92.778072 -77.3684)
		(end 92.524072 -77.3684)
		(width 0.127)
		(layer "In2.Cu")
		(net "XM_DATA8")
	)
	(segment
		(start 92.524072 -77.3684)
		(end 92.397072 -77.4954)
		(width 0.127)
		(layer "In2.Cu")
		(net "XM_DATA8")
	)
	(segment
		(start 92.016072 -78.098396)
		(end 91.889072 -77.971396)
		(width 0.127)
		(layer "In2.Cu")
		(net "XM_DATA8")
	)
	(segment
		(start 90.492072 -77.3684)
		(end 90.365072 -77.4954)
		(width 0.127)
		(layer "In2.Cu")
		(net "XM_DATA8")
	)
	(segment
		(start 90.873072 -77.4954)
		(end 90.746072 -77.3684)
		(width 0.127)
		(layer "In2.Cu")
		(net "XM_DATA8")
	)
	(segment
		(start 92.905072 -77.4954)
		(end 92.778072 -77.3684)
		(width 0.127)
		(layer "In2.Cu")
		(net "XM_DATA8")
	)
	(segment
		(start 91.889072 -77.971396)
		(end 91.889072 -77.4954)
		(width 0.127)
		(layer "In2.Cu")
		(net "XM_DATA8")
	)
	(segment
		(start 86.701122 -77.47)
		(end 86.574122 -77.597)
		(width 0.127)
		(layer "In2.Cu")
		(net "XM_DATA8")
	)
	(segment
		(start 91.889072 -77.4954)
		(end 91.762072 -77.3684)
		(width 0.127)
		(layer "In2.Cu")
		(net "XM_DATA8")
	)
	(segment
		(start 111.000032 -80.000094)
		(end 110.531402 -79.531464)
		(width 0.127)
		(layer "In2.Cu")
		(net "XM_DATA8")
	)
	(segment
		(start 94.302072 -78.098396)
		(end 94.048072 -78.098396)
		(width 0.127)
		(layer "In2.Cu")
		(net "XM_DATA8")
	)
	(segment
		(start 98.876866 -77.47)
		(end 98.24847 -78.098396)
		(width 0.127)
		(layer "In2.Cu")
		(net "XM_DATA8")
	)
	(segment
		(start 87.209122 -78.098396)
		(end 87.082122 -77.971396)
		(width 0.127)
		(layer "In2.Cu")
		(net "XM_DATA8")
	)
	(segment
		(start 90.365072 -77.4954)
		(end 90.365072 -77.971396)
		(width 0.127)
		(layer "In2.Cu")
		(net "XM_DATA8")
	)
	(segment
		(start 90.873072 -77.971396)
		(end 90.873072 -77.4954)
		(width 0.127)
		(layer "In2.Cu")
		(net "XM_DATA8")
	)
	(segment
		(start 94.937072 -77.971396)
		(end 94.937072 -77.4954)
		(width 0.127)
		(layer "In2.Cu")
		(net "XM_DATA8")
	)
	(segment
		(start 91.000072 -78.098396)
		(end 90.873072 -77.971396)
		(width 0.127)
		(layer "In2.Cu")
		(net "XM_DATA8")
	)
	(segment
		(start 93.413072 -77.4954)
		(end 93.413072 -77.971396)
		(width 0.127)
		(layer "In2.Cu")
		(net "XM_DATA8")
	)
	(segment
		(start 87.082122 -77.597)
		(end 86.955122 -77.47)
		(width 0.127)
		(layer "In2.Cu")
		(net "XM_DATA8")
	)
	(segment
		(start 92.270072 -78.098396)
		(end 92.016072 -78.098396)
		(width 0.127)
		(layer "In2.Cu")
		(net "XM_DATA8")
	)
	(segment
		(start 91.254072 -78.098396)
		(end 91.000072 -78.098396)
		(width 0.127)
		(layer "In2.Cu")
		(net "XM_DATA8")
	)
	(segment
		(start 93.286072 -78.098396)
		(end 93.032072 -78.098396)
		(width 0.127)
		(layer "In2.Cu")
		(net "XM_DATA8")
	)
	(segment
		(start 93.540072 -77.3684)
		(end 93.413072 -77.4954)
		(width 0.127)
		(layer "In2.Cu")
		(net "XM_DATA8")
	)
	(segment
		(start 90.238072 -78.098396)
		(end 89.984072 -78.098396)
		(width 0.127)
		(layer "In2.Cu")
		(net "XM_DATA8")
	)
	(segment
		(start 91.762072 -77.3684)
		(end 91.508072 -77.3684)
		(width 0.127)
		(layer "In2.Cu")
		(net "XM_DATA8")
	)
	(segment
		(start 93.921072 -77.971396)
		(end 93.921072 -77.4954)
		(width 0.127)
		(layer "In2.Cu")
		(net "XM_DATA8")
	)
	(segment
		(start 86.574122 -77.597)
		(end 86.574122 -78.099666)
		(width 0.127)
		(layer "In2.Cu")
		(net "XM_DATA8")
	)
	(segment
		(start 94.810072 -77.3684)
		(end 94.556072 -77.3684)
		(width 0.127)
		(layer "In2.Cu")
		(net "XM_DATA8")
	)
	(segment
		(start 94.429072 -77.4954)
		(end 94.429072 -77.971396)
		(width 0.127)
		(layer "In2.Cu")
		(net "XM_DATA8")
	)
	(segment
		(start 94.429072 -77.971396)
		(end 94.302072 -78.098396)
		(width 0.127)
		(layer "In2.Cu")
		(net "XM_DATA8")
	)
	(segment
		(start 94.556072 -77.3684)
		(end 94.429072 -77.4954)
		(width 0.127)
		(layer "In2.Cu")
		(net "XM_DATA8")
	)
	(segment
		(start 92.397072 -77.4954)
		(end 92.397072 -77.971396)
		(width 0.127)
		(layer "In2.Cu")
		(net "XM_DATA8")
	)
	(segment
		(start 89.984072 -78.098396)
		(end 89.857072 -77.971396)
		(width 0.127)
		(layer "In2.Cu")
		(net "XM_DATA8")
	)
	(segment
		(start 93.413072 -77.971396)
		(end 93.286072 -78.098396)
		(width 0.127)
		(layer "In2.Cu")
		(net "XM_DATA8")
	)
	(segment
		(start 92.905072 -77.971396)
		(end 92.905072 -77.4954)
		(width 0.127)
		(layer "In2.Cu")
		(net "XM_DATA8")
	)
	(segment
		(start 87.082122 -77.971396)
		(end 87.082122 -77.597)
		(width 0.127)
		(layer "In2.Cu")
		(net "XM_DATA8")
	)
	(segment
		(start 90.746072 -77.3684)
		(end 90.492072 -77.3684)
		(width 0.127)
		(layer "In2.Cu")
		(net "XM_DATA8")
	)
	(segment
		(start 109.02696 -77.47)
		(end 98.876866 -77.47)
		(width 0.127)
		(layer "In2.Cu")
		(net "XM_DATA8")
	)
	(segment
		(start 110.531402 -78.974442)
		(end 110.09503 -78.53807)
		(width 0.127)
		(layer "In2.Cu")
		(net "XM_DATA8")
	)
	(segment
		(start 95.064072 -78.098396)
		(end 94.937072 -77.971396)
		(width 0.127)
		(layer "In2.Cu")
		(net "XM_DATA8")
	)
	(segment
		(start 111.499904 -80.50022)
		(end 111.000032 -81.000092)
		(width 0.127)
		(layer "F.Cu")
		(net "XM_DATA7")
	)
	(via
		(at 111.000032 -81.000092)
		(size 0.4572)
		(drill 0.2032)
		(layers "F.Cu" "B.Cu")
		(net "XM_DATA7")
	)
	(via
		(at 77.629512 -82.425794)
		(size 0.508)
		(drill 0.254)
		(layers "F.Cu" "B.Cu")
		(net "XM_DATA7")
	)
	(segment
		(start 76.77023 -76.220574)
		(end 76.76769 -76.218034)
		(width 0.127)
		(layer "B.Cu")
		(net "XM_DATA7")
	)
	(segment
		(start 76.76769 -76.218034)
		(end 76.76769 -75.6031)
		(width 0.127)
		(layer "B.Cu")
		(net "XM_DATA7")
	)
	(segment
		(start 77.629512 -82.425794)
		(end 77.121512 -81.917794)
		(width 0.127)
		(layer "B.Cu")
		(net "XM_DATA7")
	)
	(segment
		(start 77.121512 -78.939644)
		(end 76.6064 -78.424532)
		(width 0.127)
		(layer "B.Cu")
		(net "XM_DATA7")
	)
	(segment
		(start 76.6064 -78.424532)
		(end 76.6064 -76.708)
		(width 0.127)
		(layer "B.Cu")
		(net "XM_DATA7")
	)
	(segment
		(start 77.121512 -81.917794)
		(end 77.121512 -78.939644)
		(width 0.127)
		(layer "B.Cu")
		(net "XM_DATA7")
	)
	(segment
		(start 76.6064 -76.708)
		(end 76.77023 -76.54417)
		(width 0.127)
		(layer "B.Cu")
		(net "XM_DATA7")
	)
	(segment
		(start 76.77023 -76.54417)
		(end 76.77023 -76.220574)
		(width 0.127)
		(layer "B.Cu")
		(net "XM_DATA7")
	)
	(segment
		(start 85.209634 -79.672942)
		(end 83.76539 -81.117186)
		(width 0.127)
		(layer "In2.Cu")
		(net "XM_DATA7")
	)
	(segment
		(start 109.779054 -80.4672)
		(end 109.471968 -80.160114)
		(width 0.127)
		(layer "In2.Cu")
		(net "XM_DATA7")
	)
	(segment
		(start 111.000032 -81.000092)
		(end 110.46714 -80.4672)
		(width 0.127)
		(layer "In2.Cu")
		(net "XM_DATA7")
	)
	(segment
		(start 109.471968 -80.160114)
		(end 109.471968 -78.814422)
		(width 0.127)
		(layer "In2.Cu")
		(net "XM_DATA7")
	)
	(segment
		(start 109.219746 -78.5622)
		(end 96.774762 -78.5622)
		(width 0.127)
		(layer "In2.Cu")
		(net "XM_DATA7")
	)
	(segment
		(start 78.93812 -81.117186)
		(end 77.629512 -82.425794)
		(width 0.127)
		(layer "In2.Cu")
		(net "XM_DATA7")
	)
	(segment
		(start 110.46714 -80.4672)
		(end 109.779054 -80.4672)
		(width 0.127)
		(layer "In2.Cu")
		(net "XM_DATA7")
	)
	(segment
		(start 85.731858 -79.672942)
		(end 85.209634 -79.672942)
		(width 0.127)
		(layer "In2.Cu")
		(net "XM_DATA7")
	)
	(segment
		(start 83.76539 -81.117186)
		(end 78.93812 -81.117186)
		(width 0.127)
		(layer "In2.Cu")
		(net "XM_DATA7")
	)
	(segment
		(start 109.471968 -78.814422)
		(end 109.219746 -78.5622)
		(width 0.127)
		(layer "In2.Cu")
		(net "XM_DATA7")
	)
	(segment
		(start 96.730566 -78.606396)
		(end 86.798404 -78.606396)
		(width 0.127)
		(layer "In2.Cu")
		(net "XM_DATA7")
	)
	(segment
		(start 86.798404 -78.606396)
		(end 85.731858 -79.672942)
		(width 0.127)
		(layer "In2.Cu")
		(net "XM_DATA7")
	)
	(segment
		(start 96.774762 -78.5622)
		(end 96.730566 -78.606396)
		(width 0.127)
		(layer "In2.Cu")
		(net "XM_DATA7")
	)
	(segment
		(start 111.499904 -82.500216)
		(end 111.499904 -83.109816)
		(width 0.127)
		(layer "F.Cu")
		(net "XM_DATA6")
	)
	(via
		(at 81.0514 -83.9724)
		(size 0.508)
		(drill 0.254)
		(layers "F.Cu" "B.Cu")
		(net "XM_DATA6")
	)
	(via
		(at 111.499904 -83.109816)
		(size 0.4572)
		(drill 0.2032)
		(layers "F.Cu" "B.Cu")
		(net "XM_DATA6")
	)
	(segment
		(start 77.6224 -77.778102)
		(end 78.25994 -78.415642)
		(width 0.127)
		(layer "B.Cu")
		(net "XM_DATA6")
	)
	(segment
		(start 79.3496 -83.603338)
		(end 79.718662 -83.9724)
		(width 0.127)
		(layer "B.Cu")
		(net "XM_DATA6")
	)
	(segment
		(start 77.76845 -76.494894)
		(end 77.77353 -76.499974)
		(width 0.127)
		(layer "B.Cu")
		(net "XM_DATA6")
	)
	(segment
		(start 78.25994 -79.087472)
		(end 79.3496 -80.177132)
		(width 0.127)
		(layer "B.Cu")
		(net "XM_DATA6")
	)
	(segment
		(start 78.25994 -78.415642)
		(end 78.25994 -79.087472)
		(width 0.127)
		(layer "B.Cu")
		(net "XM_DATA6")
	)
	(segment
		(start 77.77353 -76.93787)
		(end 77.6224 -77.089)
		(width 0.127)
		(layer "B.Cu")
		(net "XM_DATA6")
	)
	(segment
		(start 77.76845 -75.6031)
		(end 77.76845 -76.494894)
		(width 0.127)
		(layer "B.Cu")
		(net "XM_DATA6")
	)
	(segment
		(start 79.3496 -80.177132)
		(end 79.3496 -83.603338)
		(width 0.127)
		(layer "B.Cu")
		(net "XM_DATA6")
	)
	(segment
		(start 77.6224 -77.089)
		(end 77.6224 -77.778102)
		(width 0.127)
		(layer "B.Cu")
		(net "XM_DATA6")
	)
	(segment
		(start 77.77353 -76.499974)
		(end 77.77353 -76.93787)
		(width 0.127)
		(layer "B.Cu")
		(net "XM_DATA6")
	)
	(segment
		(start 79.718662 -83.9724)
		(end 81.0514 -83.9724)
		(width 0.127)
		(layer "B.Cu")
		(net "XM_DATA6")
	)
	(segment
		(start 82.931 -83.6676)
		(end 82.6262 -83.9724)
		(width 0.127)
		(layer "In2.Cu")
		(net "XM_DATA6")
	)
	(segment
		(start 89.4842 -82.3214)
		(end 89.3572 -82.1944)
		(width 0.127)
		(layer "In2.Cu")
		(net "XM_DATA6")
	)
	(segment
		(start 89.3572 -81.907888)
		(end 89.2302 -81.780888)
		(width 0.127)
		(layer "In2.Cu")
		(net "XM_DATA6")
	)
	(segment
		(start 93.871288 -81.780888)
		(end 91.0082 -81.780888)
		(width 0.127)
		(layer "In2.Cu")
		(net "XM_DATA6")
	)
	(segment
		(start 86.0806 -83.6676)
		(end 82.931 -83.6676)
		(width 0.127)
		(layer "In2.Cu")
		(net "XM_DATA6")
	)
	(segment
		(start 90.3732 -81.907888)
		(end 90.2462 -81.780888)
		(width 0.127)
		(layer "In2.Cu")
		(net "XM_DATA6")
	)
	(segment
		(start 107.781344 -83.458812)
		(end 98.838512 -83.458812)
		(width 0.127)
		(layer "In2.Cu")
		(net "XM_DATA6")
	)
	(segment
		(start 82.6262 -83.9724)
		(end 81.0514 -83.9724)
		(width 0.127)
		(layer "In2.Cu")
		(net "XM_DATA6")
	)
	(segment
		(start 89.7382 -82.3214)
		(end 89.4842 -82.3214)
		(width 0.127)
		(layer "In2.Cu")
		(net "XM_DATA6")
	)
	(segment
		(start 111.217456 -83.109816)
		(end 110.55604 -82.4484)
		(width 0.127)
		(layer "In2.Cu")
		(net "XM_DATA6")
	)
	(segment
		(start 90.7542 -82.3214)
		(end 90.5002 -82.3214)
		(width 0.127)
		(layer "In2.Cu")
		(net "XM_DATA6")
	)
	(segment
		(start 98.838512 -83.458812)
		(end 97.7011 -82.3214)
		(width 0.127)
		(layer "In2.Cu")
		(net "XM_DATA6")
	)
	(segment
		(start 90.8812 -82.1944)
		(end 90.7542 -82.3214)
		(width 0.127)
		(layer "In2.Cu")
		(net "XM_DATA6")
	)
	(segment
		(start 89.9922 -81.780888)
		(end 89.8652 -81.907888)
		(width 0.127)
		(layer "In2.Cu")
		(net "XM_DATA6")
	)
	(segment
		(start 108.791756 -82.4484)
		(end 107.781344 -83.458812)
		(width 0.127)
		(layer "In2.Cu")
		(net "XM_DATA6")
	)
	(segment
		(start 89.8652 -82.1944)
		(end 89.7382 -82.3214)
		(width 0.127)
		(layer "In2.Cu")
		(net "XM_DATA6")
	)
	(segment
		(start 90.3732 -82.1944)
		(end 90.3732 -81.907888)
		(width 0.127)
		(layer "In2.Cu")
		(net "XM_DATA6")
	)
	(segment
		(start 97.7011 -82.3214)
		(end 94.4118 -82.3214)
		(width 0.127)
		(layer "In2.Cu")
		(net "XM_DATA6")
	)
	(segment
		(start 91.0082 -81.780888)
		(end 90.8812 -81.907888)
		(width 0.127)
		(layer "In2.Cu")
		(net "XM_DATA6")
	)
	(segment
		(start 89.2302 -81.780888)
		(end 87.967312 -81.780888)
		(width 0.127)
		(layer "In2.Cu")
		(net "XM_DATA6")
	)
	(segment
		(start 111.499904 -83.109816)
		(end 111.217456 -83.109816)
		(width 0.127)
		(layer "In2.Cu")
		(net "XM_DATA6")
	)
	(segment
		(start 87.967312 -81.780888)
		(end 86.0806 -83.6676)
		(width 0.127)
		(layer "In2.Cu")
		(net "XM_DATA6")
	)
	(segment
		(start 89.3572 -82.1944)
		(end 89.3572 -81.907888)
		(width 0.127)
		(layer "In2.Cu")
		(net "XM_DATA6")
	)
	(segment
		(start 90.8812 -81.907888)
		(end 90.8812 -82.1944)
		(width 0.127)
		(layer "In2.Cu")
		(net "XM_DATA6")
	)
	(segment
		(start 89.8652 -81.907888)
		(end 89.8652 -82.1944)
		(width 0.127)
		(layer "In2.Cu")
		(net "XM_DATA6")
	)
	(segment
		(start 110.55604 -82.4484)
		(end 108.791756 -82.4484)
		(width 0.127)
		(layer "In2.Cu")
		(net "XM_DATA6")
	)
	(segment
		(start 90.2462 -81.780888)
		(end 89.9922 -81.780888)
		(width 0.127)
		(layer "In2.Cu")
		(net "XM_DATA6")
	)
	(segment
		(start 94.4118 -82.3214)
		(end 93.871288 -81.780888)
		(width 0.127)
		(layer "In2.Cu")
		(net "XM_DATA6")
	)
	(segment
		(start 90.5002 -82.3214)
		(end 90.3732 -82.1944)
		(width 0.127)
		(layer "In2.Cu")
		(net "XM_DATA6")
	)
	(segment
		(start 111.499904 -81.500218)
		(end 111.999776 -82.00009)
		(width 0.127)
		(layer "F.Cu")
		(net "XM_DATA5")
	)
	(via
		(at 111.999776 -82.00009)
		(size 0.4572)
		(drill 0.2032)
		(layers "F.Cu" "B.Cu")
		(net "XM_DATA5")
	)
	(via
		(at 79.883 -82.359754)
		(size 0.508)
		(drill 0.254)
		(layers "F.Cu" "B.Cu")
		(net "XM_DATA5")
	)
	(segment
		(start 79.883 -79.991966)
		(end 78.7908 -78.899766)
		(width 0.127)
		(layer "B.Cu")
		(net "XM_DATA5")
	)
	(segment
		(start 79.883 -82.359754)
		(end 79.883 -79.991966)
		(width 0.127)
		(layer "B.Cu")
		(net "XM_DATA5")
	)
	(segment
		(start 78.7908 -75.62596)
		(end 78.76794 -75.6031)
		(width 0.127)
		(layer "B.Cu")
		(net "XM_DATA5")
	)
	(segment
		(start 78.7908 -78.899766)
		(end 78.7908 -75.62596)
		(width 0.127)
		(layer "B.Cu")
		(net "XM_DATA5")
	)
	(segment
		(start 108.1024 -80.4672)
		(end 98.7806 -80.4672)
		(width 0.127)
		(layer "In2.Cu")
		(net "XM_DATA5")
	)
	(segment
		(start 97.3328 -79.686658)
		(end 96.755458 -80.264)
		(width 0.127)
		(layer "In2.Cu")
		(net "XM_DATA5")
	)
	(segment
		(start 98.7806 -80.4672)
		(end 98.000058 -79.686658)
		(width 0.127)
		(layer "In2.Cu")
		(net "XM_DATA5")
	)
	(segment
		(start 108.458 -80.8228)
		(end 108.1024 -80.4672)
		(width 0.127)
		(layer "In2.Cu")
		(net "XM_DATA5")
	)
	(segment
		(start 86.814914 -80.058768)
		(end 86.814914 -80.723232)
		(width 0.127)
		(layer "In2.Cu")
		(net "XM_DATA5")
	)
	(segment
		(start 89.32545 -80.137)
		(end 89.07145 -80.137)
		(width 0.127)
		(layer "In2.Cu")
		(net "XM_DATA5")
	)
	(segment
		(start 108.458 -81.153254)
		(end 108.458 -80.8228)
		(width 0.127)
		(layer "In2.Cu")
		(net "XM_DATA5")
	)
	(segment
		(start 98.000058 -79.686658)
		(end 97.3328 -79.686658)
		(width 0.127)
		(layer "In2.Cu")
		(net "XM_DATA5")
	)
	(segment
		(start 88.94445 -80.01)
		(end 88.94445 -79.813658)
		(width 0.127)
		(layer "In2.Cu")
		(net "XM_DATA5")
	)
	(segment
		(start 87.187024 -79.686658)
		(end 86.814914 -80.058768)
		(width 0.127)
		(layer "In2.Cu")
		(net "XM_DATA5")
	)
	(segment
		(start 108.991146 -81.6864)
		(end 108.458 -81.153254)
		(width 0.127)
		(layer "In2.Cu")
		(net "XM_DATA5")
	)
	(segment
		(start 111.686086 -81.6864)
		(end 108.991146 -81.6864)
		(width 0.127)
		(layer "In2.Cu")
		(net "XM_DATA5")
	)
	(segment
		(start 85.394546 -82.1436)
		(end 80.4164 -82.1436)
		(width 0.127)
		(layer "In2.Cu")
		(net "XM_DATA5")
	)
	(segment
		(start 88.81745 -79.686658)
		(end 87.187024 -79.686658)
		(width 0.127)
		(layer "In2.Cu")
		(net "XM_DATA5")
	)
	(segment
		(start 86.814914 -80.723232)
		(end 85.394546 -82.1436)
		(width 0.127)
		(layer "In2.Cu")
		(net "XM_DATA5")
	)
	(segment
		(start 94.8436 -79.686658)
		(end 94.27337 -80.256888)
		(width 0.127)
		(layer "In2.Cu")
		(net "XM_DATA5")
	)
	(segment
		(start 89.07145 -80.137)
		(end 88.94445 -80.01)
		(width 0.127)
		(layer "In2.Cu")
		(net "XM_DATA5")
	)
	(segment
		(start 95.409258 -79.686658)
		(end 94.8436 -79.686658)
		(width 0.127)
		(layer "In2.Cu")
		(net "XM_DATA5")
	)
	(segment
		(start 111.999776 -82.00009)
		(end 111.686086 -81.6864)
		(width 0.127)
		(layer "In2.Cu")
		(net "XM_DATA5")
	)
	(segment
		(start 80.200246 -82.359754)
		(end 79.883 -82.359754)
		(width 0.127)
		(layer "In2.Cu")
		(net "XM_DATA5")
	)
	(segment
		(start 95.9866 -80.264)
		(end 95.409258 -79.686658)
		(width 0.127)
		(layer "In2.Cu")
		(net "XM_DATA5")
	)
	(segment
		(start 89.45245 -80.01)
		(end 89.32545 -80.137)
		(width 0.127)
		(layer "In2.Cu")
		(net "XM_DATA5")
	)
	(segment
		(start 92.513658 -79.686658)
		(end 89.57945 -79.686658)
		(width 0.127)
		(layer "In2.Cu")
		(net "XM_DATA5")
	)
	(segment
		(start 94.27337 -80.256888)
		(end 93.083888 -80.256888)
		(width 0.127)
		(layer "In2.Cu")
		(net "XM_DATA5")
	)
	(segment
		(start 89.57945 -79.686658)
		(end 89.45245 -79.813658)
		(width 0.127)
		(layer "In2.Cu")
		(net "XM_DATA5")
	)
	(segment
		(start 89.45245 -79.813658)
		(end 89.45245 -80.01)
		(width 0.127)
		(layer "In2.Cu")
		(net "XM_DATA5")
	)
	(segment
		(start 80.4164 -82.1436)
		(end 80.200246 -82.359754)
		(width 0.127)
		(layer "In2.Cu")
		(net "XM_DATA5")
	)
	(segment
		(start 88.94445 -79.813658)
		(end 88.81745 -79.686658)
		(width 0.127)
		(layer "In2.Cu")
		(net "XM_DATA5")
	)
	(segment
		(start 93.083888 -80.256888)
		(end 92.513658 -79.686658)
		(width 0.127)
		(layer "In2.Cu")
		(net "XM_DATA5")
	)
	(segment
		(start 96.755458 -80.264)
		(end 95.9866 -80.264)
		(width 0.127)
		(layer "In2.Cu")
		(net "XM_DATA5")
	)
	(segment
		(start 112.499902 -72.500236)
		(end 112.00003 -73.000108)
		(width 0.127)
		(layer "F.Cu")
		(net "XM_DATA4")
	)
	(via
		(at 112.00003 -73.000108)
		(size 0.4572)
		(drill 0.2032)
		(layers "F.Cu" "B.Cu")
		(net "XM_DATA4")
	)
	(via
		(at 79.76743 -76.9366)
		(size 0.508)
		(drill 0.254)
		(layers "F.Cu" "B.Cu")
		(net "XM_DATA4")
	)
	(segment
		(start 79.76743 -75.6031)
		(end 79.76743 -76.9366)
		(width 0.127)
		(layer "B.Cu")
		(net "XM_DATA4")
	)
	(segment
		(start 94.851982 -70.866)
		(end 94.597982 -70.866)
		(width 0.127)
		(layer "In2.Cu")
		(net "XM_DATA4")
	)
	(segment
		(start 96.502982 -70.1802)
		(end 96.375982 -70.0532)
		(width 0.127)
		(layer "In2.Cu")
		(net "XM_DATA4")
	)
	(segment
		(start 97.137982 -70.0532)
		(end 97.010982 -70.1802)
		(width 0.127)
		(layer "In2.Cu")
		(net "XM_DATA4")
	)
	(segment
		(start 95.105982 -70.0532)
		(end 94.978982 -70.1802)
		(width 0.127)
		(layer "In2.Cu")
		(net "XM_DATA4")
	)
	(segment
		(start 95.994982 -70.1802)
		(end 95.994982 -70.739)
		(width 0.127)
		(layer "In2.Cu")
		(net "XM_DATA4")
	)
	(segment
		(start 96.883982 -70.866)
		(end 96.629982 -70.866)
		(width 0.127)
		(layer "In2.Cu")
		(net "XM_DATA4")
	)
	(segment
		(start 97.010982 -70.1802)
		(end 97.010982 -70.739)
		(width 0.127)
		(layer "In2.Cu")
		(net "XM_DATA4")
	)
	(segment
		(start 95.613982 -70.866)
		(end 95.486982 -70.739)
		(width 0.127)
		(layer "In2.Cu")
		(net "XM_DATA4")
	)
	(segment
		(start 94.978982 -70.739)
		(end 94.851982 -70.866)
		(width 0.127)
		(layer "In2.Cu")
		(net "XM_DATA4")
	)
	(segment
		(start 112.00003 -72.661526)
		(end 110.525306 -71.186802)
		(width 0.127)
		(layer "In2.Cu")
		(net "XM_DATA4")
	)
	(segment
		(start 98.806 -69.5452)
		(end 98.298 -70.0532)
		(width 0.127)
		(layer "In2.Cu")
		(net "XM_DATA4")
	)
	(segment
		(start 82.4738 -73.406)
		(end 82.4738 -74.23023)
		(width 0.127)
		(layer "In2.Cu")
		(net "XM_DATA4")
	)
	(segment
		(start 109.542326 -69.985382)
		(end 109.102144 -69.5452)
		(width 0.127)
		(layer "In2.Cu")
		(net "XM_DATA4")
	)
	(segment
		(start 96.121982 -70.0532)
		(end 95.994982 -70.1802)
		(width 0.127)
		(layer "In2.Cu")
		(net "XM_DATA4")
	)
	(segment
		(start 94.978982 -70.1802)
		(end 94.978982 -70.739)
		(width 0.127)
		(layer "In2.Cu")
		(net "XM_DATA4")
	)
	(segment
		(start 89.138252 -71.948548)
		(end 83.931252 -71.948548)
		(width 0.127)
		(layer "In2.Cu")
		(net "XM_DATA4")
	)
	(segment
		(start 94.470982 -70.739)
		(end 94.470982 -70.1802)
		(width 0.127)
		(layer "In2.Cu")
		(net "XM_DATA4")
	)
	(segment
		(start 95.486982 -70.1802)
		(end 95.359982 -70.0532)
		(width 0.127)
		(layer "In2.Cu")
		(net "XM_DATA4")
	)
	(segment
		(start 96.375982 -70.0532)
		(end 96.121982 -70.0532)
		(width 0.127)
		(layer "In2.Cu")
		(net "XM_DATA4")
	)
	(segment
		(start 110.116366 -70.559676)
		(end 110.002574 -70.559676)
		(width 0.127)
		(layer "In2.Cu")
		(net "XM_DATA4")
	)
	(segment
		(start 95.359982 -70.0532)
		(end 95.105982 -70.0532)
		(width 0.127)
		(layer "In2.Cu")
		(net "XM_DATA4")
	)
	(segment
		(start 95.486982 -70.739)
		(end 95.486982 -70.1802)
		(width 0.127)
		(layer "In2.Cu")
		(net "XM_DATA4")
	)
	(segment
		(start 109.542326 -70.099428)
		(end 109.542326 -69.985382)
		(width 0.127)
		(layer "In2.Cu")
		(net "XM_DATA4")
	)
	(segment
		(start 110.525306 -71.186802)
		(end 110.525306 -70.968616)
		(width 0.127)
		(layer "In2.Cu")
		(net "XM_DATA4")
	)
	(segment
		(start 98.298 -70.0532)
		(end 97.137982 -70.0532)
		(width 0.127)
		(layer "In2.Cu")
		(net "XM_DATA4")
	)
	(segment
		(start 95.994982 -70.739)
		(end 95.867982 -70.866)
		(width 0.127)
		(layer "In2.Cu")
		(net "XM_DATA4")
	)
	(segment
		(start 97.010982 -70.739)
		(end 96.883982 -70.866)
		(width 0.127)
		(layer "In2.Cu")
		(net "XM_DATA4")
	)
	(segment
		(start 112.00003 -73.000108)
		(end 112.00003 -72.661526)
		(width 0.127)
		(layer "In2.Cu")
		(net "XM_DATA4")
	)
	(segment
		(start 83.931252 -71.948548)
		(end 82.4738 -73.406)
		(width 0.127)
		(layer "In2.Cu")
		(net "XM_DATA4")
	)
	(segment
		(start 110.525306 -70.968616)
		(end 110.116366 -70.559676)
		(width 0.127)
		(layer "In2.Cu")
		(net "XM_DATA4")
	)
	(segment
		(start 94.597982 -70.866)
		(end 94.470982 -70.739)
		(width 0.127)
		(layer "In2.Cu")
		(net "XM_DATA4")
	)
	(segment
		(start 91.0336 -70.0532)
		(end 89.138252 -71.948548)
		(width 0.127)
		(layer "In2.Cu")
		(net "XM_DATA4")
	)
	(segment
		(start 95.867982 -70.866)
		(end 95.613982 -70.866)
		(width 0.127)
		(layer "In2.Cu")
		(net "XM_DATA4")
	)
	(segment
		(start 96.502982 -70.739)
		(end 96.502982 -70.1802)
		(width 0.127)
		(layer "In2.Cu")
		(net "XM_DATA4")
	)
	(segment
		(start 94.470982 -70.1802)
		(end 94.343982 -70.0532)
		(width 0.127)
		(layer "In2.Cu")
		(net "XM_DATA4")
	)
	(segment
		(start 110.002574 -70.559676)
		(end 109.542326 -70.099428)
		(width 0.127)
		(layer "In2.Cu")
		(net "XM_DATA4")
	)
	(segment
		(start 96.629982 -70.866)
		(end 96.502982 -70.739)
		(width 0.127)
		(layer "In2.Cu")
		(net "XM_DATA4")
	)
	(segment
		(start 109.102144 -69.5452)
		(end 98.806 -69.5452)
		(width 0.127)
		(layer "In2.Cu")
		(net "XM_DATA4")
	)
	(segment
		(start 82.4738 -74.23023)
		(end 79.76743 -76.9366)
		(width 0.127)
		(layer "In2.Cu")
		(net "XM_DATA4")
	)
	(segment
		(start 94.343982 -70.0532)
		(end 91.0336 -70.0532)
		(width 0.127)
		(layer "In2.Cu")
		(net "XM_DATA4")
	)
	(segment
		(start 112.499902 -82.500216)
		(end 112.499902 -83.109816)
		(width 0.127)
		(layer "F.Cu")
		(net "XM_DATA3")
	)
	(via
		(at 79.8576 -83.274154)
		(size 0.508)
		(drill 0.254)
		(layers "F.Cu" "B.Cu")
		(net "XM_DATA3")
	)
	(via
		(at 112.499902 -83.109816)
		(size 0.4572)
		(drill 0.2032)
		(layers "F.Cu" "B.Cu")
		(net "XM_DATA3")
	)
	(segment
		(start 80.7466 -82.385154)
		(end 79.8576 -83.274154)
		(width 0.127)
		(layer "B.Cu")
		(net "XM_DATA3")
	)
	(segment
		(start 81.26857 -75.6031)
		(end 81.26857 -76.604876)
		(width 0.127)
		(layer "B.Cu")
		(net "XM_DATA3")
	)
	(segment
		(start 81.26857 -76.604876)
		(end 80.7466 -77.126846)
		(width 0.127)
		(layer "B.Cu")
		(net "XM_DATA3")
	)
	(segment
		(start 80.7466 -77.126846)
		(end 80.7466 -82.385154)
		(width 0.127)
		(layer "B.Cu")
		(net "XM_DATA3")
	)
	(segment
		(start 108.389166 -82.49158)
		(end 108.686346 -82.1944)
		(width 0.127)
		(layer "In2.Cu")
		(net "XM_DATA3")
	)
	(segment
		(start 81.164684 -83.2866)
		(end 81.291684 -83.4136)
		(width 0.127)
		(layer "In2.Cu")
		(net "XM_DATA3")
	)
	(segment
		(start 82.180684 -83.0326)
		(end 82.307684 -83.1596)
		(width 0.127)
		(layer "In2.Cu")
		(net "XM_DATA3")
	)
	(segment
		(start 81.291684 -83.4136)
		(end 81.545684 -83.4136)
		(width 0.127)
		(layer "In2.Cu")
		(net "XM_DATA3")
	)
	(segment
		(start 85.852 -83.1596)
		(end 87.738712 -81.272888)
		(width 0.127)
		(layer "In2.Cu")
		(net "XM_DATA3")
	)
	(segment
		(start 82.307684 -83.1596)
		(end 85.852 -83.1596)
		(width 0.127)
		(layer "In2.Cu")
		(net "XM_DATA3")
	)
	(segment
		(start 82.053684 -82.6516)
		(end 82.180684 -82.7786)
		(width 0.127)
		(layer "In2.Cu")
		(net "XM_DATA3")
	)
	(segment
		(start 80.047846 -83.4644)
		(end 80.529684 -83.4644)
		(width 0.127)
		(layer "In2.Cu")
		(net "XM_DATA3")
	)
	(segment
		(start 111.2012 -82.1944)
		(end 112.116616 -83.109816)
		(width 0.127)
		(layer "In2.Cu")
		(net "XM_DATA3")
	)
	(segment
		(start 112.116616 -83.109816)
		(end 112.499902 -83.109816)
		(width 0.127)
		(layer "In2.Cu")
		(net "XM_DATA3")
	)
	(segment
		(start 94.081854 -81.272888)
		(end 94.622366 -81.8134)
		(width 0.127)
		(layer "In2.Cu")
		(net "XM_DATA3")
	)
	(segment
		(start 81.672684 -83.2866)
		(end 81.672684 -82.7786)
		(width 0.127)
		(layer "In2.Cu")
		(net "XM_DATA3")
	)
	(segment
		(start 79.8576 -83.274154)
		(end 80.047846 -83.4644)
		(width 0.127)
		(layer "In2.Cu")
		(net "XM_DATA3")
	)
	(segment
		(start 80.656684 -82.7786)
		(end 80.783684 -82.6516)
		(width 0.127)
		(layer "In2.Cu")
		(net "XM_DATA3")
	)
	(segment
		(start 80.783684 -82.6516)
		(end 81.037684 -82.6516)
		(width 0.127)
		(layer "In2.Cu")
		(net "XM_DATA3")
	)
	(segment
		(start 81.799684 -82.6516)
		(end 82.053684 -82.6516)
		(width 0.127)
		(layer "In2.Cu")
		(net "XM_DATA3")
	)
	(segment
		(start 81.037684 -82.6516)
		(end 81.164684 -82.7786)
		(width 0.127)
		(layer "In2.Cu")
		(net "XM_DATA3")
	)
	(segment
		(start 81.545684 -83.4136)
		(end 81.672684 -83.2866)
		(width 0.127)
		(layer "In2.Cu")
		(net "XM_DATA3")
	)
	(segment
		(start 97.888806 -81.8134)
		(end 98.566986 -82.49158)
		(width 0.127)
		(layer "In2.Cu")
		(net "XM_DATA3")
	)
	(segment
		(start 81.672684 -82.7786)
		(end 81.799684 -82.6516)
		(width 0.127)
		(layer "In2.Cu")
		(net "XM_DATA3")
	)
	(segment
		(start 80.529684 -83.4644)
		(end 80.656684 -83.3374)
		(width 0.127)
		(layer "In2.Cu")
		(net "XM_DATA3")
	)
	(segment
		(start 87.738712 -81.272888)
		(end 94.081854 -81.272888)
		(width 0.127)
		(layer "In2.Cu")
		(net "XM_DATA3")
	)
	(segment
		(start 98.566986 -82.49158)
		(end 108.389166 -82.49158)
		(width 0.127)
		(layer "In2.Cu")
		(net "XM_DATA3")
	)
	(segment
		(start 81.164684 -82.7786)
		(end 81.164684 -83.2866)
		(width 0.127)
		(layer "In2.Cu")
		(net "XM_DATA3")
	)
	(segment
		(start 82.180684 -82.7786)
		(end 82.180684 -83.0326)
		(width 0.127)
		(layer "In2.Cu")
		(net "XM_DATA3")
	)
	(segment
		(start 80.656684 -83.3374)
		(end 80.656684 -82.7786)
		(width 0.127)
		(layer "In2.Cu")
		(net "XM_DATA3")
	)
	(segment
		(start 108.686346 -82.1944)
		(end 111.2012 -82.1944)
		(width 0.127)
		(layer "In2.Cu")
		(net "XM_DATA3")
	)
	(segment
		(start 94.622366 -81.8134)
		(end 97.888806 -81.8134)
		(width 0.127)
		(layer "In2.Cu")
		(net "XM_DATA3")
	)
	(segment
		(start 112.499902 -81.500218)
		(end 112.999774 -82.00009)
		(width 0.127)
		(layer "F.Cu")
		(net "XM_DATA2")
	)
	(via
		(at 112.999774 -82.00009)
		(size 0.4572)
		(drill 0.2032)
		(layers "F.Cu" "B.Cu")
		(net "XM_DATA2")
	)
	(via
		(at 82.677 -81.6356)
		(size 0.508)
		(drill 0.254)
		(layers "F.Cu" "B.Cu")
		(net "XM_DATA2")
	)
	(segment
		(start 82.26806 -75.6031)
		(end 82.26806 -76.87945)
		(width 0.127)
		(layer "B.Cu")
		(net "XM_DATA2")
	)
	(segment
		(start 82.26806 -76.87945)
		(end 81.788 -77.35951)
		(width 0.127)
		(layer "B.Cu")
		(net "XM_DATA2")
	)
	(segment
		(start 81.788 -80.7466)
		(end 82.677 -81.6356)
		(width 0.127)
		(layer "B.Cu")
		(net "XM_DATA2")
	)
	(segment
		(start 81.788 -77.35951)
		(end 81.788 -80.7466)
		(width 0.127)
		(layer "B.Cu")
		(net "XM_DATA2")
	)
	(segment
		(start 108.5088 -79.831946)
		(end 108.5088 -80.169004)
		(width 0.127)
		(layer "In2.Cu")
		(net "XM_DATA2")
	)
	(segment
		(start 96.697546 -79.331058)
		(end 96.849946 -79.178658)
		(width 0.127)
		(layer "In2.Cu")
		(net "XM_DATA2")
	)
	(segment
		(start 84.946744 -80.686656)
		(end 85.126322 -80.507078)
		(width 0.127)
		(layer "In2.Cu")
		(net "XM_DATA2")
	)
	(segment
		(start 84.946744 -80.866488)
		(end 84.946744 -80.686656)
		(width 0.127)
		(layer "In2.Cu")
		(net "XM_DATA2")
	)
	(segment
		(start 84.064856 -81.6356)
		(end 84.369656 -81.3308)
		(width 0.127)
		(layer "In2.Cu")
		(net "XM_DATA2")
	)
	(segment
		(start 82.677 -81.6356)
		(end 84.064856 -81.6356)
		(width 0.127)
		(layer "In2.Cu")
		(net "XM_DATA2")
	)
	(segment
		(start 96.189546 -79.331058)
		(end 96.189546 -79.629)
		(width 0.127)
		(layer "In2.Cu")
		(net "XM_DATA2")
	)
	(segment
		(start 96.570546 -79.756)
		(end 96.697546 -79.629)
		(width 0.127)
		(layer "In2.Cu")
		(net "XM_DATA2")
	)
	(segment
		(start 86.976458 -79.178658)
		(end 93.222064 -79.178658)
		(width 0.127)
		(layer "In2.Cu")
		(net "XM_DATA2")
	)
	(segment
		(start 112.2172 -81.4324)
		(end 112.78489 -82.00009)
		(width 0.127)
		(layer "In2.Cu")
		(net "XM_DATA2")
	)
	(segment
		(start 109.5502 -81.154016)
		(end 109.828584 -81.4324)
		(width 0.127)
		(layer "In2.Cu")
		(net "XM_DATA2")
	)
	(segment
		(start 112.78489 -82.00009)
		(end 112.999774 -82.00009)
		(width 0.127)
		(layer "In2.Cu")
		(net "XM_DATA2")
	)
	(segment
		(start 84.369656 -81.3308)
		(end 84.692236 -81.3308)
		(width 0.127)
		(layer "In2.Cu")
		(net "XM_DATA2")
	)
	(segment
		(start 96.316546 -79.756)
		(end 96.570546 -79.756)
		(width 0.127)
		(layer "In2.Cu")
		(net "XM_DATA2")
	)
	(segment
		(start 93.349064 -79.305658)
		(end 93.349064 -79.6036)
		(width 0.127)
		(layer "In2.Cu")
		(net "XM_DATA2")
	)
	(segment
		(start 85.126322 -80.507078)
		(end 85.306154 -80.507078)
		(width 0.127)
		(layer "In2.Cu")
		(net "XM_DATA2")
	)
	(segment
		(start 93.857064 -79.6036)
		(end 93.857064 -79.305658)
		(width 0.127)
		(layer "In2.Cu")
		(net "XM_DATA2")
	)
	(segment
		(start 108.5088 -80.169004)
		(end 108.857796 -80.518)
		(width 0.127)
		(layer "In2.Cu")
		(net "XM_DATA2")
	)
	(segment
		(start 85.890354 -80.911446)
		(end 86.069932 -80.731868)
		(width 0.127)
		(layer "In2.Cu")
		(net "XM_DATA2")
	)
	(segment
		(start 85.171534 -81.630266)
		(end 85.351112 -81.450688)
		(width 0.127)
		(layer "In2.Cu")
		(net "XM_DATA2")
	)
	(segment
		(start 93.349064 -79.6036)
		(end 93.476064 -79.7306)
		(width 0.127)
		(layer "In2.Cu")
		(net "XM_DATA2")
	)
	(segment
		(start 93.476064 -79.7306)
		(end 93.730064 -79.7306)
		(width 0.127)
		(layer "In2.Cu")
		(net "XM_DATA2")
	)
	(segment
		(start 93.222064 -79.178658)
		(end 93.349064 -79.305658)
		(width 0.127)
		(layer "In2.Cu")
		(net "XM_DATA2")
	)
	(segment
		(start 108.857796 -80.518)
		(end 109.144054 -80.518)
		(width 0.127)
		(layer "In2.Cu")
		(net "XM_DATA2")
	)
	(segment
		(start 85.939122 -80.421226)
		(end 85.939122 -80.215994)
		(width 0.127)
		(layer "In2.Cu")
		(net "XM_DATA2")
	)
	(segment
		(start 85.351112 -81.270856)
		(end 84.946744 -80.866488)
		(width 0.127)
		(layer "In2.Cu")
		(net "XM_DATA2")
	)
	(segment
		(start 108.121958 -79.445104)
		(end 108.5088 -79.831946)
		(width 0.127)
		(layer "In2.Cu")
		(net "XM_DATA2")
	)
	(segment
		(start 96.697546 -79.629)
		(end 96.697546 -79.331058)
		(width 0.127)
		(layer "In2.Cu")
		(net "XM_DATA2")
	)
	(segment
		(start 109.828584 -81.4324)
		(end 112.2172 -81.4324)
		(width 0.127)
		(layer "In2.Cu")
		(net "XM_DATA2")
	)
	(segment
		(start 96.849946 -79.178658)
		(end 98.207068 -79.178658)
		(width 0.127)
		(layer "In2.Cu")
		(net "XM_DATA2")
	)
	(segment
		(start 85.306154 -80.507078)
		(end 85.710522 -80.911446)
		(width 0.127)
		(layer "In2.Cu")
		(net "XM_DATA2")
	)
	(segment
		(start 96.189546 -79.629)
		(end 96.316546 -79.756)
		(width 0.127)
		(layer "In2.Cu")
		(net "XM_DATA2")
	)
	(segment
		(start 98.207068 -79.178658)
		(end 98.473514 -79.445104)
		(width 0.127)
		(layer "In2.Cu")
		(net "XM_DATA2")
	)
	(segment
		(start 86.069932 -80.731868)
		(end 86.069932 -80.552036)
		(width 0.127)
		(layer "In2.Cu")
		(net "XM_DATA2")
	)
	(segment
		(start 84.692236 -81.3308)
		(end 84.991702 -81.630266)
		(width 0.127)
		(layer "In2.Cu")
		(net "XM_DATA2")
	)
	(segment
		(start 93.857064 -79.305658)
		(end 93.984064 -79.178658)
		(width 0.127)
		(layer "In2.Cu")
		(net "XM_DATA2")
	)
	(segment
		(start 109.144054 -80.518)
		(end 109.5502 -80.924146)
		(width 0.127)
		(layer "In2.Cu")
		(net "XM_DATA2")
	)
	(segment
		(start 85.710522 -80.911446)
		(end 85.890354 -80.911446)
		(width 0.127)
		(layer "In2.Cu")
		(net "XM_DATA2")
	)
	(segment
		(start 85.351112 -81.450688)
		(end 85.351112 -81.270856)
		(width 0.127)
		(layer "In2.Cu")
		(net "XM_DATA2")
	)
	(segment
		(start 86.069932 -80.552036)
		(end 85.939122 -80.421226)
		(width 0.127)
		(layer "In2.Cu")
		(net "XM_DATA2")
	)
	(segment
		(start 93.984064 -79.178658)
		(end 96.037146 -79.178658)
		(width 0.127)
		(layer "In2.Cu")
		(net "XM_DATA2")
	)
	(segment
		(start 109.5502 -80.924146)
		(end 109.5502 -81.154016)
		(width 0.127)
		(layer "In2.Cu")
		(net "XM_DATA2")
	)
	(segment
		(start 93.730064 -79.7306)
		(end 93.857064 -79.6036)
		(width 0.127)
		(layer "In2.Cu")
		(net "XM_DATA2")
	)
	(segment
		(start 96.037146 -79.178658)
		(end 96.189546 -79.331058)
		(width 0.127)
		(layer "In2.Cu")
		(net "XM_DATA2")
	)
	(segment
		(start 98.473514 -79.445104)
		(end 108.121958 -79.445104)
		(width 0.127)
		(layer "In2.Cu")
		(net "XM_DATA2")
	)
	(segment
		(start 84.991702 -81.630266)
		(end 85.171534 -81.630266)
		(width 0.127)
		(layer "In2.Cu")
		(net "XM_DATA2")
	)
	(segment
		(start 85.939122 -80.215994)
		(end 86.976458 -79.178658)
		(width 0.127)
		(layer "In2.Cu")
		(net "XM_DATA2")
	)
	(segment
		(start 112.499902 -77.500226)
		(end 112.00003 -78.000098)
		(width 0.127)
		(layer "F.Cu")
		(net "XM_DATA15")
	)
	(via
		(at 76.613512 -81.409794)
		(size 0.508)
		(drill 0.254)
		(layers "F.Cu" "B.Cu")
		(net "XM_DATA15")
	)
	(via
		(at 112.00003 -78.000098)
		(size 0.4572)
		(drill 0.2032)
		(layers "F.Cu" "B.Cu")
		(net "XM_DATA15")
	)
	(segment
		(start 75.9968 -76.6826)
		(end 76.26858 -76.41082)
		(width 0.127)
		(layer "B.Cu")
		(net "XM_DATA15")
	)
	(segment
		(start 75.9968 -78.546452)
		(end 75.9968 -76.6826)
		(width 0.127)
		(layer "B.Cu")
		(net "XM_DATA15")
	)
	(segment
		(start 76.26858 -76.41082)
		(end 76.26858 -75.6031)
		(width 0.127)
		(layer "B.Cu")
		(net "XM_DATA15")
	)
	(segment
		(start 76.613512 -81.409794)
		(end 76.613512 -79.163164)
		(width 0.127)
		(layer "B.Cu")
		(net "XM_DATA15")
	)
	(segment
		(start 76.613512 -79.163164)
		(end 75.9968 -78.546452)
		(width 0.127)
		(layer "B.Cu")
		(net "XM_DATA15")
	)
	(segment
		(start 82.823558 -79.74203)
		(end 86.217506 -76.348082)
		(width 0.127)
		(layer "In2.Cu")
		(net "XM_DATA15")
	)
	(segment
		(start 110.472728 -77.108812)
		(end 110.910878 -77.546962)
		(width 0.127)
		(layer "In2.Cu")
		(net "XM_DATA15")
	)
	(segment
		(start 78.281276 -79.74203)
		(end 82.823558 -79.74203)
		(width 0.127)
		(layer "In2.Cu")
		(net "XM_DATA15")
	)
	(segment
		(start 86.217506 -76.348082)
		(end 97.549208 -76.348082)
		(width 0.127)
		(layer "In2.Cu")
		(net "XM_DATA15")
	)
	(segment
		(start 98.35769 -75.5396)
		(end 109.1946 -75.5396)
		(width 0.127)
		(layer "In2.Cu")
		(net "XM_DATA15")
	)
	(segment
		(start 109.5248 -75.8698)
		(end 109.5248 -76.174346)
		(width 0.127)
		(layer "In2.Cu")
		(net "XM_DATA15")
	)
	(segment
		(start 109.887004 -76.53655)
		(end 110.19155 -76.53655)
		(width 0.127)
		(layer "In2.Cu")
		(net "XM_DATA15")
	)
	(segment
		(start 110.910878 -77.546962)
		(end 111.546894 -77.546962)
		(width 0.127)
		(layer "In2.Cu")
		(net "XM_DATA15")
	)
	(segment
		(start 97.549208 -76.348082)
		(end 98.35769 -75.5396)
		(width 0.127)
		(layer "In2.Cu")
		(net "XM_DATA15")
	)
	(segment
		(start 109.5248 -76.174346)
		(end 109.887004 -76.53655)
		(width 0.127)
		(layer "In2.Cu")
		(net "XM_DATA15")
	)
	(segment
		(start 76.613512 -81.409794)
		(end 78.281276 -79.74203)
		(width 0.127)
		(layer "In2.Cu")
		(net "XM_DATA15")
	)
	(segment
		(start 109.1946 -75.5396)
		(end 109.5248 -75.8698)
		(width 0.127)
		(layer "In2.Cu")
		(net "XM_DATA15")
	)
	(segment
		(start 111.546894 -77.546962)
		(end 112.00003 -78.000098)
		(width 0.127)
		(layer "In2.Cu")
		(net "XM_DATA15")
	)
	(segment
		(start 110.472728 -76.817728)
		(end 110.472728 -77.108812)
		(width 0.127)
		(layer "In2.Cu")
		(net "XM_DATA15")
	)
	(segment
		(start 110.19155 -76.53655)
		(end 110.472728 -76.817728)
		(width 0.127)
		(layer "In2.Cu")
		(net "XM_DATA15")
	)
	(segment
		(start 112.499902 -78.500224)
		(end 112.00003 -79.000096)
		(width 0.127)
		(layer "F.Cu")
		(net "XM_DATA14")
	)
	(via
		(at 77.629512 -81.409794)
		(size 0.508)
		(drill 0.254)
		(layers "F.Cu" "B.Cu")
		(net "XM_DATA14")
	)
	(via
		(at 112.00003 -79.000096)
		(size 0.4572)
		(drill 0.2032)
		(layers "F.Cu" "B.Cu")
		(net "XM_DATA14")
	)
	(segment
		(start 77.629512 -78.63332)
		(end 77.1144 -78.118208)
		(width 0.127)
		(layer "B.Cu")
		(net "XM_DATA14")
	)
	(segment
		(start 77.27188 -76.601574)
		(end 77.26807 -76.597764)
		(width 0.127)
		(layer "B.Cu")
		(net "XM_DATA14")
	)
	(segment
		(start 77.1144 -76.759054)
		(end 77.27188 -76.601574)
		(width 0.127)
		(layer "B.Cu")
		(net "XM_DATA14")
	)
	(segment
		(start 77.629512 -81.409794)
		(end 77.629512 -78.63332)
		(width 0.127)
		(layer "B.Cu")
		(net "XM_DATA14")
	)
	(segment
		(start 77.1144 -78.118208)
		(end 77.1144 -76.759054)
		(width 0.127)
		(layer "B.Cu")
		(net "XM_DATA14")
	)
	(segment
		(start 77.26807 -76.597764)
		(end 77.26807 -75.6031)
		(width 0.127)
		(layer "B.Cu")
		(net "XM_DATA14")
	)
	(segment
		(start 88.923114 -76.856082)
		(end 88.359996 -77.4192)
		(width 0.127)
		(layer "In2.Cu")
		(net "XM_DATA14")
	)
	(segment
		(start 95.093282 -76.856082)
		(end 88.923114 -76.856082)
		(width 0.127)
		(layer "In2.Cu")
		(net "XM_DATA14")
	)
	(segment
		(start 109.09173 -76.452476)
		(end 98.274632 -76.452476)
		(width 0.127)
		(layer "In2.Cu")
		(net "XM_DATA14")
	)
	(segment
		(start 110.134654 -77.47)
		(end 109.8296 -77.47)
		(width 0.127)
		(layer "In2.Cu")
		(net "XM_DATA14")
	)
	(segment
		(start 87.63 -77.4192)
		(end 87.0966 -76.8858)
		(width 0.127)
		(layer "In2.Cu")
		(net "XM_DATA14")
	)
	(segment
		(start 112.00003 -79.000096)
		(end 111.485934 -78.486)
		(width 0.127)
		(layer "In2.Cu")
		(net "XM_DATA14")
	)
	(segment
		(start 87.0966 -76.8858)
		(end 86.398354 -76.8858)
		(width 0.127)
		(layer "In2.Cu")
		(net "XM_DATA14")
	)
	(segment
		(start 111.485934 -78.486)
		(end 110.7948 -78.486)
		(width 0.127)
		(layer "In2.Cu")
		(net "XM_DATA14")
	)
	(segment
		(start 97.136712 -77.590396)
		(end 95.827596 -77.590396)
		(width 0.127)
		(layer "In2.Cu")
		(net "XM_DATA14")
	)
	(segment
		(start 98.274632 -76.452476)
		(end 97.136712 -77.590396)
		(width 0.127)
		(layer "In2.Cu")
		(net "XM_DATA14")
	)
	(segment
		(start 110.482634 -78.173834)
		(end 110.482634 -77.81798)
		(width 0.127)
		(layer "In2.Cu")
		(net "XM_DATA14")
	)
	(segment
		(start 86.398354 -76.8858)
		(end 83.034124 -80.25003)
		(width 0.127)
		(layer "In2.Cu")
		(net "XM_DATA14")
	)
	(segment
		(start 109.560614 -76.92136)
		(end 109.09173 -76.452476)
		(width 0.127)
		(layer "In2.Cu")
		(net "XM_DATA14")
	)
	(segment
		(start 83.034124 -80.25003)
		(end 78.789276 -80.25003)
		(width 0.127)
		(layer "In2.Cu")
		(net "XM_DATA14")
	)
	(segment
		(start 109.8296 -77.47)
		(end 109.560614 -77.201014)
		(width 0.127)
		(layer "In2.Cu")
		(net "XM_DATA14")
	)
	(segment
		(start 109.560614 -77.201014)
		(end 109.560614 -76.92136)
		(width 0.127)
		(layer "In2.Cu")
		(net "XM_DATA14")
	)
	(segment
		(start 110.482634 -77.81798)
		(end 110.134654 -77.47)
		(width 0.127)
		(layer "In2.Cu")
		(net "XM_DATA14")
	)
	(segment
		(start 110.7948 -78.486)
		(end 110.482634 -78.173834)
		(width 0.127)
		(layer "In2.Cu")
		(net "XM_DATA14")
	)
	(segment
		(start 88.359996 -77.4192)
		(end 87.63 -77.4192)
		(width 0.127)
		(layer "In2.Cu")
		(net "XM_DATA14")
	)
	(segment
		(start 78.789276 -80.25003)
		(end 77.629512 -81.409794)
		(width 0.127)
		(layer "In2.Cu")
		(net "XM_DATA14")
	)
	(segment
		(start 95.827596 -77.590396)
		(end 95.093282 -76.856082)
		(width 0.127)
		(layer "In2.Cu")
		(net "XM_DATA14")
	)
	(segment
		(start 112.499902 -73.500234)
		(end 112.00003 -74.000106)
		(width 0.127)
		(layer "F.Cu")
		(net "XM_DATA13")
	)
	(via
		(at 78.27772 -77.5208)
		(size 0.508)
		(drill 0.254)
		(layers "F.Cu" "B.Cu")
		(net "XM_DATA13")
	)
	(via
		(at 112.00003 -74.000106)
		(size 0.4572)
		(drill 0.2032)
		(layers "F.Cu" "B.Cu")
		(net "XM_DATA13")
	)
	(segment
		(start 78.27772 -77.5208)
		(end 78.26756 -77.51064)
		(width 0.127)
		(layer "B.Cu")
		(net "XM_DATA13")
	)
	(segment
		(start 78.26756 -77.51064)
		(end 78.26756 -75.6031)
		(width 0.127)
		(layer "B.Cu")
		(net "XM_DATA13")
	)
	(segment
		(start 93.248734 -71.2724)
		(end 93.121734 -71.3994)
		(width 0.127)
		(layer "In2.Cu")
		(net "XM_DATA13")
	)
	(segment
		(start 97.911412 -71.3994)
		(end 93.883734 -71.3994)
		(width 0.127)
		(layer "In2.Cu")
		(net "XM_DATA13")
	)
	(segment
		(start 92.105734 -71.3994)
		(end 91.851734 -71.3994)
		(width 0.127)
		(layer "In2.Cu")
		(net "XM_DATA13")
	)
	(segment
		(start 112.00003 -73.87463)
		(end 111.55553 -73.43013)
		(width 0.127)
		(layer "In2.Cu")
		(net "XM_DATA13")
	)
	(segment
		(start 109.47781 -70.920864)
		(end 109.131608 -70.574662)
		(width 0.127)
		(layer "In2.Cu")
		(net "XM_DATA13")
	)
	(segment
		(start 93.121734 -71.3994)
		(end 92.867734 -71.3994)
		(width 0.127)
		(layer "In2.Cu")
		(net "XM_DATA13")
	)
	(segment
		(start 92.232734 -70.733412)
		(end 92.232734 -71.2724)
		(width 0.127)
		(layer "In2.Cu")
		(net "XM_DATA13")
	)
	(segment
		(start 91.209622 -70.606412)
		(end 89.359486 -72.456548)
		(width 0.127)
		(layer "In2.Cu")
		(net "XM_DATA13")
	)
	(segment
		(start 93.756734 -71.2724)
		(end 93.756734 -70.733412)
		(width 0.127)
		(layer "In2.Cu")
		(net "XM_DATA13")
	)
	(segment
		(start 93.375734 -70.606412)
		(end 93.248734 -70.733412)
		(width 0.127)
		(layer "In2.Cu")
		(net "XM_DATA13")
	)
	(segment
		(start 92.740734 -70.733412)
		(end 92.613734 -70.606412)
		(width 0.127)
		(layer "In2.Cu")
		(net "XM_DATA13")
	)
	(segment
		(start 91.724734 -70.733412)
		(end 91.597734 -70.606412)
		(width 0.127)
		(layer "In2.Cu")
		(net "XM_DATA13")
	)
	(segment
		(start 110.235746 -71.501)
		(end 109.943646 -71.501)
		(width 0.127)
		(layer "In2.Cu")
		(net "XM_DATA13")
	)
	(segment
		(start 109.943646 -71.501)
		(end 109.47781 -71.035164)
		(width 0.127)
		(layer "In2.Cu")
		(net "XM_DATA13")
	)
	(segment
		(start 93.629734 -70.606412)
		(end 93.375734 -70.606412)
		(width 0.127)
		(layer "In2.Cu")
		(net "XM_DATA13")
	)
	(segment
		(start 91.724734 -71.2724)
		(end 91.724734 -70.733412)
		(width 0.127)
		(layer "In2.Cu")
		(net "XM_DATA13")
	)
	(segment
		(start 92.867734 -71.3994)
		(end 92.740734 -71.2724)
		(width 0.127)
		(layer "In2.Cu")
		(net "XM_DATA13")
	)
	(segment
		(start 109.131608 -70.574662)
		(end 98.73615 -70.574662)
		(width 0.127)
		(layer "In2.Cu")
		(net "XM_DATA13")
	)
	(segment
		(start 92.232734 -71.2724)
		(end 92.105734 -71.3994)
		(width 0.127)
		(layer "In2.Cu")
		(net "XM_DATA13")
	)
	(segment
		(start 92.359734 -70.606412)
		(end 92.232734 -70.733412)
		(width 0.127)
		(layer "In2.Cu")
		(net "XM_DATA13")
	)
	(segment
		(start 111.55553 -73.43013)
		(end 111.55553 -72.820784)
		(width 0.127)
		(layer "In2.Cu")
		(net "XM_DATA13")
	)
	(segment
		(start 93.756734 -70.733412)
		(end 93.629734 -70.606412)
		(width 0.127)
		(layer "In2.Cu")
		(net "XM_DATA13")
	)
	(segment
		(start 80.4672 -77.5208)
		(end 78.27772 -77.5208)
		(width 0.127)
		(layer "In2.Cu")
		(net "XM_DATA13")
	)
	(segment
		(start 91.851734 -71.3994)
		(end 91.724734 -71.2724)
		(width 0.127)
		(layer "In2.Cu")
		(net "XM_DATA13")
	)
	(segment
		(start 111.55553 -72.820784)
		(end 110.235746 -71.501)
		(width 0.127)
		(layer "In2.Cu")
		(net "XM_DATA13")
	)
	(segment
		(start 92.613734 -70.606412)
		(end 92.359734 -70.606412)
		(width 0.127)
		(layer "In2.Cu")
		(net "XM_DATA13")
	)
	(segment
		(start 91.597734 -70.606412)
		(end 91.209622 -70.606412)
		(width 0.127)
		(layer "In2.Cu")
		(net "XM_DATA13")
	)
	(segment
		(start 89.359486 -72.456548)
		(end 85.531452 -72.456548)
		(width 0.127)
		(layer "In2.Cu")
		(net "XM_DATA13")
	)
	(segment
		(start 98.73615 -70.574662)
		(end 97.911412 -71.3994)
		(width 0.127)
		(layer "In2.Cu")
		(net "XM_DATA13")
	)
	(segment
		(start 109.47781 -71.035164)
		(end 109.47781 -70.920864)
		(width 0.127)
		(layer "In2.Cu")
		(net "XM_DATA13")
	)
	(segment
		(start 93.248734 -70.733412)
		(end 93.248734 -71.2724)
		(width 0.127)
		(layer "In2.Cu")
		(net "XM_DATA13")
	)
	(segment
		(start 93.883734 -71.3994)
		(end 93.756734 -71.2724)
		(width 0.127)
		(layer "In2.Cu")
		(net "XM_DATA13")
	)
	(segment
		(start 85.531452 -72.456548)
		(end 80.4672 -77.5208)
		(width 0.127)
		(layer "In2.Cu")
		(net "XM_DATA13")
	)
	(segment
		(start 92.740734 -71.2724)
		(end 92.740734 -70.733412)
		(width 0.127)
		(layer "In2.Cu")
		(net "XM_DATA13")
	)
	(segment
		(start 112.00003 -74.000106)
		(end 112.00003 -73.87463)
		(width 0.127)
		(layer "In2.Cu")
		(net "XM_DATA13")
	)
	(segment
		(start 112.499902 -76.500228)
		(end 112.00003 -77.0001)
		(width 0.127)
		(layer "F.Cu")
		(net "XM_DATA12")
	)
	(via
		(at 112.00003 -77.0001)
		(size 0.4572)
		(drill 0.2032)
		(layers "F.Cu" "B.Cu")
		(net "XM_DATA12")
	)
	(via
		(at 79.8322 -79.2226)
		(size 0.508)
		(drill 0.254)
		(layers "F.Cu" "B.Cu")
		(net "XM_DATA12")
	)
	(segment
		(start 79.2988 -77.0636)
		(end 79.26832 -77.03312)
		(width 0.127)
		(layer "B.Cu")
		(net "XM_DATA12")
	)
	(segment
		(start 79.2988 -78.6892)
		(end 79.2988 -77.0636)
		(width 0.127)
		(layer "B.Cu")
		(net "XM_DATA12")
	)
	(segment
		(start 79.8322 -79.2226)
		(end 79.2988 -78.6892)
		(width 0.127)
		(layer "B.Cu")
		(net "XM_DATA12")
	)
	(segment
		(start 79.26832 -77.03312)
		(end 79.26832 -75.6031)
		(width 0.127)
		(layer "B.Cu")
		(net "XM_DATA12")
	)
	(segment
		(start 92.907866 -75.713082)
		(end 92.780866 -75.840082)
		(width 0.127)
		(layer "In2.Cu")
		(net "XM_DATA12")
	)
	(segment
		(start 91.891866 -75.713082)
		(end 91.764866 -75.840082)
		(width 0.127)
		(layer "In2.Cu")
		(net "XM_DATA12")
	)
	(segment
		(start 82.776822 -79.0702)
		(end 79.9846 -79.0702)
		(width 0.127)
		(layer "In2.Cu")
		(net "XM_DATA12")
	)
	(segment
		(start 110.8456 -76.5048)
		(end 110.502192 -76.161392)
		(width 0.127)
		(layer "In2.Cu")
		(net "XM_DATA12")
	)
	(segment
		(start 93.923866 -75.713082)
		(end 93.796866 -75.840082)
		(width 0.127)
		(layer "In2.Cu")
		(net "XM_DATA12")
	)
	(segment
		(start 89.478866 -75.840082)
		(end 89.351866 -75.713082)
		(width 0.127)
		(layer "In2.Cu")
		(net "XM_DATA12")
	)
	(segment
		(start 92.399866 -75.3618)
		(end 92.272866 -75.2348)
		(width 0.127)
		(layer "In2.Cu")
		(net "XM_DATA12")
	)
	(segment
		(start 93.034866 -75.2348)
		(end 92.907866 -75.3618)
		(width 0.127)
		(layer "In2.Cu")
		(net "XM_DATA12")
	)
	(segment
		(start 93.923866 -75.3618)
		(end 93.923866 -75.713082)
		(width 0.127)
		(layer "In2.Cu")
		(net "XM_DATA12")
	)
	(segment
		(start 93.415866 -75.3618)
		(end 93.288866 -75.2348)
		(width 0.127)
		(layer "In2.Cu")
		(net "XM_DATA12")
	)
	(segment
		(start 89.732866 -75.840082)
		(end 89.478866 -75.840082)
		(width 0.127)
		(layer "In2.Cu")
		(net "XM_DATA12")
	)
	(segment
		(start 109.866938 -75.526138)
		(end 109.550708 -75.209908)
		(width 0.127)
		(layer "In2.Cu")
		(net "XM_DATA12")
	)
	(segment
		(start 91.891866 -75.3618)
		(end 91.891866 -75.713082)
		(width 0.127)
		(layer "In2.Cu")
		(net "XM_DATA12")
	)
	(segment
		(start 79.9846 -79.0702)
		(end 79.8322 -79.2226)
		(width 0.127)
		(layer "In2.Cu")
		(net "XM_DATA12")
	)
	(segment
		(start 89.859866 -75.3618)
		(end 89.859866 -75.713082)
		(width 0.127)
		(layer "In2.Cu")
		(net "XM_DATA12")
	)
	(segment
		(start 88.843866 -75.3618)
		(end 88.843866 -75.713082)
		(width 0.127)
		(layer "In2.Cu")
		(net "XM_DATA12")
	)
	(segment
		(start 93.542866 -75.840082)
		(end 93.415866 -75.713082)
		(width 0.127)
		(layer "In2.Cu")
		(net "XM_DATA12")
	)
	(segment
		(start 111.50473 -76.5048)
		(end 110.8456 -76.5048)
		(width 0.127)
		(layer "In2.Cu")
		(net "XM_DATA12")
	)
	(segment
		(start 90.367866 -75.3618)
		(end 90.240866 -75.2348)
		(width 0.127)
		(layer "In2.Cu")
		(net "XM_DATA12")
	)
	(segment
		(start 89.351866 -75.713082)
		(end 89.351866 -75.3618)
		(width 0.127)
		(layer "In2.Cu")
		(net "XM_DATA12")
	)
	(segment
		(start 88.843866 -75.713082)
		(end 88.716866 -75.840082)
		(width 0.127)
		(layer "In2.Cu")
		(net "XM_DATA12")
	)
	(segment
		(start 91.383866 -75.3618)
		(end 91.256866 -75.2348)
		(width 0.127)
		(layer "In2.Cu")
		(net "XM_DATA12")
	)
	(segment
		(start 94.558866 -75.840082)
		(end 94.431866 -75.713082)
		(width 0.127)
		(layer "In2.Cu")
		(net "XM_DATA12")
	)
	(segment
		(start 91.256866 -75.2348)
		(end 91.002866 -75.2348)
		(width 0.127)
		(layer "In2.Cu")
		(net "XM_DATA12")
	)
	(segment
		(start 89.859866 -75.713082)
		(end 89.732866 -75.840082)
		(width 0.127)
		(layer "In2.Cu")
		(net "XM_DATA12")
	)
	(segment
		(start 90.240866 -75.2348)
		(end 89.986866 -75.2348)
		(width 0.127)
		(layer "In2.Cu")
		(net "XM_DATA12")
	)
	(segment
		(start 91.002866 -75.2348)
		(end 90.875866 -75.3618)
		(width 0.127)
		(layer "In2.Cu")
		(net "XM_DATA12")
	)
	(segment
		(start 88.716866 -75.840082)
		(end 86.00694 -75.840082)
		(width 0.127)
		(layer "In2.Cu")
		(net "XM_DATA12")
	)
	(segment
		(start 109.550708 -74.905362)
		(end 109.194346 -74.549)
		(width 0.127)
		(layer "In2.Cu")
		(net "XM_DATA12")
	)
	(segment
		(start 92.907866 -75.3618)
		(end 92.907866 -75.713082)
		(width 0.127)
		(layer "In2.Cu")
		(net "XM_DATA12")
	)
	(segment
		(start 94.304866 -75.2348)
		(end 94.050866 -75.2348)
		(width 0.127)
		(layer "In2.Cu")
		(net "XM_DATA12")
	)
	(segment
		(start 90.748866 -75.840082)
		(end 90.494866 -75.840082)
		(width 0.127)
		(layer "In2.Cu")
		(net "XM_DATA12")
	)
	(segment
		(start 93.288866 -75.2348)
		(end 93.034866 -75.2348)
		(width 0.127)
		(layer "In2.Cu")
		(net "XM_DATA12")
	)
	(segment
		(start 109.550708 -75.209908)
		(end 109.550708 -74.905362)
		(width 0.127)
		(layer "In2.Cu")
		(net "XM_DATA12")
	)
	(segment
		(start 92.780866 -75.840082)
		(end 92.526866 -75.840082)
		(width 0.127)
		(layer "In2.Cu")
		(net "XM_DATA12")
	)
	(segment
		(start 93.796866 -75.840082)
		(end 93.542866 -75.840082)
		(width 0.127)
		(layer "In2.Cu")
		(net "XM_DATA12")
	)
	(segment
		(start 93.415866 -75.713082)
		(end 93.415866 -75.3618)
		(width 0.127)
		(layer "In2.Cu")
		(net "XM_DATA12")
	)
	(segment
		(start 98.452178 -74.549)
		(end 97.161096 -75.840082)
		(width 0.127)
		(layer "In2.Cu")
		(net "XM_DATA12")
	)
	(segment
		(start 97.161096 -75.840082)
		(end 94.558866 -75.840082)
		(width 0.127)
		(layer "In2.Cu")
		(net "XM_DATA12")
	)
	(segment
		(start 112.00003 -77.0001)
		(end 111.50473 -76.5048)
		(width 0.127)
		(layer "In2.Cu")
		(net "XM_DATA12")
	)
	(segment
		(start 90.367866 -75.713082)
		(end 90.367866 -75.3618)
		(width 0.127)
		(layer "In2.Cu")
		(net "XM_DATA12")
	)
	(segment
		(start 94.431866 -75.3618)
		(end 94.304866 -75.2348)
		(width 0.127)
		(layer "In2.Cu")
		(net "XM_DATA12")
	)
	(segment
		(start 89.986866 -75.2348)
		(end 89.859866 -75.3618)
		(width 0.127)
		(layer "In2.Cu")
		(net "XM_DATA12")
	)
	(segment
		(start 109.194346 -74.549)
		(end 98.452178 -74.549)
		(width 0.127)
		(layer "In2.Cu")
		(net "XM_DATA12")
	)
	(segment
		(start 89.224866 -75.2348)
		(end 88.970866 -75.2348)
		(width 0.127)
		(layer "In2.Cu")
		(net "XM_DATA12")
	)
	(segment
		(start 92.526866 -75.840082)
		(end 92.399866 -75.713082)
		(width 0.127)
		(layer "In2.Cu")
		(net "XM_DATA12")
	)
	(segment
		(start 91.764866 -75.840082)
		(end 91.510866 -75.840082)
		(width 0.127)
		(layer "In2.Cu")
		(net "XM_DATA12")
	)
	(segment
		(start 92.272866 -75.2348)
		(end 92.018866 -75.2348)
		(width 0.127)
		(layer "In2.Cu")
		(net "XM_DATA12")
	)
	(segment
		(start 92.018866 -75.2348)
		(end 91.891866 -75.3618)
		(width 0.127)
		(layer "In2.Cu")
		(net "XM_DATA12")
	)
	(segment
		(start 91.510866 -75.840082)
		(end 91.383866 -75.713082)
		(width 0.127)
		(layer "In2.Cu")
		(net "XM_DATA12")
	)
	(segment
		(start 91.383866 -75.713082)
		(end 91.383866 -75.3618)
		(width 0.127)
		(layer "In2.Cu")
		(net "XM_DATA12")
	)
	(segment
		(start 90.494866 -75.840082)
		(end 90.367866 -75.713082)
		(width 0.127)
		(layer "In2.Cu")
		(net "XM_DATA12")
	)
	(segment
		(start 94.050866 -75.2348)
		(end 93.923866 -75.3618)
		(width 0.127)
		(layer "In2.Cu")
		(net "XM_DATA12")
	)
	(segment
		(start 110.502192 -75.831446)
		(end 110.196884 -75.526138)
		(width 0.127)
		(layer "In2.Cu")
		(net "XM_DATA12")
	)
	(segment
		(start 92.399866 -75.713082)
		(end 92.399866 -75.3618)
		(width 0.127)
		(layer "In2.Cu")
		(net "XM_DATA12")
	)
	(segment
		(start 89.351866 -75.3618)
		(end 89.224866 -75.2348)
		(width 0.127)
		(layer "In2.Cu")
		(net "XM_DATA12")
	)
	(segment
		(start 110.196884 -75.526138)
		(end 109.866938 -75.526138)
		(width 0.127)
		(layer "In2.Cu")
		(net "XM_DATA12")
	)
	(segment
		(start 110.502192 -76.161392)
		(end 110.502192 -75.831446)
		(width 0.127)
		(layer "In2.Cu")
		(net "XM_DATA12")
	)
	(segment
		(start 90.875866 -75.713082)
		(end 90.748866 -75.840082)
		(width 0.127)
		(layer "In2.Cu")
		(net "XM_DATA12")
	)
	(segment
		(start 90.875866 -75.3618)
		(end 90.875866 -75.713082)
		(width 0.127)
		(layer "In2.Cu")
		(net "XM_DATA12")
	)
	(segment
		(start 94.431866 -75.713082)
		(end 94.431866 -75.3618)
		(width 0.127)
		(layer "In2.Cu")
		(net "XM_DATA12")
	)
	(segment
		(start 88.970866 -75.2348)
		(end 88.843866 -75.3618)
		(width 0.127)
		(layer "In2.Cu")
		(net "XM_DATA12")
	)
	(segment
		(start 86.00694 -75.840082)
		(end 82.776822 -79.0702)
		(width 0.127)
		(layer "In2.Cu")
		(net "XM_DATA12")
	)
	(segment
		(start 112.499902 -75.50023)
		(end 112.00003 -76.000102)
		(width 0.127)
		(layer "F.Cu")
		(net "XM_DATA11")
	)
	(via
		(at 79.817214 -78.348586)
		(size 0.508)
		(drill 0.254)
		(layers "F.Cu" "B.Cu")
		(net "XM_DATA11")
	)
	(via
		(at 112.00003 -76.000102)
		(size 0.4572)
		(drill 0.2032)
		(layers "F.Cu" "B.Cu")
		(net "XM_DATA11")
	)
	(segment
		(start 79.817214 -77.528674)
		(end 80.76819 -76.577698)
		(width 0.127)
		(layer "B.Cu")
		(net "XM_DATA11")
	)
	(segment
		(start 80.76819 -76.577698)
		(end 80.76819 -75.6031)
		(width 0.127)
		(layer "B.Cu")
		(net "XM_DATA11")
	)
	(segment
		(start 79.817214 -78.348586)
		(end 79.817214 -77.528674)
		(width 0.127)
		(layer "B.Cu")
		(net "XM_DATA11")
	)
	(segment
		(start 82.002884 -76.772516)
		(end 82.002884 -76.952348)
		(width 0.127)
		(layer "In2.Cu")
		(net "XM_DATA11")
	)
	(segment
		(start 112.4458 -74.7522)
		(end 112.140746 -74.447146)
		(width 0.127)
		(layer "In2.Cu")
		(net "XM_DATA11")
	)
	(segment
		(start 82.229452 -77.178916)
		(end 82.229452 -77.358748)
		(width 0.127)
		(layer "In2.Cu")
		(net "XM_DATA11")
	)
	(segment
		(start 111.444532 -73.827132)
		(end 111.125762 -73.508362)
		(width 0.127)
		(layer "In2.Cu")
		(net "XM_DATA11")
	)
	(segment
		(start 85.810852 -72.964548)
		(end 84.159344 -74.616056)
		(width 0.127)
		(layer "In2.Cu")
		(net "XM_DATA11")
	)
	(segment
		(start 83.667092 -75.921108)
		(end 83.487514 -76.100686)
		(width 0.127)
		(layer "In2.Cu")
		(net "XM_DATA11")
	)
	(segment
		(start 109.720126 -72.432672)
		(end 108.839254 -71.5518)
		(width 0.127)
		(layer "In2.Cu")
		(net "XM_DATA11")
	)
	(segment
		(start 82.362294 -76.592938)
		(end 82.182462 -76.592938)
		(width 0.127)
		(layer "In2.Cu")
		(net "XM_DATA11")
	)
	(segment
		(start 112.140746 -74.447146)
		(end 111.7854 -74.447146)
		(width 0.127)
		(layer "In2.Cu")
		(net "XM_DATA11")
	)
	(segment
		(start 84.159344 -74.795888)
		(end 84.385912 -75.022456)
		(width 0.127)
		(layer "In2.Cu")
		(net "XM_DATA11")
	)
	(segment
		(start 82.721704 -76.053696)
		(end 82.721704 -76.233528)
		(width 0.127)
		(layer "In2.Cu")
		(net "XM_DATA11")
	)
	(segment
		(start 82.588862 -76.819506)
		(end 82.362294 -76.592938)
		(width 0.127)
		(layer "In2.Cu")
		(net "XM_DATA11")
	)
	(segment
		(start 84.206334 -75.381866)
		(end 84.026502 -75.381866)
		(width 0.127)
		(layer "In2.Cu")
		(net "XM_DATA11")
	)
	(segment
		(start 98.278188 -71.952612)
		(end 90.581988 -71.952612)
		(width 0.127)
		(layer "In2.Cu")
		(net "XM_DATA11")
	)
	(segment
		(start 82.948272 -76.639928)
		(end 82.768694 -76.819506)
		(width 0.127)
		(layer "In2.Cu")
		(net "XM_DATA11")
	)
	(segment
		(start 82.229452 -77.358748)
		(end 82.049874 -77.538326)
		(width 0.127)
		(layer "In2.Cu")
		(net "XM_DATA11")
	)
	(segment
		(start 84.385912 -75.202288)
		(end 84.206334 -75.381866)
		(width 0.127)
		(layer "In2.Cu")
		(net "XM_DATA11")
	)
	(segment
		(start 112.00003 -76.000102)
		(end 112.00003 -75.941428)
		(width 0.127)
		(layer "In2.Cu")
		(net "XM_DATA11")
	)
	(segment
		(start 83.081114 -75.874118)
		(end 82.901282 -75.874118)
		(width 0.127)
		(layer "In2.Cu")
		(net "XM_DATA11")
	)
	(segment
		(start 84.159344 -74.616056)
		(end 84.159344 -74.795888)
		(width 0.127)
		(layer "In2.Cu")
		(net "XM_DATA11")
	)
	(segment
		(start 108.839254 -71.5518)
		(end 98.679 -71.5518)
		(width 0.127)
		(layer "In2.Cu")
		(net "XM_DATA11")
	)
	(segment
		(start 90.581988 -71.952612)
		(end 89.570052 -72.964548)
		(width 0.127)
		(layer "In2.Cu")
		(net "XM_DATA11")
	)
	(segment
		(start 83.667092 -75.741276)
		(end 83.667092 -75.921108)
		(width 0.127)
		(layer "In2.Cu")
		(net "XM_DATA11")
	)
	(segment
		(start 82.721704 -76.233528)
		(end 82.948272 -76.460096)
		(width 0.127)
		(layer "In2.Cu")
		(net "XM_DATA11")
	)
	(segment
		(start 82.901282 -75.874118)
		(end 82.721704 -76.053696)
		(width 0.127)
		(layer "In2.Cu")
		(net "XM_DATA11")
	)
	(segment
		(start 110.489492 -72.821292)
		(end 110.100872 -72.432672)
		(width 0.127)
		(layer "In2.Cu")
		(net "XM_DATA11")
	)
	(segment
		(start 110.100872 -72.432672)
		(end 109.720126 -72.432672)
		(width 0.127)
		(layer "In2.Cu")
		(net "XM_DATA11")
	)
	(segment
		(start 84.026502 -75.381866)
		(end 83.799934 -75.155298)
		(width 0.127)
		(layer "In2.Cu")
		(net "XM_DATA11")
	)
	(segment
		(start 83.307682 -76.100686)
		(end 83.081114 -75.874118)
		(width 0.127)
		(layer "In2.Cu")
		(net "XM_DATA11")
	)
	(segment
		(start 83.620102 -75.155298)
		(end 83.440524 -75.334876)
		(width 0.127)
		(layer "In2.Cu")
		(net "XM_DATA11")
	)
	(segment
		(start 82.049874 -77.538326)
		(end 81.870042 -77.538326)
		(width 0.127)
		(layer "In2.Cu")
		(net "XM_DATA11")
	)
	(segment
		(start 84.385912 -75.022456)
		(end 84.385912 -75.202288)
		(width 0.127)
		(layer "In2.Cu")
		(net "XM_DATA11")
	)
	(segment
		(start 81.643474 -77.311758)
		(end 81.463642 -77.311758)
		(width 0.127)
		(layer "In2.Cu")
		(net "XM_DATA11")
	)
	(segment
		(start 112.00003 -75.941428)
		(end 112.4458 -75.495658)
		(width 0.127)
		(layer "In2.Cu")
		(net "XM_DATA11")
	)
	(segment
		(start 83.487514 -76.100686)
		(end 83.307682 -76.100686)
		(width 0.127)
		(layer "In2.Cu")
		(net "XM_DATA11")
	)
	(segment
		(start 89.570052 -72.964548)
		(end 85.810852 -72.964548)
		(width 0.127)
		(layer "In2.Cu")
		(net "XM_DATA11")
	)
	(segment
		(start 112.4458 -75.495658)
		(end 112.4458 -74.7522)
		(width 0.127)
		(layer "In2.Cu")
		(net "XM_DATA11")
	)
	(segment
		(start 111.125762 -73.508362)
		(end 110.853728 -73.508362)
		(width 0.127)
		(layer "In2.Cu")
		(net "XM_DATA11")
	)
	(segment
		(start 81.463642 -77.311758)
		(end 80.426814 -78.348586)
		(width 0.127)
		(layer "In2.Cu")
		(net "XM_DATA11")
	)
	(segment
		(start 98.679 -71.5518)
		(end 98.278188 -71.952612)
		(width 0.127)
		(layer "In2.Cu")
		(net "XM_DATA11")
	)
	(segment
		(start 82.002884 -76.952348)
		(end 82.229452 -77.178916)
		(width 0.127)
		(layer "In2.Cu")
		(net "XM_DATA11")
	)
	(segment
		(start 82.182462 -76.592938)
		(end 82.002884 -76.772516)
		(width 0.127)
		(layer "In2.Cu")
		(net "XM_DATA11")
	)
	(segment
		(start 80.426814 -78.348586)
		(end 79.817214 -78.348586)
		(width 0.127)
		(layer "In2.Cu")
		(net "XM_DATA11")
	)
	(segment
		(start 83.799934 -75.155298)
		(end 83.620102 -75.155298)
		(width 0.127)
		(layer "In2.Cu")
		(net "XM_DATA11")
	)
	(segment
		(start 82.768694 -76.819506)
		(end 82.588862 -76.819506)
		(width 0.127)
		(layer "In2.Cu")
		(net "XM_DATA11")
	)
	(segment
		(start 111.444532 -74.106278)
		(end 111.444532 -73.827132)
		(width 0.127)
		(layer "In2.Cu")
		(net "XM_DATA11")
	)
	(segment
		(start 83.440524 -75.334876)
		(end 83.440524 -75.514708)
		(width 0.127)
		(layer "In2.Cu")
		(net "XM_DATA11")
	)
	(segment
		(start 110.853728 -73.508362)
		(end 110.489492 -73.144126)
		(width 0.127)
		(layer "In2.Cu")
		(net "XM_DATA11")
	)
	(segment
		(start 82.948272 -76.460096)
		(end 82.948272 -76.639928)
		(width 0.127)
		(layer "In2.Cu")
		(net "XM_DATA11")
	)
	(segment
		(start 110.489492 -73.144126)
		(end 110.489492 -72.821292)
		(width 0.127)
		(layer "In2.Cu")
		(net "XM_DATA11")
	)
	(segment
		(start 111.7854 -74.447146)
		(end 111.444532 -74.106278)
		(width 0.127)
		(layer "In2.Cu")
		(net "XM_DATA11")
	)
	(segment
		(start 81.870042 -77.538326)
		(end 81.643474 -77.311758)
		(width 0.127)
		(layer "In2.Cu")
		(net "XM_DATA11")
	)
	(segment
		(start 83.440524 -75.514708)
		(end 83.667092 -75.741276)
		(width 0.127)
		(layer "In2.Cu")
		(net "XM_DATA11")
	)
	(segment
		(start 113.4999 -81.90738)
		(end 113.4999 -81.500218)
		(width 0.127)
		(layer "F.Cu")
		(net "XM_DATA10")
	)
	(segment
		(start 113.9698 -82.7024)
		(end 113.9698 -82.37728)
		(width 0.127)
		(layer "F.Cu")
		(net "XM_DATA10")
	)
	(segment
		(start 113.5126 -83.1596)
		(end 113.9698 -82.7024)
		(width 0.127)
		(layer "F.Cu")
		(net "XM_DATA10")
	)
	(segment
		(start 113.3348 -83.1596)
		(end 113.5126 -83.1596)
		(width 0.127)
		(layer "F.Cu")
		(net "XM_DATA10")
	)
	(segment
		(start 113.9698 -82.37728)
		(end 113.4999 -81.90738)
		(width 0.127)
		(layer "F.Cu")
		(net "XM_DATA10")
	)
	(via
		(at 82.677 -82.6516)
		(size 0.508)
		(drill 0.254)
		(layers "F.Cu" "B.Cu")
		(net "XM_DATA10")
	)
	(via
		(at 113.3348 -83.1596)
		(size 0.4572)
		(drill 0.2032)
		(layers "F.Cu" "B.Cu")
		(net "XM_DATA10")
	)
	(segment
		(start 81.290414 -81.847182)
		(end 81.290414 -82.027014)
		(width 0.127)
		(layer "B.Cu")
		(net "XM_DATA10")
	)
	(segment
		(start 81.28 -81.2546)
		(end 81.491582 -81.466182)
		(width 0.127)
		(layer "B.Cu")
		(net "XM_DATA10")
	)
	(segment
		(start 81.28 -77.172312)
		(end 81.28 -81.2546)
		(width 0.127)
		(layer "B.Cu")
		(net "XM_DATA10")
	)
	(segment
		(start 81.649824 -82.206592)
		(end 81.850992 -82.005424)
		(width 0.127)
		(layer "B.Cu")
		(net "XM_DATA10")
	)
	(segment
		(start 81.76768 -75.6031)
		(end 81.76768 -76.684632)
		(width 0.127)
		(layer "B.Cu")
		(net "XM_DATA10")
	)
	(segment
		(start 82.030824 -82.005424)
		(end 82.677 -82.6516)
		(width 0.127)
		(layer "B.Cu")
		(net "XM_DATA10")
	)
	(segment
		(start 81.290414 -82.027014)
		(end 81.469992 -82.206592)
		(width 0.127)
		(layer "B.Cu")
		(net "XM_DATA10")
	)
	(segment
		(start 81.491582 -81.646014)
		(end 81.290414 -81.847182)
		(width 0.127)
		(layer "B.Cu")
		(net "XM_DATA10")
	)
	(segment
		(start 81.76768 -76.684632)
		(end 81.28 -77.172312)
		(width 0.127)
		(layer "B.Cu")
		(net "XM_DATA10")
	)
	(segment
		(start 81.850992 -82.005424)
		(end 82.030824 -82.005424)
		(width 0.127)
		(layer "B.Cu")
		(net "XM_DATA10")
	)
	(segment
		(start 81.491582 -81.466182)
		(end 81.491582 -81.646014)
		(width 0.127)
		(layer "B.Cu")
		(net "XM_DATA10")
	)
	(segment
		(start 81.469992 -82.206592)
		(end 81.649824 -82.206592)
		(width 0.127)
		(layer "B.Cu")
		(net "XM_DATA10")
	)
	(segment
		(start 97.414588 -80.7974)
		(end 97.668588 -80.7974)
		(width 0.127)
		(layer "In2.Cu")
		(net "XM_DATA10")
	)
	(segment
		(start 96.271588 -80.9244)
		(end 96.398588 -80.7974)
		(width 0.127)
		(layer "In2.Cu")
		(net "XM_DATA10")
	)
	(segment
		(start 108.842556 -81.9404)
		(end 111.332264 -81.9404)
		(width 0.127)
		(layer "In2.Cu")
		(net "XM_DATA10")
	)
	(segment
		(start 112.847882 -82.4484)
		(end 113.3348 -82.935318)
		(width 0.127)
		(layer "In2.Cu")
		(net "XM_DATA10")
	)
	(segment
		(start 94.874588 -81.3054)
		(end 95.128588 -81.3054)
		(width 0.127)
		(layer "In2.Cu")
		(net "XM_DATA10")
	)
	(segment
		(start 95.255588 -80.9244)
		(end 95.382588 -80.7974)
		(width 0.127)
		(layer "In2.Cu")
		(net "XM_DATA10")
	)
	(segment
		(start 98.186494 -81.569306)
		(end 108.471462 -81.569306)
		(width 0.127)
		(layer "In2.Cu")
		(net "XM_DATA10")
	)
	(segment
		(start 95.890588 -81.3054)
		(end 96.144588 -81.3054)
		(width 0.127)
		(layer "In2.Cu")
		(net "XM_DATA10")
	)
	(segment
		(start 96.144588 -81.3054)
		(end 96.271588 -81.1784)
		(width 0.127)
		(layer "In2.Cu")
		(net "XM_DATA10")
	)
	(segment
		(start 95.763588 -81.1784)
		(end 95.890588 -81.3054)
		(width 0.127)
		(layer "In2.Cu")
		(net "XM_DATA10")
	)
	(segment
		(start 94.620588 -80.764888)
		(end 94.747588 -80.891888)
		(width 0.127)
		(layer "In2.Cu")
		(net "XM_DATA10")
	)
	(segment
		(start 111.840264 -82.4484)
		(end 112.847882 -82.4484)
		(width 0.127)
		(layer "In2.Cu")
		(net "XM_DATA10")
	)
	(segment
		(start 96.652588 -80.7974)
		(end 96.779588 -80.9244)
		(width 0.127)
		(layer "In2.Cu")
		(net "XM_DATA10")
	)
	(segment
		(start 97.668588 -80.7974)
		(end 97.795588 -80.9244)
		(width 0.127)
		(layer "In2.Cu")
		(net "XM_DATA10")
	)
	(segment
		(start 113.3348 -82.935318)
		(end 113.3348 -83.1596)
		(width 0.127)
		(layer "In2.Cu")
		(net "XM_DATA10")
	)
	(segment
		(start 95.255588 -81.1784)
		(end 95.255588 -80.9244)
		(width 0.127)
		(layer "In2.Cu")
		(net "XM_DATA10")
	)
	(segment
		(start 96.398588 -80.7974)
		(end 96.652588 -80.7974)
		(width 0.127)
		(layer "In2.Cu")
		(net "XM_DATA10")
	)
	(segment
		(start 97.287588 -80.9244)
		(end 97.414588 -80.7974)
		(width 0.127)
		(layer "In2.Cu")
		(net "XM_DATA10")
	)
	(segment
		(start 97.160588 -81.3054)
		(end 97.287588 -81.1784)
		(width 0.127)
		(layer "In2.Cu")
		(net "XM_DATA10")
	)
	(segment
		(start 108.471462 -81.569306)
		(end 108.842556 -81.9404)
		(width 0.127)
		(layer "In2.Cu")
		(net "XM_DATA10")
	)
	(segment
		(start 85.6234 -82.6516)
		(end 87.510112 -80.764888)
		(width 0.127)
		(layer "In2.Cu")
		(net "XM_DATA10")
	)
	(segment
		(start 96.271588 -81.1784)
		(end 96.271588 -80.9244)
		(width 0.127)
		(layer "In2.Cu")
		(net "XM_DATA10")
	)
	(segment
		(start 95.382588 -80.7974)
		(end 95.636588 -80.7974)
		(width 0.127)
		(layer "In2.Cu")
		(net "XM_DATA10")
	)
	(segment
		(start 95.763588 -80.9244)
		(end 95.763588 -81.1784)
		(width 0.127)
		(layer "In2.Cu")
		(net "XM_DATA10")
	)
	(segment
		(start 94.747588 -81.1784)
		(end 94.874588 -81.3054)
		(width 0.127)
		(layer "In2.Cu")
		(net "XM_DATA10")
	)
	(segment
		(start 96.779588 -80.9244)
		(end 96.779588 -81.1784)
		(width 0.127)
		(layer "In2.Cu")
		(net "XM_DATA10")
	)
	(segment
		(start 96.779588 -81.1784)
		(end 96.906588 -81.3054)
		(width 0.127)
		(layer "In2.Cu")
		(net "XM_DATA10")
	)
	(segment
		(start 94.747588 -80.891888)
		(end 94.747588 -81.1784)
		(width 0.127)
		(layer "In2.Cu")
		(net "XM_DATA10")
	)
	(segment
		(start 111.332264 -81.9404)
		(end 111.840264 -82.4484)
		(width 0.127)
		(layer "In2.Cu")
		(net "XM_DATA10")
	)
	(segment
		(start 97.287588 -81.1784)
		(end 97.287588 -80.9244)
		(width 0.127)
		(layer "In2.Cu")
		(net "XM_DATA10")
	)
	(segment
		(start 95.636588 -80.7974)
		(end 95.763588 -80.9244)
		(width 0.127)
		(layer "In2.Cu")
		(net "XM_DATA10")
	)
	(segment
		(start 82.677 -82.6516)
		(end 85.6234 -82.6516)
		(width 0.127)
		(layer "In2.Cu")
		(net "XM_DATA10")
	)
	(segment
		(start 95.128588 -81.3054)
		(end 95.255588 -81.1784)
		(width 0.127)
		(layer "In2.Cu")
		(net "XM_DATA10")
	)
	(segment
		(start 97.795588 -81.1784)
		(end 98.186494 -81.569306)
		(width 0.127)
		(layer "In2.Cu")
		(net "XM_DATA10")
	)
	(segment
		(start 96.906588 -81.3054)
		(end 97.160588 -81.3054)
		(width 0.127)
		(layer "In2.Cu")
		(net "XM_DATA10")
	)
	(segment
		(start 97.795588 -80.9244)
		(end 97.795588 -81.1784)
		(width 0.127)
		(layer "In2.Cu")
		(net "XM_DATA10")
	)
	(segment
		(start 87.510112 -80.764888)
		(end 94.620588 -80.764888)
		(width 0.127)
		(layer "In2.Cu")
		(net "XM_DATA10")
	)
	(segment
		(start 112.9157 -82.7913)
		(end 113.206784 -82.500216)
		(width 0.127)
		(layer "F.Cu")
		(net "XM_DATA1")
	)
	(segment
		(start 112.9157 -83.4517)
		(end 112.9157 -82.7913)
		(width 0.127)
		(layer "F.Cu")
		(net "XM_DATA1")
	)
	(segment
		(start 112.4712 -83.8962)
		(end 112.9157 -83.4517)
		(width 0.127)
		(layer "F.Cu")
		(net "XM_DATA1")
	)
	(segment
		(start 113.206784 -82.500216)
		(end 113.4999 -82.500216)
		(width 0.127)
		(layer "F.Cu")
		(net "XM_DATA1")
	)
	(via
		(at 83.3374 -84.1502)
		(size 0.508)
		(drill 0.254)
		(layers "F.Cu" "B.Cu")
		(net "XM_DATA1")
	)
	(via
		(at 112.4712 -83.8962)
		(size 0.4572)
		(drill 0.2032)
		(layers "F.Cu" "B.Cu")
		(net "XM_DATA1")
	)
	(segment
		(start 82.9564 -79.386176)
		(end 83.0834 -79.513176)
		(width 0.127)
		(layer "B.Cu")
		(net "XM_DATA1")
	)
	(segment
		(start 83.0834 -79.767176)
		(end 82.9564 -79.894176)
		(width 0.127)
		(layer "B.Cu")
		(net "XM_DATA1")
	)
	(segment
		(start 83.0834 -77.13853)
		(end 83.0834 -78.751176)
		(width 0.127)
		(layer "B.Cu")
		(net "XM_DATA1")
	)
	(segment
		(start 83.26755 -76.95438)
		(end 83.0834 -77.13853)
		(width 0.127)
		(layer "B.Cu")
		(net "XM_DATA1")
	)
	(segment
		(start 82.9564 -78.878176)
		(end 82.423 -78.878176)
		(width 0.127)
		(layer "B.Cu")
		(net "XM_DATA1")
	)
	(segment
		(start 82.423 -80.402176)
		(end 82.9564 -80.402176)
		(width 0.127)
		(layer "B.Cu")
		(net "XM_DATA1")
	)
	(segment
		(start 82.296 -80.021176)
		(end 82.296 -80.275176)
		(width 0.127)
		(layer "B.Cu")
		(net "XM_DATA1")
	)
	(segment
		(start 82.423 -79.386176)
		(end 82.9564 -79.386176)
		(width 0.127)
		(layer "B.Cu")
		(net "XM_DATA1")
	)
	(segment
		(start 82.296 -79.259176)
		(end 82.423 -79.386176)
		(width 0.127)
		(layer "B.Cu")
		(net "XM_DATA1")
	)
	(segment
		(start 82.423 -79.894176)
		(end 82.296 -80.021176)
		(width 0.127)
		(layer "B.Cu")
		(net "XM_DATA1")
	)
	(segment
		(start 83.0834 -78.751176)
		(end 82.9564 -78.878176)
		(width 0.127)
		(layer "B.Cu")
		(net "XM_DATA1")
	)
	(segment
		(start 83.0834 -79.513176)
		(end 83.0834 -79.767176)
		(width 0.127)
		(layer "B.Cu")
		(net "XM_DATA1")
	)
	(segment
		(start 82.9564 -80.402176)
		(end 83.0834 -80.529176)
		(width 0.127)
		(layer "B.Cu")
		(net "XM_DATA1")
	)
	(segment
		(start 82.9564 -79.894176)
		(end 82.423 -79.894176)
		(width 0.127)
		(layer "B.Cu")
		(net "XM_DATA1")
	)
	(segment
		(start 83.3374 -81.2292)
		(end 83.3374 -84.1502)
		(width 0.127)
		(layer "B.Cu")
		(net "XM_DATA1")
	)
	(segment
		(start 83.26755 -75.6031)
		(end 83.26755 -76.95438)
		(width 0.127)
		(layer "B.Cu")
		(net "XM_DATA1")
	)
	(segment
		(start 82.423 -78.878176)
		(end 82.296 -79.005176)
		(width 0.127)
		(layer "B.Cu")
		(net "XM_DATA1")
	)
	(segment
		(start 82.296 -80.275176)
		(end 82.423 -80.402176)
		(width 0.127)
		(layer "B.Cu")
		(net "XM_DATA1")
	)
	(segment
		(start 83.0834 -80.529176)
		(end 83.0834 -80.9752)
		(width 0.127)
		(layer "B.Cu")
		(net "XM_DATA1")
	)
	(segment
		(start 83.0834 -80.9752)
		(end 83.3374 -81.2292)
		(width 0.127)
		(layer "B.Cu")
		(net "XM_DATA1")
	)
	(segment
		(start 82.296 -79.005176)
		(end 82.296 -79.259176)
		(width 0.127)
		(layer "B.Cu")
		(net "XM_DATA1")
	)
	(segment
		(start 108.665264 -82.934302)
		(end 110.480348 -82.934302)
		(width 0.127)
		(layer "In2.Cu")
		(net "XM_DATA1")
	)
	(segment
		(start 93.220794 -82.729324)
		(end 93.220794 -82.423)
		(width 0.127)
		(layer "In2.Cu")
		(net "XM_DATA1")
	)
	(segment
		(start 92.585794 -82.296)
		(end 92.712794 -82.423)
		(width 0.127)
		(layer "In2.Cu")
		(net "XM_DATA1")
	)
	(segment
		(start 92.204794 -82.423)
		(end 92.331794 -82.296)
		(width 0.127)
		(layer "In2.Cu")
		(net "XM_DATA1")
	)
	(segment
		(start 110.480348 -82.934302)
		(end 111.442246 -83.8962)
		(width 0.127)
		(layer "In2.Cu")
		(net "XM_DATA1")
	)
	(segment
		(start 93.855794 -82.856324)
		(end 97.674684 -82.856324)
		(width 0.127)
		(layer "In2.Cu")
		(net "XM_DATA1")
	)
	(segment
		(start 93.601794 -82.296)
		(end 93.728794 -82.423)
		(width 0.127)
		(layer "In2.Cu")
		(net "XM_DATA1")
	)
	(segment
		(start 92.204794 -82.729324)
		(end 92.204794 -82.423)
		(width 0.127)
		(layer "In2.Cu")
		(net "XM_DATA1")
	)
	(segment
		(start 86.311994 -84.196428)
		(end 87.652098 -82.856324)
		(width 0.127)
		(layer "In2.Cu")
		(net "XM_DATA1")
	)
	(segment
		(start 93.093794 -82.856324)
		(end 93.220794 -82.729324)
		(width 0.127)
		(layer "In2.Cu")
		(net "XM_DATA1")
	)
	(segment
		(start 111.442246 -83.8962)
		(end 112.4712 -83.8962)
		(width 0.127)
		(layer "In2.Cu")
		(net "XM_DATA1")
	)
	(segment
		(start 92.077794 -82.856324)
		(end 92.204794 -82.729324)
		(width 0.127)
		(layer "In2.Cu")
		(net "XM_DATA1")
	)
	(segment
		(start 83.3374 -84.1502)
		(end 83.383628 -84.196428)
		(width 0.127)
		(layer "In2.Cu")
		(net "XM_DATA1")
	)
	(segment
		(start 92.839794 -82.856324)
		(end 93.093794 -82.856324)
		(width 0.127)
		(layer "In2.Cu")
		(net "XM_DATA1")
	)
	(segment
		(start 93.220794 -82.423)
		(end 93.347794 -82.296)
		(width 0.127)
		(layer "In2.Cu")
		(net "XM_DATA1")
	)
	(segment
		(start 83.383628 -84.196428)
		(end 86.311994 -84.196428)
		(width 0.127)
		(layer "In2.Cu")
		(net "XM_DATA1")
	)
	(segment
		(start 98.531172 -83.712812)
		(end 107.886754 -83.712812)
		(width 0.127)
		(layer "In2.Cu")
		(net "XM_DATA1")
	)
	(segment
		(start 107.886754 -83.712812)
		(end 108.665264 -82.934302)
		(width 0.127)
		(layer "In2.Cu")
		(net "XM_DATA1")
	)
	(segment
		(start 97.674684 -82.856324)
		(end 98.531172 -83.712812)
		(width 0.127)
		(layer "In2.Cu")
		(net "XM_DATA1")
	)
	(segment
		(start 92.712794 -82.729324)
		(end 92.839794 -82.856324)
		(width 0.127)
		(layer "In2.Cu")
		(net "XM_DATA1")
	)
	(segment
		(start 93.728794 -82.423)
		(end 93.728794 -82.729324)
		(width 0.127)
		(layer "In2.Cu")
		(net "XM_DATA1")
	)
	(segment
		(start 92.712794 -82.423)
		(end 92.712794 -82.729324)
		(width 0.127)
		(layer "In2.Cu")
		(net "XM_DATA1")
	)
	(segment
		(start 92.331794 -82.296)
		(end 92.585794 -82.296)
		(width 0.127)
		(layer "In2.Cu")
		(net "XM_DATA1")
	)
	(segment
		(start 87.652098 -82.856324)
		(end 92.077794 -82.856324)
		(width 0.127)
		(layer "In2.Cu")
		(net "XM_DATA1")
	)
	(segment
		(start 93.728794 -82.729324)
		(end 93.855794 -82.856324)
		(width 0.127)
		(layer "In2.Cu")
		(net "XM_DATA1")
	)
	(segment
		(start 93.347794 -82.296)
		(end 93.601794 -82.296)
		(width 0.127)
		(layer "In2.Cu")
		(net "XM_DATA1")
	)
	(segment
		(start 112.499902 -74.500232)
		(end 112.00003 -75.000104)
		(width 0.127)
		(layer "F.Cu")
		(net "XM_DATA0")
	)
	(via
		(at 84.080604 -77.051916)
		(size 0.508)
		(drill 0.254)
		(layers "F.Cu" "B.Cu")
		(net "XM_DATA0")
	)
	(via
		(at 112.00003 -75.000104)
		(size 0.4572)
		(drill 0.2032)
		(layers "F.Cu" "B.Cu")
		(net "XM_DATA0")
	)
	(segment
		(start 84.26831 -76.632308)
		(end 84.26831 -75.6031)
		(width 0.127)
		(layer "B.Cu")
		(net "XM_DATA0")
	)
	(segment
		(start 84.080604 -76.820014)
		(end 84.26831 -76.632308)
		(width 0.127)
		(layer "B.Cu")
		(net "XM_DATA0")
	)
	(segment
		(start 84.080604 -77.051916)
		(end 84.080604 -76.820014)
		(width 0.127)
		(layer "B.Cu")
		(net "XM_DATA0")
	)
	(segment
		(start 91.893644 -74.6887)
		(end 92.147644 -74.6887)
		(width 0.127)
		(layer "In2.Cu")
		(net "XM_DATA0")
	)
	(segment
		(start 95.703644 -74.0156)
		(end 95.830644 -74.1426)
		(width 0.127)
		(layer "In2.Cu")
		(net "XM_DATA0")
	)
	(segment
		(start 90.623644 -74.0156)
		(end 90.750644 -74.1426)
		(width 0.127)
		(layer "In2.Cu")
		(net "XM_DATA0")
	)
	(segment
		(start 110.4646 -75.133454)
		(end 110.769146 -75.438)
		(width 0.127)
		(layer "In2.Cu")
		(net "XM_DATA0")
	)
	(segment
		(start 96.719644 -74.0156)
		(end 96.846644 -74.1426)
		(width 0.127)
		(layer "In2.Cu")
		(net "XM_DATA0")
	)
	(segment
		(start 90.750644 -74.5617)
		(end 90.877644 -74.6887)
		(width 0.127)
		(layer "In2.Cu")
		(net "XM_DATA0")
	)
	(segment
		(start 110.0582 -74.4474)
		(end 110.4646 -74.8538)
		(width 0.127)
		(layer "In2.Cu")
		(net "XM_DATA0")
	)
	(segment
		(start 93.671644 -74.0156)
		(end 93.798644 -74.1426)
		(width 0.127)
		(layer "In2.Cu")
		(net "XM_DATA0")
	)
	(segment
		(start 110.4646 -74.8538)
		(end 110.4646 -75.133454)
		(width 0.127)
		(layer "In2.Cu")
		(net "XM_DATA0")
	)
	(segment
		(start 86.833964 -74.8157)
		(end 86.833964 -75.184)
		(width 0.127)
		(layer "In2.Cu")
		(net "XM_DATA0")
	)
	(segment
		(start 90.369644 -74.0156)
		(end 90.623644 -74.0156)
		(width 0.127)
		(layer "In2.Cu")
		(net "XM_DATA0")
	)
	(segment
		(start 93.163644 -74.6887)
		(end 93.290644 -74.5617)
		(width 0.127)
		(layer "In2.Cu")
		(net "XM_DATA0")
	)
	(segment
		(start 91.258644 -74.5617)
		(end 91.258644 -74.1426)
		(width 0.127)
		(layer "In2.Cu")
		(net "XM_DATA0")
	)
	(segment
		(start 91.258644 -74.1426)
		(end 91.385644 -74.0156)
		(width 0.127)
		(layer "In2.Cu")
		(net "XM_DATA0")
	)
	(segment
		(start 89.861644 -74.6887)
		(end 90.115644 -74.6887)
		(width 0.127)
		(layer "In2.Cu")
		(net "XM_DATA0")
	)
	(segment
		(start 92.147644 -74.6887)
		(end 92.274644 -74.5617)
		(width 0.127)
		(layer "In2.Cu")
		(net "XM_DATA0")
	)
	(segment
		(start 109.501432 -73.865232)
		(end 109.501432 -74.144886)
		(width 0.127)
		(layer "In2.Cu")
		(net "XM_DATA0")
	)
	(segment
		(start 93.925644 -74.6887)
		(end 94.179644 -74.6887)
		(width 0.127)
		(layer "In2.Cu")
		(net "XM_DATA0")
	)
	(segment
		(start 93.798644 -74.1426)
		(end 93.798644 -74.5617)
		(width 0.127)
		(layer "In2.Cu")
		(net "XM_DATA0")
	)
	(segment
		(start 96.338644 -74.1426)
		(end 96.465644 -74.0156)
		(width 0.127)
		(layer "In2.Cu")
		(net "XM_DATA0")
	)
	(segment
		(start 94.814644 -74.1426)
		(end 94.814644 -74.9808)
		(width 0.127)
		(layer "In2.Cu")
		(net "XM_DATA0")
	)
	(segment
		(start 86.706964 -74.6887)
		(end 86.833964 -74.8157)
		(width 0.127)
		(layer "In2.Cu")
		(net "XM_DATA0")
	)
	(segment
		(start 86.833964 -75.184)
		(end 86.960964 -75.311)
		(width 0.127)
		(layer "In2.Cu")
		(net "XM_DATA0")
	)
	(segment
		(start 92.909644 -74.6887)
		(end 93.163644 -74.6887)
		(width 0.127)
		(layer "In2.Cu")
		(net "XM_DATA0")
	)
	(segment
		(start 87.341964 -75.184)
		(end 87.341964 -74.8157)
		(width 0.127)
		(layer "In2.Cu")
		(net "XM_DATA0")
	)
	(segment
		(start 84.080604 -77.047852)
		(end 86.439756 -74.6887)
		(width 0.127)
		(layer "In2.Cu")
		(net "XM_DATA0")
	)
	(segment
		(start 95.830644 -74.1426)
		(end 95.830644 -74.9808)
		(width 0.127)
		(layer "In2.Cu")
		(net "XM_DATA0")
	)
	(segment
		(start 94.433644 -74.0156)
		(end 94.687644 -74.0156)
		(width 0.127)
		(layer "In2.Cu")
		(net "XM_DATA0")
	)
	(segment
		(start 90.242644 -74.1426)
		(end 90.369644 -74.0156)
		(width 0.127)
		(layer "In2.Cu")
		(net "XM_DATA0")
	)
	(segment
		(start 91.766644 -74.5617)
		(end 91.893644 -74.6887)
		(width 0.127)
		(layer "In2.Cu")
		(net "XM_DATA0")
	)
	(segment
		(start 95.957644 -75.1078)
		(end 96.211644 -75.1078)
		(width 0.127)
		(layer "In2.Cu")
		(net "XM_DATA0")
	)
	(segment
		(start 90.242644 -74.5617)
		(end 90.242644 -74.1426)
		(width 0.127)
		(layer "In2.Cu")
		(net "XM_DATA0")
	)
	(segment
		(start 94.687644 -74.0156)
		(end 94.814644 -74.1426)
		(width 0.127)
		(layer "In2.Cu")
		(net "XM_DATA0")
	)
	(segment
		(start 90.115644 -74.6887)
		(end 90.242644 -74.5617)
		(width 0.127)
		(layer "In2.Cu")
		(net "XM_DATA0")
	)
	(segment
		(start 94.814644 -74.9808)
		(end 94.941644 -75.1078)
		(width 0.127)
		(layer "In2.Cu")
		(net "XM_DATA0")
	)
	(segment
		(start 89.226644 -74.5617)
		(end 89.226644 -74.1426)
		(width 0.127)
		(layer "In2.Cu")
		(net "XM_DATA0")
	)
	(segment
		(start 93.798644 -74.5617)
		(end 93.925644 -74.6887)
		(width 0.127)
		(layer "In2.Cu")
		(net "XM_DATA0")
	)
	(segment
		(start 89.734644 -74.1426)
		(end 89.734644 -74.5617)
		(width 0.127)
		(layer "In2.Cu")
		(net "XM_DATA0")
	)
	(segment
		(start 95.322644 -74.9808)
		(end 95.322644 -74.1426)
		(width 0.127)
		(layer "In2.Cu")
		(net "XM_DATA0")
	)
	(segment
		(start 91.639644 -74.0156)
		(end 91.766644 -74.1426)
		(width 0.127)
		(layer "In2.Cu")
		(net "XM_DATA0")
	)
	(segment
		(start 91.131644 -74.6887)
		(end 91.258644 -74.5617)
		(width 0.127)
		(layer "In2.Cu")
		(net "XM_DATA0")
	)
	(segment
		(start 92.782644 -74.1426)
		(end 92.782644 -74.5617)
		(width 0.127)
		(layer "In2.Cu")
		(net "XM_DATA0")
	)
	(segment
		(start 94.306644 -74.1426)
		(end 94.433644 -74.0156)
		(width 0.127)
		(layer "In2.Cu")
		(net "XM_DATA0")
	)
	(segment
		(start 95.830644 -74.9808)
		(end 95.957644 -75.1078)
		(width 0.127)
		(layer "In2.Cu")
		(net "XM_DATA0")
	)
	(segment
		(start 87.341964 -74.8157)
		(end 87.468964 -74.6887)
		(width 0.127)
		(layer "In2.Cu")
		(net "XM_DATA0")
	)
	(segment
		(start 87.214964 -75.311)
		(end 87.341964 -75.184)
		(width 0.127)
		(layer "In2.Cu")
		(net "XM_DATA0")
	)
	(segment
		(start 92.782644 -74.5617)
		(end 92.909644 -74.6887)
		(width 0.127)
		(layer "In2.Cu")
		(net "XM_DATA0")
	)
	(segment
		(start 92.274644 -74.5617)
		(end 92.274644 -74.1426)
		(width 0.127)
		(layer "In2.Cu")
		(net "XM_DATA0")
	)
	(segment
		(start 92.274644 -74.1426)
		(end 92.401644 -74.0156)
		(width 0.127)
		(layer "In2.Cu")
		(net "XM_DATA0")
	)
	(segment
		(start 90.877644 -74.6887)
		(end 91.131644 -74.6887)
		(width 0.127)
		(layer "In2.Cu")
		(net "XM_DATA0")
	)
	(segment
		(start 110.769146 -75.438)
		(end 111.562134 -75.438)
		(width 0.127)
		(layer "In2.Cu")
		(net "XM_DATA0")
	)
	(segment
		(start 109.1946 -73.5584)
		(end 109.501432 -73.865232)
		(width 0.127)
		(layer "In2.Cu")
		(net "XM_DATA0")
	)
	(segment
		(start 96.846644 -74.1426)
		(end 96.846644 -74.5617)
		(width 0.127)
		(layer "In2.Cu")
		(net "XM_DATA0")
	)
	(segment
		(start 93.290644 -74.1426)
		(end 93.417644 -74.0156)
		(width 0.127)
		(layer "In2.Cu")
		(net "XM_DATA0")
	)
	(segment
		(start 91.385644 -74.0156)
		(end 91.639644 -74.0156)
		(width 0.127)
		(layer "In2.Cu")
		(net "XM_DATA0")
	)
	(segment
		(start 109.803946 -74.4474)
		(end 110.0582 -74.4474)
		(width 0.127)
		(layer "In2.Cu")
		(net "XM_DATA0")
	)
	(segment
		(start 84.080604 -77.051916)
		(end 84.080604 -77.047852)
		(width 0.127)
		(layer "In2.Cu")
		(net "XM_DATA0")
	)
	(segment
		(start 94.179644 -74.6887)
		(end 94.306644 -74.5617)
		(width 0.127)
		(layer "In2.Cu")
		(net "XM_DATA0")
	)
	(segment
		(start 95.449644 -74.0156)
		(end 95.703644 -74.0156)
		(width 0.127)
		(layer "In2.Cu")
		(net "XM_DATA0")
	)
	(segment
		(start 92.655644 -74.0156)
		(end 92.782644 -74.1426)
		(width 0.127)
		(layer "In2.Cu")
		(net "XM_DATA0")
	)
	(segment
		(start 93.417644 -74.0156)
		(end 93.671644 -74.0156)
		(width 0.127)
		(layer "In2.Cu")
		(net "XM_DATA0")
	)
	(segment
		(start 96.211644 -75.1078)
		(end 96.338644 -74.9808)
		(width 0.127)
		(layer "In2.Cu")
		(net "XM_DATA0")
	)
	(segment
		(start 94.941644 -75.1078)
		(end 95.195644 -75.1078)
		(width 0.127)
		(layer "In2.Cu")
		(net "XM_DATA0")
	)
	(segment
		(start 94.306644 -74.5617)
		(end 94.306644 -74.1426)
		(width 0.127)
		(layer "In2.Cu")
		(net "XM_DATA0")
	)
	(segment
		(start 87.468964 -74.6887)
		(end 89.099644 -74.6887)
		(width 0.127)
		(layer "In2.Cu")
		(net "XM_DATA0")
	)
	(segment
		(start 109.501432 -74.144886)
		(end 109.803946 -74.4474)
		(width 0.127)
		(layer "In2.Cu")
		(net "XM_DATA0")
	)
	(segment
		(start 86.439756 -74.6887)
		(end 86.706964 -74.6887)
		(width 0.127)
		(layer "In2.Cu")
		(net "XM_DATA0")
	)
	(segment
		(start 89.099644 -74.6887)
		(end 89.226644 -74.5617)
		(width 0.127)
		(layer "In2.Cu")
		(net "XM_DATA0")
	)
	(segment
		(start 96.973644 -74.6887)
		(end 97.510854 -74.6887)
		(width 0.127)
		(layer "In2.Cu")
		(net "XM_DATA0")
	)
	(segment
		(start 91.766644 -74.1426)
		(end 91.766644 -74.5617)
		(width 0.127)
		(layer "In2.Cu")
		(net "XM_DATA0")
	)
	(segment
		(start 89.734644 -74.5617)
		(end 89.861644 -74.6887)
		(width 0.127)
		(layer "In2.Cu")
		(net "XM_DATA0")
	)
	(segment
		(start 96.465644 -74.0156)
		(end 96.719644 -74.0156)
		(width 0.127)
		(layer "In2.Cu")
		(net "XM_DATA0")
	)
	(segment
		(start 89.353644 -74.0156)
		(end 89.607644 -74.0156)
		(width 0.127)
		(layer "In2.Cu")
		(net "XM_DATA0")
	)
	(segment
		(start 96.846644 -74.5617)
		(end 96.973644 -74.6887)
		(width 0.127)
		(layer "In2.Cu")
		(net "XM_DATA0")
	)
	(segment
		(start 90.750644 -74.1426)
		(end 90.750644 -74.5617)
		(width 0.127)
		(layer "In2.Cu")
		(net "XM_DATA0")
	)
	(segment
		(start 89.607644 -74.0156)
		(end 89.734644 -74.1426)
		(width 0.127)
		(layer "In2.Cu")
		(net "XM_DATA0")
	)
	(segment
		(start 95.322644 -74.1426)
		(end 95.449644 -74.0156)
		(width 0.127)
		(layer "In2.Cu")
		(net "XM_DATA0")
	)
	(segment
		(start 86.960964 -75.311)
		(end 87.214964 -75.311)
		(width 0.127)
		(layer "In2.Cu")
		(net "XM_DATA0")
	)
	(segment
		(start 111.562134 -75.438)
		(end 112.00003 -75.000104)
		(width 0.127)
		(layer "In2.Cu")
		(net "XM_DATA0")
	)
	(segment
		(start 93.290644 -74.5617)
		(end 93.290644 -74.1426)
		(width 0.127)
		(layer "In2.Cu")
		(net "XM_DATA0")
	)
	(segment
		(start 95.195644 -75.1078)
		(end 95.322644 -74.9808)
		(width 0.127)
		(layer "In2.Cu")
		(net "XM_DATA0")
	)
	(segment
		(start 98.641154 -73.5584)
		(end 109.1946 -73.5584)
		(width 0.127)
		(layer "In2.Cu")
		(net "XM_DATA0")
	)
	(segment
		(start 92.401644 -74.0156)
		(end 92.655644 -74.0156)
		(width 0.127)
		(layer "In2.Cu")
		(net "XM_DATA0")
	)
	(segment
		(start 89.226644 -74.1426)
		(end 89.353644 -74.0156)
		(width 0.127)
		(layer "In2.Cu")
		(net "XM_DATA0")
	)
	(segment
		(start 97.510854 -74.6887)
		(end 98.641154 -73.5584)
		(width 0.127)
		(layer "In2.Cu")
		(net "XM_DATA0")
	)
	(segment
		(start 96.338644 -74.9808)
		(end 96.338644 -74.1426)
		(width 0.127)
		(layer "In2.Cu")
		(net "XM_DATA0")
	)
	(segment
		(start 183.399938 -49.9999)
		(end 183.799734 -50.399696)
		(width 0.127)
		(layer "F.Cu")
		(net "XM_DATA_9")
	)
	(via
		(at 199.348598 -68.027804)
		(size 0.508)
		(drill 0.254)
		(layers "F.Cu" "B.Cu")
		(net "XM_DATA_9")
	)
	(via
		(at 183.799734 -50.399696)
		(size 0.508)
		(drill 0.254)
		(layers "F.Cu" "B.Cu")
		(net "XM_DATA_9")
	)
	(segment
		(start 199.348598 -68.027804)
		(end 200.848468 -69.527674)
		(width 0.127)
		(layer "B.Cu")
		(net "XM_DATA_9")
	)
	(segment
		(start 200.848468 -69.527674)
		(end 203.22032 -69.527674)
		(width 0.127)
		(layer "B.Cu")
		(net "XM_DATA_9")
	)
	(segment
		(start 184.513982 -54.43601)
		(end 184.640982 -54.30901)
		(width 0.127)
		(layer "In2.Cu")
		(net "XM_DATA_9")
	)
	(segment
		(start 184.386982 -51.838606)
		(end 183.881522 -51.838606)
		(width 0.127)
		(layer "In2.Cu")
		(net "XM_DATA_9")
	)
	(segment
		(start 184.640982 -53.80101)
		(end 184.513982 -53.67401)
		(width 0.127)
		(layer "In2.Cu")
		(net "XM_DATA_9")
	)
	(segment
		(start 188.82106 -59.55792)
		(end 185.09615 -55.83301)
		(width 0.127)
		(layer "In2.Cu")
		(net "XM_DATA_9")
	)
	(segment
		(start 185.09615 -55.83301)
		(end 184.640982 -55.83301)
		(width 0.127)
		(layer "In2.Cu")
		(net "XM_DATA_9")
	)
	(segment
		(start 184.386982 -51.330606)
		(end 184.513982 -51.203606)
		(width 0.127)
		(layer "In2.Cu")
		(net "XM_DATA_9")
	)
	(segment
		(start 184.640982 -54.30901)
		(end 185.1152 -54.30901)
		(width 0.127)
		(layer "In2.Cu")
		(net "XM_DATA_9")
	)
	(segment
		(start 193.462656 -59.68492)
		(end 193.462656 -60.080652)
		(width 0.127)
		(layer "In2.Cu")
		(net "XM_DATA_9")
	)
	(segment
		(start 192.319656 -60.207652)
		(end 192.065656 -60.207652)
		(width 0.127)
		(layer "In2.Cu")
		(net "XM_DATA_9")
	)
	(segment
		(start 185.2422 -53.92801)
		(end 185.1152 -53.80101)
		(width 0.127)
		(layer "In2.Cu")
		(net "XM_DATA_9")
	)
	(segment
		(start 185.168032 -54.81701)
		(end 184.640982 -54.81701)
		(width 0.127)
		(layer "In2.Cu")
		(net "XM_DATA_9")
	)
	(segment
		(start 184.640982 -55.83301)
		(end 184.513982 -55.70601)
		(width 0.127)
		(layer "In2.Cu")
		(net "XM_DATA_9")
	)
	(segment
		(start 184.513982 -55.70601)
		(end 184.513982 -55.45201)
		(width 0.127)
		(layer "In2.Cu")
		(net "XM_DATA_9")
	)
	(segment
		(start 183.754522 -51.457606)
		(end 183.881522 -51.330606)
		(width 0.127)
		(layer "In2.Cu")
		(net "XM_DATA_9")
	)
	(segment
		(start 192.065656 -60.207652)
		(end 191.938656 -60.080652)
		(width 0.127)
		(layer "In2.Cu")
		(net "XM_DATA_9")
	)
	(segment
		(start 185.2422 -54.18201)
		(end 185.2422 -53.92801)
		(width 0.127)
		(layer "In2.Cu")
		(net "XM_DATA_9")
	)
	(segment
		(start 191.938656 -59.68492)
		(end 191.811656 -59.55792)
		(width 0.127)
		(layer "In2.Cu")
		(net "XM_DATA_9")
	)
	(segment
		(start 184.640982 -54.81701)
		(end 184.513982 -54.69001)
		(width 0.127)
		(layer "In2.Cu")
		(net "XM_DATA_9")
	)
	(segment
		(start 185.295032 -55.19801)
		(end 185.295032 -54.94401)
		(width 0.127)
		(layer "In2.Cu")
		(net "XM_DATA_9")
	)
	(segment
		(start 193.776346 -59.55792)
		(end 193.589656 -59.55792)
		(width 0.127)
		(layer "In2.Cu")
		(net "XM_DATA_9")
	)
	(segment
		(start 184.513982 -51.203606)
		(end 184.513982 -50.526696)
		(width 0.127)
		(layer "In2.Cu")
		(net "XM_DATA_9")
	)
	(segment
		(start 184.513982 -51.965606)
		(end 184.386982 -51.838606)
		(width 0.127)
		(layer "In2.Cu")
		(net "XM_DATA_9")
	)
	(segment
		(start 193.589656 -59.55792)
		(end 193.462656 -59.68492)
		(width 0.127)
		(layer "In2.Cu")
		(net "XM_DATA_9")
	)
	(segment
		(start 192.954656 -60.080652)
		(end 192.954656 -59.68492)
		(width 0.127)
		(layer "In2.Cu")
		(net "XM_DATA_9")
	)
	(segment
		(start 183.881522 -51.838606)
		(end 183.754522 -51.711606)
		(width 0.127)
		(layer "In2.Cu")
		(net "XM_DATA_9")
	)
	(segment
		(start 184.386982 -50.399696)
		(end 183.799734 -50.399696)
		(width 0.127)
		(layer "In2.Cu")
		(net "XM_DATA_9")
	)
	(segment
		(start 191.938656 -60.080652)
		(end 191.938656 -59.68492)
		(width 0.127)
		(layer "In2.Cu")
		(net "XM_DATA_9")
	)
	(segment
		(start 185.1152 -54.30901)
		(end 185.2422 -54.18201)
		(width 0.127)
		(layer "In2.Cu")
		(net "XM_DATA_9")
	)
	(segment
		(start 193.335656 -60.207652)
		(end 193.081656 -60.207652)
		(width 0.127)
		(layer "In2.Cu")
		(net "XM_DATA_9")
	)
	(segment
		(start 193.462656 -60.080652)
		(end 193.335656 -60.207652)
		(width 0.127)
		(layer "In2.Cu")
		(net "XM_DATA_9")
	)
	(segment
		(start 199.246998 -68.027804)
		(end 197.824598 -66.605404)
		(width 0.127)
		(layer "In2.Cu")
		(net "XM_DATA_9")
	)
	(segment
		(start 184.513982 -55.45201)
		(end 184.640982 -55.32501)
		(width 0.127)
		(layer "In2.Cu")
		(net "XM_DATA_9")
	)
	(segment
		(start 192.446656 -59.68492)
		(end 192.446656 -60.080652)
		(width 0.127)
		(layer "In2.Cu")
		(net "XM_DATA_9")
	)
	(segment
		(start 184.513982 -54.69001)
		(end 184.513982 -54.43601)
		(width 0.127)
		(layer "In2.Cu")
		(net "XM_DATA_9")
	)
	(segment
		(start 184.640982 -55.32501)
		(end 185.168032 -55.32501)
		(width 0.127)
		(layer "In2.Cu")
		(net "XM_DATA_9")
	)
	(segment
		(start 183.754522 -51.711606)
		(end 183.754522 -51.457606)
		(width 0.127)
		(layer "In2.Cu")
		(net "XM_DATA_9")
	)
	(segment
		(start 192.573656 -59.55792)
		(end 192.446656 -59.68492)
		(width 0.127)
		(layer "In2.Cu")
		(net "XM_DATA_9")
	)
	(segment
		(start 184.513982 -50.526696)
		(end 184.386982 -50.399696)
		(width 0.127)
		(layer "In2.Cu")
		(net "XM_DATA_9")
	)
	(segment
		(start 183.881522 -51.330606)
		(end 184.386982 -51.330606)
		(width 0.127)
		(layer "In2.Cu")
		(net "XM_DATA_9")
	)
	(segment
		(start 185.1152 -53.80101)
		(end 184.640982 -53.80101)
		(width 0.127)
		(layer "In2.Cu")
		(net "XM_DATA_9")
	)
	(segment
		(start 185.168032 -55.32501)
		(end 185.295032 -55.19801)
		(width 0.127)
		(layer "In2.Cu")
		(net "XM_DATA_9")
	)
	(segment
		(start 199.348598 -68.027804)
		(end 199.246998 -68.027804)
		(width 0.127)
		(layer "In2.Cu")
		(net "XM_DATA_9")
	)
	(segment
		(start 193.081656 -60.207652)
		(end 192.954656 -60.080652)
		(width 0.127)
		(layer "In2.Cu")
		(net "XM_DATA_9")
	)
	(segment
		(start 197.824598 -66.605404)
		(end 197.824598 -63.606172)
		(width 0.127)
		(layer "In2.Cu")
		(net "XM_DATA_9")
	)
	(segment
		(start 184.513982 -53.67401)
		(end 184.513982 -51.965606)
		(width 0.127)
		(layer "In2.Cu")
		(net "XM_DATA_9")
	)
	(segment
		(start 192.827656 -59.55792)
		(end 192.573656 -59.55792)
		(width 0.127)
		(layer "In2.Cu")
		(net "XM_DATA_9")
	)
	(segment
		(start 192.446656 -60.080652)
		(end 192.319656 -60.207652)
		(width 0.127)
		(layer "In2.Cu")
		(net "XM_DATA_9")
	)
	(segment
		(start 197.824598 -63.606172)
		(end 193.776346 -59.55792)
		(width 0.127)
		(layer "In2.Cu")
		(net "XM_DATA_9")
	)
	(segment
		(start 191.811656 -59.55792)
		(end 188.82106 -59.55792)
		(width 0.127)
		(layer "In2.Cu")
		(net "XM_DATA_9")
	)
	(segment
		(start 185.295032 -54.94401)
		(end 185.168032 -54.81701)
		(width 0.127)
		(layer "In2.Cu")
		(net "XM_DATA_9")
	)
	(segment
		(start 192.954656 -59.68492)
		(end 192.827656 -59.55792)
		(width 0.127)
		(layer "In2.Cu")
		(net "XM_DATA_9")
	)
	(segment
		(start 179.399946 -49.9999)
		(end 179.799742 -50.399696)
		(width 0.127)
		(layer "F.Cu")
		(net "XM_DATA_8")
	)
	(via
		(at 179.799742 -50.399696)
		(size 0.508)
		(drill 0.254)
		(layers "F.Cu" "B.Cu")
		(net "XM_DATA_8")
	)
	(via
		(at 199.348598 -69.027294)
		(size 0.508)
		(drill 0.254)
		(layers "F.Cu" "B.Cu")
		(net "XM_DATA_8")
	)
	(segment
		(start 200.848468 -70.527164)
		(end 203.22032 -70.527164)
		(width 0.127)
		(layer "B.Cu")
		(net "XM_DATA_8")
	)
	(segment
		(start 199.348598 -69.027294)
		(end 200.848468 -70.527164)
		(width 0.127)
		(layer "B.Cu")
		(net "XM_DATA_8")
	)
	(segment
		(start 181.18074 -54.794658)
		(end 181.18074 -52.328064)
		(width 0.127)
		(layer "In2.Cu")
		(net "XM_DATA_8")
	)
	(segment
		(start 196.249798 -68.166488)
		(end 196.249798 -65.271904)
		(width 0.127)
		(layer "In2.Cu")
		(net "XM_DATA_8")
	)
	(segment
		(start 192.004442 -62.76086)
		(end 191.447928 -62.76086)
		(width 0.127)
		(layer "In2.Cu")
		(net "XM_DATA_8")
	)
	(segment
		(start 198.840598 -68.519294)
		(end 196.602604 -68.519294)
		(width 0.127)
		(layer "In2.Cu")
		(net "XM_DATA_8")
	)
	(segment
		(start 181.000908 -54.97449)
		(end 181.18074 -54.794658)
		(width 0.127)
		(layer "In2.Cu")
		(net "XM_DATA_8")
	)
	(segment
		(start 196.602604 -68.519294)
		(end 196.249798 -68.166488)
		(width 0.127)
		(layer "In2.Cu")
		(net "XM_DATA_8")
	)
	(segment
		(start 181.18074 -52.328064)
		(end 179.799742 -50.947066)
		(width 0.127)
		(layer "In2.Cu")
		(net "XM_DATA_8")
	)
	(segment
		(start 191.447928 -62.76086)
		(end 190.393828 -61.70676)
		(width 0.127)
		(layer "In2.Cu")
		(net "XM_DATA_8")
	)
	(segment
		(start 183.189626 -60.503054)
		(end 183.189626 -60.153296)
		(width 0.127)
		(layer "In2.Cu")
		(net "XM_DATA_8")
	)
	(segment
		(start 183.189626 -60.153296)
		(end 181.000908 -57.964578)
		(width 0.127)
		(layer "In2.Cu")
		(net "XM_DATA_8")
	)
	(segment
		(start 199.348598 -69.027294)
		(end 198.840598 -68.519294)
		(width 0.127)
		(layer "In2.Cu")
		(net "XM_DATA_8")
	)
	(segment
		(start 181.000908 -57.964578)
		(end 181.000908 -54.97449)
		(width 0.127)
		(layer "In2.Cu")
		(net "XM_DATA_8")
	)
	(segment
		(start 196.249798 -65.271904)
		(end 194.409568 -63.431674)
		(width 0.127)
		(layer "In2.Cu")
		(net "XM_DATA_8")
	)
	(segment
		(start 190.393828 -61.70676)
		(end 184.393332 -61.70676)
		(width 0.127)
		(layer "In2.Cu")
		(net "XM_DATA_8")
	)
	(segment
		(start 192.675256 -63.431674)
		(end 192.004442 -62.76086)
		(width 0.127)
		(layer "In2.Cu")
		(net "XM_DATA_8")
	)
	(segment
		(start 184.393332 -61.70676)
		(end 183.189626 -60.503054)
		(width 0.127)
		(layer "In2.Cu")
		(net "XM_DATA_8")
	)
	(segment
		(start 179.799742 -50.947066)
		(end 179.799742 -50.399696)
		(width 0.127)
		(layer "In2.Cu")
		(net "XM_DATA_8")
	)
	(segment
		(start 194.409568 -63.431674)
		(end 192.675256 -63.431674)
		(width 0.127)
		(layer "In2.Cu")
		(net "XM_DATA_8")
	)
	(segment
		(start 181.799992 -50.000154)
		(end 181.799992 -49.9999)
		(width 0.127)
		(layer "F.Cu")
		(net "XM_DATA_7")
	)
	(segment
		(start 182.199788 -50.39995)
		(end 181.799992 -50.000154)
		(width 0.127)
		(layer "F.Cu")
		(net "XM_DATA_7")
	)
	(via
		(at 182.199788 -50.39995)
		(size 0.508)
		(drill 0.254)
		(layers "F.Cu" "B.Cu")
		(net "XM_DATA_7")
	)
	(via
		(at 196.757798 -63.976504)
		(size 0.508)
		(drill 0.254)
		(layers "F.Cu" "B.Cu")
		(net "XM_DATA_7")
	)
	(segment
		(start 197.671436 -63.849504)
		(end 197.671436 -63.743078)
		(width 0.127)
		(layer "B.Cu")
		(net "XM_DATA_7")
	)
	(segment
		(start 199.195436 -63.892684)
		(end 199.322436 -64.019684)
		(width 0.127)
		(layer "B.Cu")
		(net "XM_DATA_7")
	)
	(segment
		(start 200.665334 -64.019684)
		(end 201.158348 -63.526924)
		(width 0.127)
		(layer "B.Cu")
		(net "XM_DATA_7")
	)
	(segment
		(start 198.179436 -63.892684)
		(end 198.306436 -64.019684)
		(width 0.127)
		(layer "B.Cu")
		(net "XM_DATA_7")
	)
	(segment
		(start 200.211436 -63.892684)
		(end 200.338436 -64.019684)
		(width 0.127)
		(layer "B.Cu")
		(net "XM_DATA_7")
	)
	(segment
		(start 196.757798 -63.976504)
		(end 197.544436 -63.976504)
		(width 0.127)
		(layer "B.Cu")
		(net "XM_DATA_7")
	)
	(segment
		(start 197.544436 -63.976504)
		(end 197.671436 -63.849504)
		(width 0.127)
		(layer "B.Cu")
		(net "XM_DATA_7")
	)
	(segment
		(start 199.068436 -63.616078)
		(end 199.195436 -63.743078)
		(width 0.127)
		(layer "B.Cu")
		(net "XM_DATA_7")
	)
	(segment
		(start 199.703436 -63.892684)
		(end 199.703436 -63.743078)
		(width 0.127)
		(layer "B.Cu")
		(net "XM_DATA_7")
	)
	(segment
		(start 198.179436 -63.743078)
		(end 198.179436 -63.892684)
		(width 0.127)
		(layer "B.Cu")
		(net "XM_DATA_7")
	)
	(segment
		(start 198.306436 -64.019684)
		(end 198.560436 -64.019684)
		(width 0.127)
		(layer "B.Cu")
		(net "XM_DATA_7")
	)
	(segment
		(start 200.338436 -64.019684)
		(end 200.665334 -64.019684)
		(width 0.127)
		(layer "B.Cu")
		(net "XM_DATA_7")
	)
	(segment
		(start 199.322436 -64.019684)
		(end 199.576436 -64.019684)
		(width 0.127)
		(layer "B.Cu")
		(net "XM_DATA_7")
	)
	(segment
		(start 199.576436 -64.019684)
		(end 199.703436 -63.892684)
		(width 0.127)
		(layer "B.Cu")
		(net "XM_DATA_7")
	)
	(segment
		(start 199.195436 -63.743078)
		(end 199.195436 -63.892684)
		(width 0.127)
		(layer "B.Cu")
		(net "XM_DATA_7")
	)
	(segment
		(start 200.211436 -63.743078)
		(end 200.211436 -63.892684)
		(width 0.127)
		(layer "B.Cu")
		(net "XM_DATA_7")
	)
	(segment
		(start 200.084436 -63.616078)
		(end 200.211436 -63.743078)
		(width 0.127)
		(layer "B.Cu")
		(net "XM_DATA_7")
	)
	(segment
		(start 198.687436 -63.743078)
		(end 198.814436 -63.616078)
		(width 0.127)
		(layer "B.Cu")
		(net "XM_DATA_7")
	)
	(segment
		(start 199.830436 -63.616078)
		(end 200.084436 -63.616078)
		(width 0.127)
		(layer "B.Cu")
		(net "XM_DATA_7")
	)
	(segment
		(start 197.798436 -63.616078)
		(end 198.052436 -63.616078)
		(width 0.127)
		(layer "B.Cu")
		(net "XM_DATA_7")
	)
	(segment
		(start 198.560436 -64.019684)
		(end 198.687436 -63.892684)
		(width 0.127)
		(layer "B.Cu")
		(net "XM_DATA_7")
	)
	(segment
		(start 198.814436 -63.616078)
		(end 199.068436 -63.616078)
		(width 0.127)
		(layer "B.Cu")
		(net "XM_DATA_7")
	)
	(segment
		(start 198.687436 -63.892684)
		(end 198.687436 -63.743078)
		(width 0.127)
		(layer "B.Cu")
		(net "XM_DATA_7")
	)
	(segment
		(start 201.158348 -63.526924)
		(end 203.22032 -63.526924)
		(width 0.127)
		(layer "B.Cu")
		(net "XM_DATA_7")
	)
	(segment
		(start 197.671436 -63.743078)
		(end 197.798436 -63.616078)
		(width 0.127)
		(layer "B.Cu")
		(net "XM_DATA_7")
	)
	(segment
		(start 199.703436 -63.743078)
		(end 199.830436 -63.616078)
		(width 0.127)
		(layer "B.Cu")
		(net "XM_DATA_7")
	)
	(segment
		(start 198.052436 -63.616078)
		(end 198.179436 -63.743078)
		(width 0.127)
		(layer "B.Cu")
		(net "XM_DATA_7")
	)
	(segment
		(start 190.855854 -60.680854)
		(end 185.882788 -60.680854)
		(width 0.127)
		(layer "In2.Cu")
		(net "XM_DATA_7")
	)
	(segment
		(start 193.62674 -61.817758)
		(end 193.49974 -61.690758)
		(width 0.127)
		(layer "In2.Cu")
		(net "XM_DATA_7")
	)
	(segment
		(start 183.232044 -58.170572)
		(end 183.052212 -58.170572)
		(width 0.127)
		(layer "In2.Cu")
		(net "XM_DATA_7")
	)
	(segment
		(start 182.03672 -51.81473)
		(end 182.199788 -51.651662)
		(width 0.127)
		(layer "In2.Cu")
		(net "XM_DATA_7")
	)
	(segment
		(start 182.637684 -56.54421)
		(end 182.637684 -55.617618)
		(width 0.127)
		(layer "In2.Cu")
		(net "XM_DATA_7")
	)
	(segment
		(start 184.15508 -57.966356)
		(end 184.15508 -57.786524)
		(width 0.127)
		(layer "In2.Cu")
		(net "XM_DATA_7")
	)
	(segment
		(start 182.764684 -53.966618)
		(end 182.637684 -53.839618)
		(width 0.127)
		(layer "In2.Cu")
		(net "XM_DATA_7")
	)
	(segment
		(start 182.637684 -54.855618)
		(end 182.637684 -54.601618)
		(width 0.127)
		(layer "In2.Cu")
		(net "XM_DATA_7")
	)
	(segment
		(start 182.764684 -54.982618)
		(end 182.637684 -54.855618)
		(width 0.127)
		(layer "In2.Cu")
		(net "XM_DATA_7")
	)
	(segment
		(start 194.00774 -62.213236)
		(end 193.75374 -62.213236)
		(width 0.127)
		(layer "In2.Cu")
		(net "XM_DATA_7")
	)
	(segment
		(start 185.882788 -60.680854)
		(end 185.137298 -59.935364)
		(width 0.127)
		(layer "In2.Cu")
		(net "XM_DATA_7")
	)
	(segment
		(start 183.285638 -57.392824)
		(end 183.285638 -57.192164)
		(width 0.127)
		(layer "In2.Cu")
		(net "XM_DATA_7")
	)
	(segment
		(start 182.03672 -52.41417)
		(end 182.03672 -51.81473)
		(width 0.127)
		(layer "In2.Cu")
		(net "XM_DATA_7")
	)
	(segment
		(start 182.637684 -55.617618)
		(end 182.764684 -55.490618)
		(width 0.127)
		(layer "In2.Cu")
		(net "XM_DATA_7")
	)
	(segment
		(start 185.137298 -59.631326)
		(end 184.26303 -58.757058)
		(width 0.127)
		(layer "In2.Cu")
		(net "XM_DATA_7")
	)
	(segment
		(start 185.137298 -59.935364)
		(end 185.137298 -59.631326)
		(width 0.127)
		(layer "In2.Cu")
		(net "XM_DATA_7")
	)
	(segment
		(start 182.764684 -55.490618)
		(end 182.987188 -55.490618)
		(width 0.127)
		(layer "In2.Cu")
		(net "XM_DATA_7")
	)
	(segment
		(start 183.591454 -58.529982)
		(end 184.15508 -57.966356)
		(width 0.127)
		(layer "In2.Cu")
		(net "XM_DATA_7")
	)
	(segment
		(start 182.872634 -57.805828)
		(end 183.285638 -57.392824)
		(width 0.127)
		(layer "In2.Cu")
		(net "XM_DATA_7")
	)
	(segment
		(start 182.987188 -53.966618)
		(end 182.764684 -53.966618)
		(width 0.127)
		(layer "In2.Cu")
		(net "XM_DATA_7")
	)
	(segment
		(start 194.472052 -61.690758)
		(end 194.26174 -61.690758)
		(width 0.127)
		(layer "In2.Cu")
		(net "XM_DATA_7")
	)
	(segment
		(start 194.13474 -62.086236)
		(end 194.00774 -62.213236)
		(width 0.127)
		(layer "In2.Cu")
		(net "XM_DATA_7")
	)
	(segment
		(start 182.637684 -53.015134)
		(end 182.03672 -52.41417)
		(width 0.127)
		(layer "In2.Cu")
		(net "XM_DATA_7")
	)
	(segment
		(start 182.764684 -54.474618)
		(end 182.987188 -54.474618)
		(width 0.127)
		(layer "In2.Cu")
		(net "XM_DATA_7")
	)
	(segment
		(start 182.987188 -55.490618)
		(end 183.114188 -55.363618)
		(width 0.127)
		(layer "In2.Cu")
		(net "XM_DATA_7")
	)
	(segment
		(start 183.771032 -58.889392)
		(end 183.591454 -58.709814)
		(width 0.127)
		(layer "In2.Cu")
		(net "XM_DATA_7")
	)
	(segment
		(start 182.872634 -57.990994)
		(end 182.872634 -57.805828)
		(width 0.127)
		(layer "In2.Cu")
		(net "XM_DATA_7")
	)
	(segment
		(start 193.62674 -62.086236)
		(end 193.62674 -61.817758)
		(width 0.127)
		(layer "In2.Cu")
		(net "XM_DATA_7")
	)
	(segment
		(start 182.637684 -54.601618)
		(end 182.764684 -54.474618)
		(width 0.127)
		(layer "In2.Cu")
		(net "XM_DATA_7")
	)
	(segment
		(start 183.285638 -57.192164)
		(end 182.637684 -56.54421)
		(width 0.127)
		(layer "In2.Cu")
		(net "XM_DATA_7")
	)
	(segment
		(start 183.950864 -58.889392)
		(end 183.771032 -58.889392)
		(width 0.127)
		(layer "In2.Cu")
		(net "XM_DATA_7")
	)
	(segment
		(start 183.114188 -55.363618)
		(end 183.114188 -55.109618)
		(width 0.127)
		(layer "In2.Cu")
		(net "XM_DATA_7")
	)
	(segment
		(start 196.757798 -63.976504)
		(end 194.472052 -61.690758)
		(width 0.127)
		(layer "In2.Cu")
		(net "XM_DATA_7")
	)
	(segment
		(start 182.199788 -51.651662)
		(end 182.199788 -50.39995)
		(width 0.127)
		(layer "In2.Cu")
		(net "XM_DATA_7")
	)
	(segment
		(start 193.49974 -61.690758)
		(end 191.865758 -61.690758)
		(width 0.127)
		(layer "In2.Cu")
		(net "XM_DATA_7")
	)
	(segment
		(start 194.26174 -61.690758)
		(end 194.13474 -61.817758)
		(width 0.127)
		(layer "In2.Cu")
		(net "XM_DATA_7")
	)
	(segment
		(start 191.865758 -61.690758)
		(end 190.855854 -60.680854)
		(width 0.127)
		(layer "In2.Cu")
		(net "XM_DATA_7")
	)
	(segment
		(start 183.975502 -57.606946)
		(end 183.79567 -57.606946)
		(width 0.127)
		(layer "In2.Cu")
		(net "XM_DATA_7")
	)
	(segment
		(start 183.591454 -58.709814)
		(end 183.591454 -58.529982)
		(width 0.127)
		(layer "In2.Cu")
		(net "XM_DATA_7")
	)
	(segment
		(start 183.052212 -58.170572)
		(end 182.872634 -57.990994)
		(width 0.127)
		(layer "In2.Cu")
		(net "XM_DATA_7")
	)
	(segment
		(start 183.114188 -55.109618)
		(end 182.987188 -54.982618)
		(width 0.127)
		(layer "In2.Cu")
		(net "XM_DATA_7")
	)
	(segment
		(start 184.26303 -58.757058)
		(end 184.083198 -58.757058)
		(width 0.127)
		(layer "In2.Cu")
		(net "XM_DATA_7")
	)
	(segment
		(start 184.15508 -57.786524)
		(end 183.975502 -57.606946)
		(width 0.127)
		(layer "In2.Cu")
		(net "XM_DATA_7")
	)
	(segment
		(start 183.114188 -54.347618)
		(end 183.114188 -54.093618)
		(width 0.127)
		(layer "In2.Cu")
		(net "XM_DATA_7")
	)
	(segment
		(start 182.987188 -54.474618)
		(end 183.114188 -54.347618)
		(width 0.127)
		(layer "In2.Cu")
		(net "XM_DATA_7")
	)
	(segment
		(start 194.13474 -61.817758)
		(end 194.13474 -62.086236)
		(width 0.127)
		(layer "In2.Cu")
		(net "XM_DATA_7")
	)
	(segment
		(start 193.75374 -62.213236)
		(end 193.62674 -62.086236)
		(width 0.127)
		(layer "In2.Cu")
		(net "XM_DATA_7")
	)
	(segment
		(start 182.637684 -53.839618)
		(end 182.637684 -53.015134)
		(width 0.127)
		(layer "In2.Cu")
		(net "XM_DATA_7")
	)
	(segment
		(start 184.083198 -58.757058)
		(end 183.950864 -58.889392)
		(width 0.127)
		(layer "In2.Cu")
		(net "XM_DATA_7")
	)
	(segment
		(start 183.114188 -54.093618)
		(end 182.987188 -53.966618)
		(width 0.127)
		(layer "In2.Cu")
		(net "XM_DATA_7")
	)
	(segment
		(start 183.79567 -57.606946)
		(end 183.232044 -58.170572)
		(width 0.127)
		(layer "In2.Cu")
		(net "XM_DATA_7")
	)
	(segment
		(start 182.987188 -54.982618)
		(end 182.764684 -54.982618)
		(width 0.127)
		(layer "In2.Cu")
		(net "XM_DATA_7")
	)
	(segment
		(start 178.599846 -49.9999)
		(end 178.999896 -50.39995)
		(width 0.127)
		(layer "F.Cu")
		(net "XM_DATA_6")
	)
	(via
		(at 178.999896 -50.39995)
		(size 0.508)
		(drill 0.254)
		(layers "F.Cu" "B.Cu")
		(net "XM_DATA_6")
	)
	(via
		(at 194.472052 -64.93129)
		(size 0.508)
		(drill 0.254)
		(layers "F.Cu" "B.Cu")
		(net "XM_DATA_6")
	)
	(segment
		(start 194.875658 -64.527684)
		(end 194.472052 -64.93129)
		(width 0.127)
		(layer "B.Cu")
		(net "XM_DATA_6")
	)
	(segment
		(start 203.22032 -64.527684)
		(end 194.875658 -64.527684)
		(width 0.127)
		(layer "B.Cu")
		(net "XM_DATA_6")
	)
	(segment
		(start 188.039502 -63.504826)
		(end 188.166502 -63.377826)
		(width 0.127)
		(layer "In2.Cu")
		(net "XM_DATA_6")
	)
	(segment
		(start 185.372502 -63.377826)
		(end 185.499502 -63.504826)
		(width 0.127)
		(layer "In2.Cu")
		(net "XM_DATA_6")
	)
	(segment
		(start 191.006476 -63.880746)
		(end 191.620394 -63.880746)
		(width 0.127)
		(layer "In2.Cu")
		(net "XM_DATA_6")
	)
	(segment
		(start 188.166502 -63.377826)
		(end 189.233048 -63.377826)
		(width 0.127)
		(layer "In2.Cu")
		(net "XM_DATA_6")
	)
	(segment
		(start 187.150502 -63.377826)
		(end 187.404502 -63.377826)
		(width 0.127)
		(layer "In2.Cu")
		(net "XM_DATA_6")
	)
	(segment
		(start 185.499502 -63.762382)
		(end 185.626502 -63.889382)
		(width 0.127)
		(layer "In2.Cu")
		(net "XM_DATA_6")
	)
	(segment
		(start 189.233048 -63.377826)
		(end 189.360048 -63.504826)
		(width 0.127)
		(layer "In2.Cu")
		(net "XM_DATA_6")
	)
	(segment
		(start 187.023502 -63.504826)
		(end 187.150502 -63.377826)
		(width 0.127)
		(layer "In2.Cu")
		(net "XM_DATA_6")
	)
	(segment
		(start 186.515502 -63.504826)
		(end 186.515502 -63.762382)
		(width 0.127)
		(layer "In2.Cu")
		(net "XM_DATA_6")
	)
	(segment
		(start 186.896502 -63.889382)
		(end 187.023502 -63.762382)
		(width 0.127)
		(layer "In2.Cu")
		(net "XM_DATA_6")
	)
	(segment
		(start 187.912502 -63.889382)
		(end 188.039502 -63.762382)
		(width 0.127)
		(layer "In2.Cu")
		(net "XM_DATA_6")
	)
	(segment
		(start 178.999896 -50.39995)
		(end 178.999896 -50.562764)
		(width 0.127)
		(layer "In2.Cu")
		(net "XM_DATA_6")
	)
	(segment
		(start 186.007502 -63.762382)
		(end 186.007502 -63.504826)
		(width 0.127)
		(layer "In2.Cu")
		(net "XM_DATA_6")
	)
	(segment
		(start 186.388502 -63.377826)
		(end 186.515502 -63.504826)
		(width 0.127)
		(layer "In2.Cu")
		(net "XM_DATA_6")
	)
	(segment
		(start 193.930524 -65.472818)
		(end 194.472052 -64.93129)
		(width 0.127)
		(layer "In2.Cu")
		(net "XM_DATA_6")
	)
	(segment
		(start 187.404502 -63.377826)
		(end 187.531502 -63.504826)
		(width 0.127)
		(layer "In2.Cu")
		(net "XM_DATA_6")
	)
	(segment
		(start 193.212466 -65.472818)
		(end 193.930524 -65.472818)
		(width 0.127)
		(layer "In2.Cu")
		(net "XM_DATA_6")
	)
	(segment
		(start 188.039502 -63.762382)
		(end 188.039502 -63.504826)
		(width 0.127)
		(layer "In2.Cu")
		(net "XM_DATA_6")
	)
	(segment
		(start 186.642502 -63.889382)
		(end 186.896502 -63.889382)
		(width 0.127)
		(layer "In2.Cu")
		(net "XM_DATA_6")
	)
	(segment
		(start 190.503556 -63.377826)
		(end 191.006476 -63.880746)
		(width 0.127)
		(layer "In2.Cu")
		(net "XM_DATA_6")
	)
	(segment
		(start 179.984908 -58.735468)
		(end 184.627266 -63.377826)
		(width 0.127)
		(layer "In2.Cu")
		(net "XM_DATA_6")
	)
	(segment
		(start 185.626502 -63.889382)
		(end 185.880502 -63.889382)
		(width 0.127)
		(layer "In2.Cu")
		(net "XM_DATA_6")
	)
	(segment
		(start 189.360048 -63.780416)
		(end 189.487048 -63.907416)
		(width 0.127)
		(layer "In2.Cu")
		(net "XM_DATA_6")
	)
	(segment
		(start 185.499502 -63.504826)
		(end 185.499502 -63.762382)
		(width 0.127)
		(layer "In2.Cu")
		(net "XM_DATA_6")
	)
	(segment
		(start 186.515502 -63.762382)
		(end 186.642502 -63.889382)
		(width 0.127)
		(layer "In2.Cu")
		(net "XM_DATA_6")
	)
	(segment
		(start 187.531502 -63.504826)
		(end 187.531502 -63.762382)
		(width 0.127)
		(layer "In2.Cu")
		(net "XM_DATA_6")
	)
	(segment
		(start 186.134502 -63.377826)
		(end 186.388502 -63.377826)
		(width 0.127)
		(layer "In2.Cu")
		(net "XM_DATA_6")
	)
	(segment
		(start 191.620394 -63.880746)
		(end 193.212466 -65.472818)
		(width 0.127)
		(layer "In2.Cu")
		(net "XM_DATA_6")
	)
	(segment
		(start 179.984908 -51.547776)
		(end 179.984908 -58.735468)
		(width 0.127)
		(layer "In2.Cu")
		(net "XM_DATA_6")
	)
	(segment
		(start 187.658502 -63.889382)
		(end 187.912502 -63.889382)
		(width 0.127)
		(layer "In2.Cu")
		(net "XM_DATA_6")
	)
	(segment
		(start 189.995048 -63.377826)
		(end 190.503556 -63.377826)
		(width 0.127)
		(layer "In2.Cu")
		(net "XM_DATA_6")
	)
	(segment
		(start 178.999896 -50.562764)
		(end 179.984908 -51.547776)
		(width 0.127)
		(layer "In2.Cu")
		(net "XM_DATA_6")
	)
	(segment
		(start 186.007502 -63.504826)
		(end 186.134502 -63.377826)
		(width 0.127)
		(layer "In2.Cu")
		(net "XM_DATA_6")
	)
	(segment
		(start 189.868048 -63.504826)
		(end 189.995048 -63.377826)
		(width 0.127)
		(layer "In2.Cu")
		(net "XM_DATA_6")
	)
	(segment
		(start 189.487048 -63.907416)
		(end 189.741048 -63.907416)
		(width 0.127)
		(layer "In2.Cu")
		(net "XM_DATA_6")
	)
	(segment
		(start 184.627266 -63.377826)
		(end 185.372502 -63.377826)
		(width 0.127)
		(layer "In2.Cu")
		(net "XM_DATA_6")
	)
	(segment
		(start 189.360048 -63.504826)
		(end 189.360048 -63.780416)
		(width 0.127)
		(layer "In2.Cu")
		(net "XM_DATA_6")
	)
	(segment
		(start 185.880502 -63.889382)
		(end 186.007502 -63.762382)
		(width 0.127)
		(layer "In2.Cu")
		(net "XM_DATA_6")
	)
	(segment
		(start 187.531502 -63.762382)
		(end 187.658502 -63.889382)
		(width 0.127)
		(layer "In2.Cu")
		(net "XM_DATA_6")
	)
	(segment
		(start 189.868048 -63.780416)
		(end 189.868048 -63.504826)
		(width 0.127)
		(layer "In2.Cu")
		(net "XM_DATA_6")
	)
	(segment
		(start 189.741048 -63.907416)
		(end 189.868048 -63.780416)
		(width 0.127)
		(layer "In2.Cu")
		(net "XM_DATA_6")
	)
	(segment
		(start 187.023502 -63.762382)
		(end 187.023502 -63.504826)
		(width 0.127)
		(layer "In2.Cu")
		(net "XM_DATA_6")
	)
	(segment
		(start 180.199792 -49.9999)
		(end 180.599842 -50.39995)
		(width 0.127)
		(layer "F.Cu")
		(net "XM_DATA_5")
	)
	(via
		(at 180.599842 -50.39995)
		(size 0.508)
		(drill 0.254)
		(layers "F.Cu" "B.Cu")
		(net "XM_DATA_5")
	)
	(via
		(at 196.762878 -65.023746)
		(size 0.508)
		(drill 0.254)
		(layers "F.Cu" "B.Cu")
		(net "XM_DATA_5")
	)
	(segment
		(start 201.318622 -65.527174)
		(end 203.22032 -65.527174)
		(width 0.127)
		(layer "B.Cu")
		(net "XM_DATA_5")
	)
	(segment
		(start 201.105008 -65.31356)
		(end 201.318622 -65.527174)
		(width 0.127)
		(layer "B.Cu")
		(net "XM_DATA_5")
	)
	(segment
		(start 196.762878 -65.023746)
		(end 197.052692 -65.31356)
		(width 0.127)
		(layer "B.Cu")
		(net "XM_DATA_5")
	)
	(segment
		(start 197.052692 -65.31356)
		(end 201.105008 -65.31356)
		(width 0.127)
		(layer "B.Cu")
		(net "XM_DATA_5")
	)
	(segment
		(start 185.151776 -60.997846)
		(end 185.342784 -61.188854)
		(width 0.127)
		(layer "In2.Cu")
		(net "XM_DATA_5")
	)
	(segment
		(start 190.645288 -61.188854)
		(end 191.655192 -62.198758)
		(width 0.127)
		(layer "In2.Cu")
		(net "XM_DATA_5")
	)
	(segment
		(start 182.103014 -54.633622)
		(end 182.103014 -54.887622)
		(width 0.127)
		(layer "In2.Cu")
		(net "XM_DATA_5")
	)
	(segment
		(start 182.12435 -55.649622)
		(end 182.12435 -56.60263)
		(width 0.127)
		(layer "In2.Cu")
		(net "XM_DATA_5")
	)
	(segment
		(start 181.737762 -54.506622)
		(end 181.976014 -54.506622)
		(width 0.127)
		(layer "In2.Cu")
		(net "XM_DATA_5")
	)
	(segment
		(start 181.536594 -57.11063)
		(end 181.663594 -57.23763)
		(width 0.127)
		(layer "In2.Cu")
		(net "XM_DATA_5")
	)
	(segment
		(start 181.663594 -56.72963)
		(end 181.536594 -56.85663)
		(width 0.127)
		(layer "In2.Cu")
		(net "XM_DATA_5")
	)
	(segment
		(start 181.610762 -54.379622)
		(end 181.737762 -54.506622)
		(width 0.127)
		(layer "In2.Cu")
		(net "XM_DATA_5")
	)
	(segment
		(start 183.893714 -59.739784)
		(end 183.893714 -59.919616)
		(width 0.127)
		(layer "In2.Cu")
		(net "XM_DATA_5")
	)
	(segment
		(start 192.983612 -62.198758)
		(end 193.68643 -62.901576)
		(width 0.127)
		(layer "In2.Cu")
		(net "XM_DATA_5")
	)
	(segment
		(start 181.563518 -52.710842)
		(end 182.177944 -53.325268)
		(width 0.127)
		(layer "In2.Cu")
		(net "XM_DATA_5")
	)
	(segment
		(start 185.342784 -61.188854)
		(end 190.645288 -61.188854)
		(width 0.127)
		(layer "In2.Cu")
		(net "XM_DATA_5")
	)
	(segment
		(start 184.253124 -60.279026)
		(end 184.432956 -60.279026)
		(width 0.127)
		(layer "In2.Cu")
		(net "XM_DATA_5")
	)
	(segment
		(start 182.177944 -58.024014)
		(end 183.893714 -59.739784)
		(width 0.127)
		(layer "In2.Cu")
		(net "XM_DATA_5")
	)
	(segment
		(start 181.976014 -54.506622)
		(end 182.103014 -54.633622)
		(width 0.127)
		(layer "In2.Cu")
		(net "XM_DATA_5")
	)
	(segment
		(start 184.784746 -61.185044)
		(end 184.971944 -60.997846)
		(width 0.127)
		(layer "In2.Cu")
		(net "XM_DATA_5")
	)
	(segment
		(start 180.599842 -50.39995)
		(end 180.599842 -51.118008)
		(width 0.127)
		(layer "In2.Cu")
		(net "XM_DATA_5")
	)
	(segment
		(start 184.425336 -60.825634)
		(end 184.425336 -61.005466)
		(width 0.127)
		(layer "In2.Cu")
		(net "XM_DATA_5")
	)
	(segment
		(start 184.971944 -60.997846)
		(end 185.151776 -60.997846)
		(width 0.127)
		(layer "In2.Cu")
		(net "XM_DATA_5")
	)
	(segment
		(start 181.610762 -55.395622)
		(end 181.737762 -55.522622)
		(width 0.127)
		(layer "In2.Cu")
		(net "XM_DATA_5")
	)
	(segment
		(start 182.050944 -53.998622)
		(end 181.737762 -53.998622)
		(width 0.127)
		(layer "In2.Cu")
		(net "XM_DATA_5")
	)
	(segment
		(start 193.68643 -62.901576)
		(end 194.640708 -62.901576)
		(width 0.127)
		(layer "In2.Cu")
		(net "XM_DATA_5")
	)
	(segment
		(start 182.12435 -56.60263)
		(end 181.99735 -56.72963)
		(width 0.127)
		(layer "In2.Cu")
		(net "XM_DATA_5")
	)
	(segment
		(start 181.99735 -56.72963)
		(end 181.663594 -56.72963)
		(width 0.127)
		(layer "In2.Cu")
		(net "XM_DATA_5")
	)
	(segment
		(start 183.893714 -59.919616)
		(end 183.706516 -60.106814)
		(width 0.127)
		(layer "In2.Cu")
		(net "XM_DATA_5")
	)
	(segment
		(start 182.103014 -54.887622)
		(end 181.976014 -55.014622)
		(width 0.127)
		(layer "In2.Cu")
		(net "XM_DATA_5")
	)
	(segment
		(start 191.655192 -62.198758)
		(end 192.983612 -62.198758)
		(width 0.127)
		(layer "In2.Cu")
		(net "XM_DATA_5")
	)
	(segment
		(start 181.737762 -55.014622)
		(end 181.610762 -55.141622)
		(width 0.127)
		(layer "In2.Cu")
		(net "XM_DATA_5")
	)
	(segment
		(start 181.99735 -55.522622)
		(end 182.12435 -55.649622)
		(width 0.127)
		(layer "In2.Cu")
		(net "XM_DATA_5")
	)
	(segment
		(start 182.050944 -57.23763)
		(end 182.177944 -57.36463)
		(width 0.127)
		(layer "In2.Cu")
		(net "XM_DATA_5")
	)
	(segment
		(start 184.604914 -61.185044)
		(end 184.784746 -61.185044)
		(width 0.127)
		(layer "In2.Cu")
		(net "XM_DATA_5")
	)
	(segment
		(start 181.737762 -55.522622)
		(end 181.99735 -55.522622)
		(width 0.127)
		(layer "In2.Cu")
		(net "XM_DATA_5")
	)
	(segment
		(start 182.177944 -53.325268)
		(end 182.177944 -53.871622)
		(width 0.127)
		(layer "In2.Cu")
		(net "XM_DATA_5")
	)
	(segment
		(start 183.886094 -60.466224)
		(end 184.065926 -60.466224)
		(width 0.127)
		(layer "In2.Cu")
		(net "XM_DATA_5")
	)
	(segment
		(start 180.599842 -51.118008)
		(end 181.563518 -52.081684)
		(width 0.127)
		(layer "In2.Cu")
		(net "XM_DATA_5")
	)
	(segment
		(start 181.976014 -55.014622)
		(end 181.737762 -55.014622)
		(width 0.127)
		(layer "In2.Cu")
		(net "XM_DATA_5")
	)
	(segment
		(start 182.177944 -57.36463)
		(end 182.177944 -58.024014)
		(width 0.127)
		(layer "In2.Cu")
		(net "XM_DATA_5")
	)
	(segment
		(start 181.563518 -52.081684)
		(end 181.563518 -52.710842)
		(width 0.127)
		(layer "In2.Cu")
		(net "XM_DATA_5")
	)
	(segment
		(start 182.177944 -53.871622)
		(end 182.050944 -53.998622)
		(width 0.127)
		(layer "In2.Cu")
		(net "XM_DATA_5")
	)
	(segment
		(start 181.610762 -54.125622)
		(end 181.610762 -54.379622)
		(width 0.127)
		(layer "In2.Cu")
		(net "XM_DATA_5")
	)
	(segment
		(start 184.612534 -60.458604)
		(end 184.612534 -60.638436)
		(width 0.127)
		(layer "In2.Cu")
		(net "XM_DATA_5")
	)
	(segment
		(start 184.425336 -61.005466)
		(end 184.604914 -61.185044)
		(width 0.127)
		(layer "In2.Cu")
		(net "XM_DATA_5")
	)
	(segment
		(start 181.610762 -55.141622)
		(end 181.610762 -55.395622)
		(width 0.127)
		(layer "In2.Cu")
		(net "XM_DATA_5")
	)
	(segment
		(start 183.706516 -60.106814)
		(end 183.706516 -60.286646)
		(width 0.127)
		(layer "In2.Cu")
		(net "XM_DATA_5")
	)
	(segment
		(start 184.612534 -60.638436)
		(end 184.425336 -60.825634)
		(width 0.127)
		(layer "In2.Cu")
		(net "XM_DATA_5")
	)
	(segment
		(start 184.432956 -60.279026)
		(end 184.612534 -60.458604)
		(width 0.127)
		(layer "In2.Cu")
		(net "XM_DATA_5")
	)
	(segment
		(start 181.737762 -53.998622)
		(end 181.610762 -54.125622)
		(width 0.127)
		(layer "In2.Cu")
		(net "XM_DATA_5")
	)
	(segment
		(start 181.536594 -56.85663)
		(end 181.536594 -57.11063)
		(width 0.127)
		(layer "In2.Cu")
		(net "XM_DATA_5")
	)
	(segment
		(start 194.640708 -62.901576)
		(end 196.762878 -65.023746)
		(width 0.127)
		(layer "In2.Cu")
		(net "XM_DATA_5")
	)
	(segment
		(start 183.706516 -60.286646)
		(end 183.886094 -60.466224)
		(width 0.127)
		(layer "In2.Cu")
		(net "XM_DATA_5")
	)
	(segment
		(start 184.065926 -60.466224)
		(end 184.253124 -60.279026)
		(width 0.127)
		(layer "In2.Cu")
		(net "XM_DATA_5")
	)
	(segment
		(start 181.663594 -57.23763)
		(end 182.050944 -57.23763)
		(width 0.127)
		(layer "In2.Cu")
		(net "XM_DATA_5")
	)
	(segment
		(start 185.799984 -43.599862)
		(end 186.19978 -43.200066)
		(width 0.127)
		(layer "F.Cu")
		(net "XM_DATA_4")
	)
	(via
		(at 201.634598 -66.978784)
		(size 0.508)
		(drill 0.254)
		(layers "F.Cu" "B.Cu")
		(net "XM_DATA_4")
	)
	(via
		(at 186.19978 -43.200066)
		(size 0.508)
		(drill 0.254)
		(layers "F.Cu" "B.Cu")
		(net "XM_DATA_4")
	)
	(segment
		(start 201.634598 -66.978784)
		(end 202.086718 -66.526664)
		(width 0.127)
		(layer "B.Cu")
		(net "XM_DATA_4")
	)
	(segment
		(start 202.086718 -66.526664)
		(end 203.22032 -66.526664)
		(width 0.127)
		(layer "B.Cu")
		(net "XM_DATA_4")
	)
	(segment
		(start 202.057 -66.556382)
		(end 201.634598 -66.978784)
		(width 0.127)
		(layer "In2.Cu")
		(net "XM_DATA_4")
	)
	(segment
		(start 186.19978 -43.200066)
		(end 186.380882 -43.200066)
		(width 0.127)
		(layer "In2.Cu")
		(net "XM_DATA_4")
	)
	(segment
		(start 190.75273 -46.589696)
		(end 190.932054 -46.589696)
		(width 0.127)
		(layer "In2.Cu")
		(net "XM_DATA_4")
	)
	(segment
		(start 202.616308 -65.54851)
		(end 202.057 -66.107818)
		(width 0.127)
		(layer "In2.Cu")
		(net "XM_DATA_4")
	)
	(segment
		(start 191.7319 -46.329092)
		(end 191.7319 -46.508416)
		(width 0.127)
		(layer "In2.Cu")
		(net "XM_DATA_4")
	)
	(segment
		(start 193.102992 -53.9369)
		(end 193.472054 -53.9369)
		(width 0.127)
		(layer "In2.Cu")
		(net "XM_DATA_4")
	)
	(segment
		(start 188.434472 -44.54271)
		(end 188.705744 -44.54271)
		(width 0.127)
		(layer "In2.Cu")
		(net "XM_DATA_4")
	)
	(segment
		(start 191.01308 -45.610272)
		(end 191.01308 -45.789596)
		(width 0.127)
		(layer "In2.Cu")
		(net "XM_DATA_4")
	)
	(segment
		(start 191.936116 -47.773082)
		(end 191.936116 -52.770024)
		(width 0.127)
		(layer "In2.Cu")
		(net "XM_DATA_4")
	)
	(segment
		(start 187.510928 -43.619166)
		(end 188.434472 -44.54271)
		(width 0.127)
		(layer "In2.Cu")
		(net "XM_DATA_4")
	)
	(segment
		(start 191.7319 -46.508416)
		(end 191.291464 -46.949106)
		(width 0.127)
		(layer "In2.Cu")
		(net "XM_DATA_4")
	)
	(segment
		(start 190.65367 -45.430186)
		(end 190.832994 -45.430186)
		(width 0.127)
		(layer "In2.Cu")
		(net "XM_DATA_4")
	)
	(segment
		(start 190.572644 -46.40961)
		(end 190.75273 -46.589696)
		(width 0.127)
		(layer "In2.Cu")
		(net "XM_DATA_4")
	)
	(segment
		(start 191.37249 -46.149006)
		(end 191.551814 -46.149006)
		(width 0.127)
		(layer "In2.Cu")
		(net "XM_DATA_4")
	)
	(segment
		(start 202.057 -66.107818)
		(end 202.057 -66.556382)
		(width 0.127)
		(layer "In2.Cu")
		(net "XM_DATA_4")
	)
	(segment
		(start 191.551814 -46.149006)
		(end 191.7319 -46.329092)
		(width 0.127)
		(layer "In2.Cu")
		(net "XM_DATA_4")
	)
	(segment
		(start 190.572644 -46.230286)
		(end 190.572644 -46.40961)
		(width 0.127)
		(layer "In2.Cu")
		(net "XM_DATA_4")
	)
	(segment
		(start 190.832994 -45.430186)
		(end 191.01308 -45.610272)
		(width 0.127)
		(layer "In2.Cu")
		(net "XM_DATA_4")
	)
	(segment
		(start 186.380882 -43.200066)
		(end 186.799982 -43.619166)
		(width 0.127)
		(layer "In2.Cu")
		(net "XM_DATA_4")
	)
	(segment
		(start 190.932054 -46.589696)
		(end 191.37249 -46.149006)
		(width 0.127)
		(layer "In2.Cu")
		(net "XM_DATA_4")
	)
	(segment
		(start 191.936116 -52.770024)
		(end 193.102992 -53.9369)
		(width 0.127)
		(layer "In2.Cu")
		(net "XM_DATA_4")
	)
	(segment
		(start 196.53758 -55.29961)
		(end 202.616308 -61.378338)
		(width 0.127)
		(layer "In2.Cu")
		(net "XM_DATA_4")
	)
	(segment
		(start 186.799982 -43.619166)
		(end 187.510928 -43.619166)
		(width 0.127)
		(layer "In2.Cu")
		(net "XM_DATA_4")
	)
	(segment
		(start 191.291464 -46.949106)
		(end 191.291464 -47.12843)
		(width 0.127)
		(layer "In2.Cu")
		(net "XM_DATA_4")
	)
	(segment
		(start 190.03391 -45.870876)
		(end 190.213234 -45.870876)
		(width 0.127)
		(layer "In2.Cu")
		(net "XM_DATA_4")
	)
	(segment
		(start 193.472054 -53.9369)
		(end 194.834764 -55.29961)
		(width 0.127)
		(layer "In2.Cu")
		(net "XM_DATA_4")
	)
	(segment
		(start 191.01308 -45.789596)
		(end 190.572644 -46.230286)
		(width 0.127)
		(layer "In2.Cu")
		(net "XM_DATA_4")
	)
	(segment
		(start 190.213234 -45.870876)
		(end 190.65367 -45.430186)
		(width 0.127)
		(layer "In2.Cu")
		(net "XM_DATA_4")
	)
	(segment
		(start 191.291464 -47.12843)
		(end 191.936116 -47.773082)
		(width 0.127)
		(layer "In2.Cu")
		(net "XM_DATA_4")
	)
	(segment
		(start 202.616308 -61.378338)
		(end 202.616308 -65.54851)
		(width 0.127)
		(layer "In2.Cu")
		(net "XM_DATA_4")
	)
	(segment
		(start 194.834764 -55.29961)
		(end 196.53758 -55.29961)
		(width 0.127)
		(layer "In2.Cu")
		(net "XM_DATA_4")
	)
	(segment
		(start 188.705744 -44.54271)
		(end 190.03391 -45.870876)
		(width 0.127)
		(layer "In2.Cu")
		(net "XM_DATA_4")
	)
	(segment
		(start 186.59983 -43.599862)
		(end 186.999626 -43.200066)
		(width 0.127)
		(layer "F.Cu")
		(net "XM_DATA_3")
	)
	(via
		(at 186.999626 -43.200066)
		(size 0.508)
		(drill 0.254)
		(layers "F.Cu" "B.Cu")
		(net "XM_DATA_3")
	)
	(via
		(at 201.634598 -68.027804)
		(size 0.508)
		(drill 0.254)
		(layers "F.Cu" "B.Cu")
		(net "XM_DATA_3")
	)
	(segment
		(start 203.22032 -68.027804)
		(end 201.634598 -68.027804)
		(width 0.127)
		(layer "B.Cu")
		(net "XM_DATA_3")
	)
	(segment
		(start 189.34303 -43.765216)
		(end 189.34303 -43.945048)
		(width 0.127)
		(layer "In2.Cu")
		(net "XM_DATA_3")
	)
	(segment
		(start 190.003684 -44.722034)
		(end 190.183262 -44.901612)
		(width 0.127)
		(layer "In2.Cu")
		(net "XM_DATA_3")
	)
	(segment
		(start 189.522608 -44.124626)
		(end 189.70244 -44.124626)
		(width 0.127)
		(layer "In2.Cu")
		(net "XM_DATA_3")
	)
	(segment
		(start 189.525148 -43.403774)
		(end 189.525148 -43.583098)
		(width 0.127)
		(layer "In2.Cu")
		(net "XM_DATA_3")
	)
	(segment
		(start 190.603378 -44.661328)
		(end 190.782702 -44.661328)
		(width 0.127)
		(layer "In2.Cu")
		(net "XM_DATA_3")
	)
	(segment
		(start 189.70244 -44.124626)
		(end 189.884558 -43.942508)
		(width 0.127)
		(layer "In2.Cu")
		(net "XM_DATA_3")
	)
	(segment
		(start 195.27774 -54.750716)
		(end 196.729604 -54.750716)
		(width 0.127)
		(layer "In2.Cu")
		(net "XM_DATA_3")
	)
	(segment
		(start 196.729604 -54.750716)
		(end 203.124308 -61.14542)
		(width 0.127)
		(layer "In2.Cu")
		(net "XM_DATA_3")
	)
	(segment
		(start 202.565 -67.097402)
		(end 201.634598 -68.027804)
		(width 0.127)
		(layer "In2.Cu")
		(net "XM_DATA_3")
	)
	(segment
		(start 203.124308 -61.14542)
		(end 203.124308 -65.759076)
		(width 0.127)
		(layer "In2.Cu")
		(net "XM_DATA_3")
	)
	(segment
		(start 190.782702 -44.661328)
		(end 192.444116 -46.322742)
		(width 0.127)
		(layer "In2.Cu")
		(net "XM_DATA_3")
	)
	(segment
		(start 186.999626 -43.200066)
		(end 189.32144 -43.200066)
		(width 0.127)
		(layer "In2.Cu")
		(net "XM_DATA_3")
	)
	(segment
		(start 190.063882 -43.942508)
		(end 190.243968 -44.122594)
		(width 0.127)
		(layer "In2.Cu")
		(net "XM_DATA_3")
	)
	(segment
		(start 189.884558 -43.942508)
		(end 190.063882 -43.942508)
		(width 0.127)
		(layer "In2.Cu")
		(net "XM_DATA_3")
	)
	(segment
		(start 189.34303 -43.945048)
		(end 189.522608 -44.124626)
		(width 0.127)
		(layer "In2.Cu")
		(net "XM_DATA_3")
	)
	(segment
		(start 190.243968 -44.301918)
		(end 190.003684 -44.542202)
		(width 0.127)
		(layer "In2.Cu")
		(net "XM_DATA_3")
	)
	(segment
		(start 192.444116 -46.322742)
		(end 192.444116 -51.917092)
		(width 0.127)
		(layer "In2.Cu")
		(net "XM_DATA_3")
	)
	(segment
		(start 192.444116 -51.917092)
		(end 195.27774 -54.750716)
		(width 0.127)
		(layer "In2.Cu")
		(net "XM_DATA_3")
	)
	(segment
		(start 202.565 -66.318384)
		(end 202.565 -67.097402)
		(width 0.127)
		(layer "In2.Cu")
		(net "XM_DATA_3")
	)
	(segment
		(start 189.32144 -43.200066)
		(end 189.525148 -43.403774)
		(width 0.127)
		(layer "In2.Cu")
		(net "XM_DATA_3")
	)
	(segment
		(start 190.183262 -44.901612)
		(end 190.363094 -44.901612)
		(width 0.127)
		(layer "In2.Cu")
		(net "XM_DATA_3")
	)
	(segment
		(start 189.525148 -43.583098)
		(end 189.34303 -43.765216)
		(width 0.127)
		(layer "In2.Cu")
		(net "XM_DATA_3")
	)
	(segment
		(start 203.124308 -65.759076)
		(end 202.565 -66.318384)
		(width 0.127)
		(layer "In2.Cu")
		(net "XM_DATA_3")
	)
	(segment
		(start 190.363094 -44.901612)
		(end 190.603378 -44.661328)
		(width 0.127)
		(layer "In2.Cu")
		(net "XM_DATA_3")
	)
	(segment
		(start 190.003684 -44.542202)
		(end 190.003684 -44.722034)
		(width 0.127)
		(layer "In2.Cu")
		(net "XM_DATA_3")
	)
	(segment
		(start 190.243968 -44.122594)
		(end 190.243968 -44.301918)
		(width 0.127)
		(layer "In2.Cu")
		(net "XM_DATA_3")
	)
	(segment
		(start 184.999884 -44.399962)
		(end 185.39968 -44.000166)
		(width 0.127)
		(layer "F.Cu")
		(net "XM_DATA_2")
	)
	(via
		(at 201.634598 -69.027294)
		(size 0.508)
		(drill 0.254)
		(layers "F.Cu" "B.Cu")
		(net "XM_DATA_2")
	)
	(via
		(at 185.39968 -44.000166)
		(size 0.508)
		(drill 0.254)
		(layers "F.Cu" "B.Cu")
		(net "XM_DATA_2")
	)
	(segment
		(start 203.22032 -69.027294)
		(end 201.634598 -69.027294)
		(width 0.127)
		(layer "B.Cu")
		(net "XM_DATA_2")
	)
	(segment
		(start 188.084206 -51.482244)
		(end 186.87288 -50.270918)
		(width 0.127)
		(layer "In2.Cu")
		(net "XM_DATA_2")
	)
	(segment
		(start 196.360034 -58.726832)
		(end 196.192902 -58.89371)
		(width 0.127)
		(layer "In2.Cu")
		(net "XM_DATA_2")
	)
	(segment
		(start 196.192902 -58.89371)
		(end 196.013578 -58.89371)
		(width 0.127)
		(layer "In2.Cu")
		(net "XM_DATA_2")
	)
	(segment
		(start 200.616566 -66.006726)
		(end 199.856598 -65.246758)
		(width 0.127)
		(layer "In2.Cu")
		(net "XM_DATA_2")
	)
	(segment
		(start 196.552312 -59.432444)
		(end 196.552312 -59.25312)
		(width 0.127)
		(layer "In2.Cu")
		(net "XM_DATA_2")
	)
	(segment
		(start 186.09818 -44.546012)
		(end 185.945526 -44.546012)
		(width 0.127)
		(layer "In2.Cu")
		(net "XM_DATA_2")
	)
	(segment
		(start 195.286122 -57.473596)
		(end 192.078102 -57.473596)
		(width 0.127)
		(layer "In2.Cu")
		(net "XM_DATA_2")
	)
	(segment
		(start 201.250804 -69.027294)
		(end 200.616566 -68.393056)
		(width 0.127)
		(layer "In2.Cu")
		(net "XM_DATA_2")
	)
	(segment
		(start 198.802498 -60.989972)
		(end 197.976998 -60.164472)
		(width 0.127)
		(layer "In2.Cu")
		(net "XM_DATA_2")
	)
	(segment
		(start 198.802498 -61.618368)
		(end 198.802498 -60.989972)
		(width 0.127)
		(layer "In2.Cu")
		(net "XM_DATA_2")
	)
	(segment
		(start 200.616566 -68.393056)
		(end 200.616566 -66.006726)
		(width 0.127)
		(layer "In2.Cu")
		(net "XM_DATA_2")
	)
	(segment
		(start 196.719444 -58.906918)
		(end 196.539358 -58.726832)
		(width 0.127)
		(layer "In2.Cu")
		(net "XM_DATA_2")
	)
	(segment
		(start 197.258178 -59.445652)
		(end 197.078854 -59.445652)
		(width 0.127)
		(layer "In2.Cu")
		(net "XM_DATA_2")
	)
	(segment
		(start 197.797674 -60.164472)
		(end 197.630542 -60.33135)
		(width 0.127)
		(layer "In2.Cu")
		(net "XM_DATA_2")
	)
	(segment
		(start 197.271132 -60.151264)
		(end 197.271132 -59.97194)
		(width 0.127)
		(layer "In2.Cu")
		(net "XM_DATA_2")
	)
	(segment
		(start 195.833492 -58.713624)
		(end 195.833492 -58.5343)
		(width 0.127)
		(layer "In2.Cu")
		(net "XM_DATA_2")
	)
	(segment
		(start 196.539358 -58.726832)
		(end 196.360034 -58.726832)
		(width 0.127)
		(layer "In2.Cu")
		(net "XM_DATA_2")
	)
	(segment
		(start 196.013578 -58.89371)
		(end 195.833492 -58.713624)
		(width 0.127)
		(layer "In2.Cu")
		(net "XM_DATA_2")
	)
	(segment
		(start 192.078102 -57.473596)
		(end 188.084206 -53.4797)
		(width 0.127)
		(layer "In2.Cu")
		(net "XM_DATA_2")
	)
	(segment
		(start 188.084206 -53.4797)
		(end 188.084206 -51.482244)
		(width 0.127)
		(layer "In2.Cu")
		(net "XM_DATA_2")
	)
	(segment
		(start 199.856598 -62.672468)
		(end 198.802498 -61.618368)
		(width 0.127)
		(layer "In2.Cu")
		(net "XM_DATA_2")
	)
	(segment
		(start 197.976998 -60.164472)
		(end 197.797674 -60.164472)
		(width 0.127)
		(layer "In2.Cu")
		(net "XM_DATA_2")
	)
	(segment
		(start 197.630542 -60.33135)
		(end 197.451218 -60.33135)
		(width 0.127)
		(layer "In2.Cu")
		(net "XM_DATA_2")
	)
	(segment
		(start 196.552312 -59.25312)
		(end 196.719444 -59.086242)
		(width 0.127)
		(layer "In2.Cu")
		(net "XM_DATA_2")
	)
	(segment
		(start 196.732398 -59.61253)
		(end 196.552312 -59.432444)
		(width 0.127)
		(layer "In2.Cu")
		(net "XM_DATA_2")
	)
	(segment
		(start 196.911722 -59.61253)
		(end 196.732398 -59.61253)
		(width 0.127)
		(layer "In2.Cu")
		(net "XM_DATA_2")
	)
	(segment
		(start 196.000624 -58.188098)
		(end 195.286122 -57.473596)
		(width 0.127)
		(layer "In2.Cu")
		(net "XM_DATA_2")
	)
	(segment
		(start 197.078854 -59.445652)
		(end 196.911722 -59.61253)
		(width 0.127)
		(layer "In2.Cu")
		(net "XM_DATA_2")
	)
	(segment
		(start 197.451218 -60.33135)
		(end 197.271132 -60.151264)
		(width 0.127)
		(layer "In2.Cu")
		(net "XM_DATA_2")
	)
	(segment
		(start 197.438264 -59.625738)
		(end 197.258178 -59.445652)
		(width 0.127)
		(layer "In2.Cu")
		(net "XM_DATA_2")
	)
	(segment
		(start 186.87288 -50.270918)
		(end 186.87288 -45.320712)
		(width 0.127)
		(layer "In2.Cu")
		(net "XM_DATA_2")
	)
	(segment
		(start 197.271132 -59.97194)
		(end 197.438264 -59.805062)
		(width 0.127)
		(layer "In2.Cu")
		(net "XM_DATA_2")
	)
	(segment
		(start 196.719444 -59.086242)
		(end 196.719444 -58.906918)
		(width 0.127)
		(layer "In2.Cu")
		(net "XM_DATA_2")
	)
	(segment
		(start 196.000624 -58.367422)
		(end 196.000624 -58.188098)
		(width 0.127)
		(layer "In2.Cu")
		(net "XM_DATA_2")
	)
	(segment
		(start 195.833492 -58.5343)
		(end 196.000624 -58.367422)
		(width 0.127)
		(layer "In2.Cu")
		(net "XM_DATA_2")
	)
	(segment
		(start 201.634598 -69.027294)
		(end 201.250804 -69.027294)
		(width 0.127)
		(layer "In2.Cu")
		(net "XM_DATA_2")
	)
	(segment
		(start 197.438264 -59.805062)
		(end 197.438264 -59.625738)
		(width 0.127)
		(layer "In2.Cu")
		(net "XM_DATA_2")
	)
	(segment
		(start 199.856598 -65.246758)
		(end 199.856598 -62.672468)
		(width 0.127)
		(layer "In2.Cu")
		(net "XM_DATA_2")
	)
	(segment
		(start 186.87288 -45.320712)
		(end 186.09818 -44.546012)
		(width 0.127)
		(layer "In2.Cu")
		(net "XM_DATA_2")
	)
	(segment
		(start 185.945526 -44.546012)
		(end 185.39968 -44.000166)
		(width 0.127)
		(layer "In2.Cu")
		(net "XM_DATA_2")
	)
	(segment
		(start 177.8 -49.9999)
		(end 178.199796 -50.399696)
		(width 0.127)
		(layer "F.Cu")
		(net "XM_DATA_15")
	)
	(via
		(at 191.946022 -65.92316)
		(size 0.508)
		(drill 0.254)
		(layers "F.Cu" "B.Cu")
		(net "XM_DATA_15")
	)
	(via
		(at 178.199796 -50.399696)
		(size 0.508)
		(drill 0.254)
		(layers "F.Cu" "B.Cu")
		(net "XM_DATA_15")
	)
	(segment
		(start 193.92519 -64.759586)
		(end 193.92519 -65.074038)
		(width 0.127)
		(layer "B.Cu")
		(net "XM_DATA_15")
	)
	(segment
		(start 193.92519 -65.074038)
		(end 193.549016 -65.450212)
		(width 0.127)
		(layer "B.Cu")
		(net "XM_DATA_15")
	)
	(segment
		(start 195.656962 -63.027814)
		(end 193.92519 -64.759586)
		(width 0.127)
		(layer "B.Cu")
		(net "XM_DATA_15")
	)
	(segment
		(start 203.22032 -63.027814)
		(end 195.656962 -63.027814)
		(width 0.127)
		(layer "B.Cu")
		(net "XM_DATA_15")
	)
	(segment
		(start 192.41897 -65.450212)
		(end 191.946022 -65.92316)
		(width 0.127)
		(layer "B.Cu")
		(net "XM_DATA_15")
	)
	(segment
		(start 193.549016 -65.450212)
		(end 192.41897 -65.450212)
		(width 0.127)
		(layer "B.Cu")
		(net "XM_DATA_15")
	)
	(segment
		(start 178.968908 -55.715662)
		(end 178.199796 -54.94655)
		(width 0.127)
		(layer "In2.Cu")
		(net "XM_DATA_15")
	)
	(segment
		(start 184.492646 -65.45326)
		(end 178.968908 -59.929522)
		(width 0.127)
		(layer "In2.Cu")
		(net "XM_DATA_15")
	)
	(segment
		(start 178.968908 -59.929522)
		(end 178.968908 -55.715662)
		(width 0.127)
		(layer "In2.Cu")
		(net "XM_DATA_15")
	)
	(segment
		(start 178.199796 -54.94655)
		(end 178.199796 -50.399696)
		(width 0.127)
		(layer "In2.Cu")
		(net "XM_DATA_15")
	)
	(segment
		(start 191.946022 -65.92316)
		(end 191.476122 -65.45326)
		(width 0.127)
		(layer "In2.Cu")
		(net "XM_DATA_15")
	)
	(segment
		(start 191.476122 -65.45326)
		(end 184.492646 -65.45326)
		(width 0.127)
		(layer "In2.Cu")
		(net "XM_DATA_15")
	)
	(segment
		(start 185.805064 -48.399954)
		(end 185.799984 -48.399954)
		(width 0.127)
		(layer "F.Cu")
		(net "XM_DATA_14")
	)
	(segment
		(start 187.748672 -47.9806)
		(end 186.224418 -47.9806)
		(width 0.127)
		(layer "F.Cu")
		(net "XM_DATA_14")
	)
	(segment
		(start 188.989208 -49.221136)
		(end 187.748672 -47.9806)
		(width 0.127)
		(layer "F.Cu")
		(net "XM_DATA_14")
	)
	(segment
		(start 186.224418 -47.9806)
		(end 185.805064 -48.399954)
		(width 0.127)
		(layer "F.Cu")
		(net "XM_DATA_14")
	)
	(via
		(at 201.638408 -64.027304)
		(size 0.508)
		(drill 0.254)
		(layers "F.Cu" "B.Cu")
		(net "XM_DATA_14")
	)
	(via
		(at 188.989208 -49.221136)
		(size 0.508)
		(drill 0.254)
		(layers "F.Cu" "B.Cu")
		(net "XM_DATA_14")
	)
	(segment
		(start 203.22032 -64.027304)
		(end 201.638408 -64.027304)
		(width 0.127)
		(layer "B.Cu")
		(net "XM_DATA_14")
	)
	(segment
		(start 190.920116 -51.75377)
		(end 190.793116 -51.88077)
		(width 0.127)
		(layer "In2.Cu")
		(net "XM_DATA_14")
	)
	(segment
		(start 190.793116 -50.35677)
		(end 190.920116 -50.48377)
		(width 0.127)
		(layer "In2.Cu")
		(net "XM_DATA_14")
	)
	(segment
		(start 190.920116 -50.48377)
		(end 190.920116 -50.73777)
		(width 0.127)
		(layer "In2.Cu")
		(net "XM_DATA_14")
	)
	(segment
		(start 190.048388 -48.95977)
		(end 190.048388 -49.21377)
		(width 0.127)
		(layer "In2.Cu")
		(net "XM_DATA_14")
	)
	(segment
		(start 190.175388 -48.83277)
		(end 190.048388 -48.95977)
		(width 0.127)
		(layer "In2.Cu")
		(net "XM_DATA_14")
	)
	(segment
		(start 190.920116 -50.73777)
		(end 190.793116 -50.86477)
		(width 0.127)
		(layer "In2.Cu")
		(net "XM_DATA_14")
	)
	(segment
		(start 190.920116 -51.49977)
		(end 190.920116 -51.75377)
		(width 0.127)
		(layer "In2.Cu")
		(net "XM_DATA_14")
	)
	(segment
		(start 190.920116 -48.70577)
		(end 190.793116 -48.83277)
		(width 0.127)
		(layer "In2.Cu")
		(net "XM_DATA_14")
	)
	(segment
		(start 190.175388 -50.35677)
		(end 190.793116 -50.35677)
		(width 0.127)
		(layer "In2.Cu")
		(net "XM_DATA_14")
	)
	(segment
		(start 190.048388 -50.22977)
		(end 190.175388 -50.35677)
		(width 0.127)
		(layer "In2.Cu")
		(net "XM_DATA_14")
	)
	(segment
		(start 200.9648 -62.236858)
		(end 200.9648 -63.900304)
		(width 0.127)
		(layer "In2.Cu")
		(net "XM_DATA_14")
	)
	(segment
		(start 190.793116 -51.37277)
		(end 190.920116 -51.49977)
		(width 0.127)
		(layer "In2.Cu")
		(net "XM_DATA_14")
	)
	(segment
		(start 190.048388 -49.97577)
		(end 190.048388 -50.22977)
		(width 0.127)
		(layer "In2.Cu")
		(net "XM_DATA_14")
	)
	(segment
		(start 189.106048 -52.38877)
		(end 190.793116 -52.38877)
		(width 0.127)
		(layer "In2.Cu")
		(net "XM_DATA_14")
	)
	(segment
		(start 188.989208 -49.221136)
		(end 188.989208 -48.45177)
		(width 0.127)
		(layer "In2.Cu")
		(net "XM_DATA_14")
	)
	(segment
		(start 188.979048 -52.26177)
		(end 189.106048 -52.38877)
		(width 0.127)
		(layer "In2.Cu")
		(net "XM_DATA_14")
	)
	(segment
		(start 190.175388 -49.34077)
		(end 190.793116 -49.34077)
		(width 0.127)
		(layer "In2.Cu")
		(net "XM_DATA_14")
	)
	(segment
		(start 189.942216 -50.86477)
		(end 189.815216 -50.99177)
		(width 0.127)
		(layer "In2.Cu")
		(net "XM_DATA_14")
	)
	(segment
		(start 189.815216 -50.99177)
		(end 189.815216 -51.24577)
		(width 0.127)
		(layer "In2.Cu")
		(net "XM_DATA_14")
	)
	(segment
		(start 190.920116 -48.45177)
		(end 190.920116 -48.70577)
		(width 0.127)
		(layer "In2.Cu")
		(net "XM_DATA_14")
	)
	(segment
		(start 188.979048 -52.00777)
		(end 188.979048 -52.26177)
		(width 0.127)
		(layer "In2.Cu")
		(net "XM_DATA_14")
	)
	(segment
		(start 190.920116 -52.51577)
		(end 190.920116 -53.48859)
		(width 0.127)
		(layer "In2.Cu")
		(net "XM_DATA_14")
	)
	(segment
		(start 190.920116 -53.48859)
		(end 193.871342 -56.439816)
		(width 0.127)
		(layer "In2.Cu")
		(net "XM_DATA_14")
	)
	(segment
		(start 190.793116 -50.86477)
		(end 189.942216 -50.86477)
		(width 0.127)
		(layer "In2.Cu")
		(net "XM_DATA_14")
	)
	(segment
		(start 190.793116 -49.84877)
		(end 190.175388 -49.84877)
		(width 0.127)
		(layer "In2.Cu")
		(net "XM_DATA_14")
	)
	(segment
		(start 189.116208 -48.32477)
		(end 190.793116 -48.32477)
		(width 0.127)
		(layer "In2.Cu")
		(net "XM_DATA_14")
	)
	(segment
		(start 190.920116 -49.46777)
		(end 190.920116 -49.72177)
		(width 0.127)
		(layer "In2.Cu")
		(net "XM_DATA_14")
	)
	(segment
		(start 190.793116 -48.83277)
		(end 190.175388 -48.83277)
		(width 0.127)
		(layer "In2.Cu")
		(net "XM_DATA_14")
	)
	(segment
		(start 189.942216 -51.37277)
		(end 190.793116 -51.37277)
		(width 0.127)
		(layer "In2.Cu")
		(net "XM_DATA_14")
	)
	(segment
		(start 189.815216 -51.24577)
		(end 189.942216 -51.37277)
		(width 0.127)
		(layer "In2.Cu")
		(net "XM_DATA_14")
	)
	(segment
		(start 193.871342 -56.439816)
		(end 195.689474 -56.439816)
		(width 0.127)
		(layer "In2.Cu")
		(net "XM_DATA_14")
	)
	(segment
		(start 200.9648 -63.900304)
		(end 201.0918 -64.027304)
		(width 0.127)
		(layer "In2.Cu")
		(net "XM_DATA_14")
	)
	(segment
		(start 190.793116 -51.88077)
		(end 189.106048 -51.88077)
		(width 0.127)
		(layer "In2.Cu")
		(net "XM_DATA_14")
	)
	(segment
		(start 195.689474 -56.439816)
		(end 199.818498 -60.56884)
		(width 0.127)
		(layer "In2.Cu")
		(net "XM_DATA_14")
	)
	(segment
		(start 201.0918 -64.027304)
		(end 201.638408 -64.027304)
		(width 0.127)
		(layer "In2.Cu")
		(net "XM_DATA_14")
	)
	(segment
		(start 189.106048 -51.88077)
		(end 188.979048 -52.00777)
		(width 0.127)
		(layer "In2.Cu")
		(net "XM_DATA_14")
	)
	(segment
		(start 190.793116 -52.38877)
		(end 190.920116 -52.51577)
		(width 0.127)
		(layer "In2.Cu")
		(net "XM_DATA_14")
	)
	(segment
		(start 190.793116 -48.32477)
		(end 190.920116 -48.45177)
		(width 0.127)
		(layer "In2.Cu")
		(net "XM_DATA_14")
	)
	(segment
		(start 199.818498 -60.56884)
		(end 199.818498 -61.090556)
		(width 0.127)
		(layer "In2.Cu")
		(net "XM_DATA_14")
	)
	(segment
		(start 190.793116 -49.34077)
		(end 190.920116 -49.46777)
		(width 0.127)
		(layer "In2.Cu")
		(net "XM_DATA_14")
	)
	(segment
		(start 199.818498 -61.090556)
		(end 200.9648 -62.236858)
		(width 0.127)
		(layer "In2.Cu")
		(net "XM_DATA_14")
	)
	(segment
		(start 190.175388 -49.84877)
		(end 190.048388 -49.97577)
		(width 0.127)
		(layer "In2.Cu")
		(net "XM_DATA_14")
	)
	(segment
		(start 188.989208 -48.45177)
		(end 189.116208 -48.32477)
		(width 0.127)
		(layer "In2.Cu")
		(net "XM_DATA_14")
	)
	(segment
		(start 190.048388 -49.21377)
		(end 190.175388 -49.34077)
		(width 0.127)
		(layer "In2.Cu")
		(net "XM_DATA_14")
	)
	(segment
		(start 190.920116 -49.72177)
		(end 190.793116 -49.84877)
		(width 0.127)
		(layer "In2.Cu")
		(net "XM_DATA_14")
	)
	(segment
		(start 187.68441 -46.800008)
		(end 186.59983 -46.800008)
		(width 0.127)
		(layer "F.Cu")
		(net "XM_DATA_13")
	)
	(segment
		(start 187.693808 -46.79061)
		(end 187.68441 -46.800008)
		(width 0.127)
		(layer "F.Cu")
		(net "XM_DATA_13")
	)
	(via
		(at 187.693808 -46.79061)
		(size 0.508)
		(drill 0.254)
		(layers "F.Cu" "B.Cu")
		(net "XM_DATA_13")
	)
	(via
		(at 201.638408 -65.026794)
		(size 0.508)
		(drill 0.254)
		(layers "F.Cu" "B.Cu")
		(net "XM_DATA_13")
	)
	(segment
		(start 203.22032 -65.026794)
		(end 201.638408 -65.026794)
		(width 0.127)
		(layer "B.Cu")
		(net "XM_DATA_13")
	)
	(segment
		(start 192.190116 -55.685436)
		(end 192.369948 -55.685436)
		(width 0.127)
		(layer "In2.Cu")
		(net "XM_DATA_13")
	)
	(segment
		(start 192.048638 -56.545734)
		(end 192.048638 -56.725566)
		(width 0.127)
		(layer "In2.Cu")
		(net "XM_DATA_13")
	)
	(segment
		(start 190.610998 -55.287926)
		(end 190.790576 -55.467504)
		(width 0.127)
		(layer "In2.Cu")
		(net "XM_DATA_13")
	)
	(segment
		(start 189.570106 -53.094382)
		(end 189.570106 -53.273706)
		(width 0.127)
		(layer "In2.Cu")
		(net "XM_DATA_13")
	)
	(segment
		(start 189.173358 -53.850286)
		(end 189.352936 -54.029864)
		(width 0.127)
		(layer "In2.Cu")
		(net "XM_DATA_13")
	)
	(segment
		(start 200.4568 -62.447424)
		(end 200.4568 -64.899794)
		(width 0.127)
		(layer "In2.Cu")
		(net "XM_DATA_13")
	)
	(segment
		(start 191.471296 -54.966616)
		(end 191.651128 -54.966616)
		(width 0.127)
		(layer "In2.Cu")
		(net "XM_DATA_13")
	)
	(segment
		(start 192.549526 -56.044846)
		(end 192.048638 -56.545734)
		(width 0.127)
		(layer "In2.Cu")
		(net "XM_DATA_13")
	)
	(segment
		(start 195.478908 -56.947816)
		(end 199.310498 -60.779406)
		(width 0.127)
		(layer "In2.Cu")
		(net "XM_DATA_13")
	)
	(segment
		(start 189.892178 -54.389274)
		(end 189.892178 -54.569106)
		(width 0.127)
		(layer "In2.Cu")
		(net "XM_DATA_13")
	)
	(segment
		(start 187.66917 -47.852584)
		(end 187.79617 -47.979584)
		(width 0.127)
		(layer "In2.Cu")
		(net "XM_DATA_13")
	)
	(segment
		(start 190.752476 -54.247796)
		(end 190.932308 -54.247796)
		(width 0.127)
		(layer "In2.Cu")
		(net "XM_DATA_13")
	)
	(segment
		(start 200.4568 -64.899794)
		(end 200.5838 -65.026794)
		(width 0.127)
		(layer "In2.Cu")
		(net "XM_DATA_13")
	)
	(segment
		(start 200.5838 -65.026794)
		(end 201.638408 -65.026794)
		(width 0.127)
		(layer "In2.Cu")
		(net "XM_DATA_13")
	)
	(segment
		(start 187.693808 -46.79061)
		(end 188.36259 -46.79061)
		(width 0.127)
		(layer "In2.Cu")
		(net "XM_DATA_13")
	)
	(segment
		(start 188.48959 -53.166518)
		(end 188.634116 -53.311044)
		(width 0.127)
		(layer "In2.Cu")
		(net "XM_DATA_13")
	)
	(segment
		(start 190.071756 -54.748684)
		(end 190.251588 -54.748684)
		(width 0.127)
		(layer "In2.Cu")
		(net "XM_DATA_13")
	)
	(segment
		(start 199.310498 -61.301122)
		(end 200.4568 -62.447424)
		(width 0.127)
		(layer "In2.Cu")
		(net "XM_DATA_13")
	)
	(segment
		(start 189.389766 -52.91455)
		(end 189.570106 -53.094382)
		(width 0.127)
		(layer "In2.Cu")
		(net "XM_DATA_13")
	)
	(segment
		(start 191.689228 -56.186324)
		(end 192.190116 -55.685436)
		(width 0.127)
		(layer "In2.Cu")
		(net "XM_DATA_13")
	)
	(segment
		(start 191.329818 -56.006746)
		(end 191.509396 -56.186324)
		(width 0.127)
		(layer "In2.Cu")
		(net "XM_DATA_13")
	)
	(segment
		(start 190.251588 -54.748684)
		(end 190.752476 -54.247796)
		(width 0.127)
		(layer "In2.Cu")
		(net "XM_DATA_13")
	)
	(segment
		(start 192.549526 -55.865014)
		(end 192.549526 -56.044846)
		(width 0.127)
		(layer "In2.Cu")
		(net "XM_DATA_13")
	)
	(segment
		(start 192.369948 -55.685436)
		(end 192.549526 -55.865014)
		(width 0.127)
		(layer "In2.Cu")
		(net "XM_DATA_13")
	)
	(segment
		(start 191.111886 -54.427374)
		(end 191.111886 -54.607206)
		(width 0.127)
		(layer "In2.Cu")
		(net "XM_DATA_13")
	)
	(segment
		(start 191.651128 -54.966616)
		(end 191.830706 -55.146194)
		(width 0.127)
		(layer "In2.Cu")
		(net "XM_DATA_13")
	)
	(segment
		(start 189.173358 -53.670454)
		(end 189.173358 -53.850286)
		(width 0.127)
		(layer "In2.Cu")
		(net "XM_DATA_13")
	)
	(segment
		(start 192.270888 -56.947816)
		(end 195.478908 -56.947816)
		(width 0.127)
		(layer "In2.Cu")
		(net "XM_DATA_13")
	)
	(segment
		(start 189.532768 -54.029864)
		(end 189.983618 -53.579014)
		(width 0.127)
		(layer "In2.Cu")
		(net "XM_DATA_13")
	)
	(segment
		(start 190.790576 -55.467504)
		(end 190.970408 -55.467504)
		(width 0.127)
		(layer "In2.Cu")
		(net "XM_DATA_13")
	)
	(segment
		(start 190.932308 -54.247796)
		(end 191.111886 -54.427374)
		(width 0.127)
		(layer "In2.Cu")
		(net "XM_DATA_13")
	)
	(segment
		(start 191.329818 -55.826914)
		(end 191.329818 -56.006746)
		(width 0.127)
		(layer "In2.Cu")
		(net "XM_DATA_13")
	)
	(segment
		(start 188.36259 -46.79061)
		(end 188.48959 -46.91761)
		(width 0.127)
		(layer "In2.Cu")
		(net "XM_DATA_13")
	)
	(segment
		(start 191.111886 -54.607206)
		(end 190.610998 -55.108094)
		(width 0.127)
		(layer "In2.Cu")
		(net "XM_DATA_13")
	)
	(segment
		(start 190.610998 -55.108094)
		(end 190.610998 -55.287926)
		(width 0.127)
		(layer "In2.Cu")
		(net "XM_DATA_13")
	)
	(segment
		(start 188.36259 -47.471584)
		(end 187.79617 -47.471584)
		(width 0.127)
		(layer "In2.Cu")
		(net "XM_DATA_13")
	)
	(segment
		(start 188.634116 -53.311044)
		(end 188.813948 -53.311044)
		(width 0.127)
		(layer "In2.Cu")
		(net "XM_DATA_13")
	)
	(segment
		(start 190.343028 -53.938424)
		(end 189.892178 -54.389274)
		(width 0.127)
		(layer "In2.Cu")
		(net "XM_DATA_13")
	)
	(segment
		(start 188.48959 -46.91761)
		(end 188.48959 -47.344584)
		(width 0.127)
		(layer "In2.Cu")
		(net "XM_DATA_13")
	)
	(segment
		(start 189.210442 -52.91455)
		(end 189.389766 -52.91455)
		(width 0.127)
		(layer "In2.Cu")
		(net "XM_DATA_13")
	)
	(segment
		(start 188.36259 -47.979584)
		(end 188.48959 -48.106584)
		(width 0.127)
		(layer "In2.Cu")
		(net "XM_DATA_13")
	)
	(segment
		(start 188.48959 -47.344584)
		(end 188.36259 -47.471584)
		(width 0.127)
		(layer "In2.Cu")
		(net "XM_DATA_13")
	)
	(segment
		(start 190.343028 -53.758592)
		(end 190.343028 -53.938424)
		(width 0.127)
		(layer "In2.Cu")
		(net "XM_DATA_13")
	)
	(segment
		(start 190.16345 -53.579014)
		(end 190.343028 -53.758592)
		(width 0.127)
		(layer "In2.Cu")
		(net "XM_DATA_13")
	)
	(segment
		(start 188.813948 -53.311044)
		(end 189.210442 -52.91455)
		(width 0.127)
		(layer "In2.Cu")
		(net "XM_DATA_13")
	)
	(segment
		(start 191.830706 -55.326026)
		(end 191.329818 -55.826914)
		(width 0.127)
		(layer "In2.Cu")
		(net "XM_DATA_13")
	)
	(segment
		(start 189.983618 -53.579014)
		(end 190.16345 -53.579014)
		(width 0.127)
		(layer "In2.Cu")
		(net "XM_DATA_13")
	)
	(segment
		(start 187.79617 -47.471584)
		(end 187.66917 -47.598584)
		(width 0.127)
		(layer "In2.Cu")
		(net "XM_DATA_13")
	)
	(segment
		(start 190.970408 -55.467504)
		(end 191.471296 -54.966616)
		(width 0.127)
		(layer "In2.Cu")
		(net "XM_DATA_13")
	)
	(segment
		(start 187.79617 -47.979584)
		(end 188.36259 -47.979584)
		(width 0.127)
		(layer "In2.Cu")
		(net "XM_DATA_13")
	)
	(segment
		(start 199.310498 -60.779406)
		(end 199.310498 -61.301122)
		(width 0.127)
		(layer "In2.Cu")
		(net "XM_DATA_13")
	)
	(segment
		(start 189.570106 -53.273706)
		(end 189.173358 -53.670454)
		(width 0.127)
		(layer "In2.Cu")
		(net "XM_DATA_13")
	)
	(segment
		(start 189.352936 -54.029864)
		(end 189.532768 -54.029864)
		(width 0.127)
		(layer "In2.Cu")
		(net "XM_DATA_13")
	)
	(segment
		(start 191.830706 -55.146194)
		(end 191.830706 -55.326026)
		(width 0.127)
		(layer "In2.Cu")
		(net "XM_DATA_13")
	)
	(segment
		(start 192.048638 -56.725566)
		(end 192.270888 -56.947816)
		(width 0.127)
		(layer "In2.Cu")
		(net "XM_DATA_13")
	)
	(segment
		(start 187.66917 -47.598584)
		(end 187.66917 -47.852584)
		(width 0.127)
		(layer "In2.Cu")
		(net "XM_DATA_13")
	)
	(segment
		(start 188.48959 -48.106584)
		(end 188.48959 -53.166518)
		(width 0.127)
		(layer "In2.Cu")
		(net "XM_DATA_13")
	)
	(segment
		(start 189.892178 -54.569106)
		(end 190.071756 -54.748684)
		(width 0.127)
		(layer "In2.Cu")
		(net "XM_DATA_13")
	)
	(segment
		(start 191.509396 -56.186324)
		(end 191.689228 -56.186324)
		(width 0.127)
		(layer "In2.Cu")
		(net "XM_DATA_13")
	)
	(segment
		(start 184.999884 -45.199808)
		(end 185.39968 -44.800012)
		(width 0.127)
		(layer "F.Cu")
		(net "XM_DATA_12")
	)
	(via
		(at 199.348598 -66.027554)
		(size 0.508)
		(drill 0.254)
		(layers "F.Cu" "B.Cu")
		(net "XM_DATA_12")
	)
	(via
		(at 185.39968 -44.800012)
		(size 0.508)
		(drill 0.254)
		(layers "F.Cu" "B.Cu")
		(net "XM_DATA_12")
	)
	(segment
		(start 199.348598 -66.027554)
		(end 203.22032 -66.027554)
		(width 0.127)
		(layer "B.Cu")
		(net "XM_DATA_12")
	)
	(segment
		(start 187.533534 -54.500526)
		(end 187.713366 -54.500526)
		(width 0.127)
		(layer "In2.Cu")
		(net "XM_DATA_12")
	)
	(segment
		(start 190.229236 -57.196228)
		(end 190.408814 -57.375806)
		(width 0.127)
		(layer "In2.Cu")
		(net "XM_DATA_12")
	)
	(segment
		(start 187.96 -54.253892)
		(end 188.139832 -54.253892)
		(width 0.127)
		(layer "In2.Cu")
		(net "XM_DATA_12")
	)
	(segment
		(start 189.577472 -55.691532)
		(end 189.75705 -55.87111)
		(width 0.127)
		(layer "In2.Cu")
		(net "XM_DATA_12")
	)
	(segment
		(start 190.83528 -57.129172)
		(end 191.015112 -57.129172)
		(width 0.127)
		(layer "In2.Cu")
		(net "XM_DATA_12")
	)
	(segment
		(start 190.229236 -57.016396)
		(end 190.229236 -57.196228)
		(width 0.127)
		(layer "In2.Cu")
		(net "XM_DATA_12")
	)
	(segment
		(start 187.432188 -53.546248)
		(end 187.60059 -53.71465)
		(width 0.127)
		(layer "In2.Cu")
		(net "XM_DATA_12")
	)
	(segment
		(start 191.236092 -57.986168)
		(end 191.415924 -57.986168)
		(width 0.127)
		(layer "In2.Cu")
		(net "XM_DATA_12")
	)
	(segment
		(start 199.348598 -62.974474)
		(end 199.348598 -66.027554)
		(width 0.127)
		(layer "In2.Cu")
		(net "XM_DATA_12")
	)
	(segment
		(start 189.510416 -56.297576)
		(end 189.510416 -56.477408)
		(width 0.127)
		(layer "In2.Cu")
		(net "XM_DATA_12")
	)
	(segment
		(start 189.03823 -55.332122)
		(end 188.791596 -55.578756)
		(width 0.127)
		(layer "In2.Cu")
		(net "XM_DATA_12")
	)
	(segment
		(start 191.19469 -57.488582)
		(end 191.056514 -57.626758)
		(width 0.127)
		(layer "In2.Cu")
		(net "XM_DATA_12")
	)
	(segment
		(start 191.015112 -57.129172)
		(end 191.19469 -57.30875)
		(width 0.127)
		(layer "In2.Cu")
		(net "XM_DATA_12")
	)
	(segment
		(start 190.296292 -56.410352)
		(end 190.47587 -56.58993)
		(width 0.127)
		(layer "In2.Cu")
		(net "XM_DATA_12")
	)
	(segment
		(start 189.510416 -56.477408)
		(end 189.689994 -56.656986)
		(width 0.127)
		(layer "In2.Cu")
		(net "XM_DATA_12")
	)
	(segment
		(start 187.60059 -53.71465)
		(end 187.60059 -53.894482)
		(width 0.127)
		(layer "In2.Cu")
		(net "XM_DATA_12")
	)
	(segment
		(start 185.99277 -44.800012)
		(end 186.61888 -45.426122)
		(width 0.127)
		(layer "In2.Cu")
		(net "XM_DATA_12")
	)
	(segment
		(start 187.353956 -54.141116)
		(end 187.353956 -54.320948)
		(width 0.127)
		(layer "In2.Cu")
		(net "XM_DATA_12")
	)
	(segment
		(start 189.03823 -55.15229)
		(end 189.03823 -55.332122)
		(width 0.127)
		(layer "In2.Cu")
		(net "XM_DATA_12")
	)
	(segment
		(start 188.252354 -55.219346)
		(end 188.432186 -55.219346)
		(width 0.127)
		(layer "In2.Cu")
		(net "XM_DATA_12")
	)
	(segment
		(start 189.39764 -55.691532)
		(end 189.577472 -55.691532)
		(width 0.127)
		(layer "In2.Cu")
		(net "XM_DATA_12")
	)
	(segment
		(start 191.867536 -57.981596)
		(end 194.35572 -57.981596)
		(width 0.127)
		(layer "In2.Cu")
		(net "XM_DATA_12")
	)
	(segment
		(start 190.47587 -56.769762)
		(end 190.229236 -57.016396)
		(width 0.127)
		(layer "In2.Cu")
		(net "XM_DATA_12")
	)
	(segment
		(start 185.39968 -44.800012)
		(end 185.99277 -44.800012)
		(width 0.127)
		(layer "In2.Cu")
		(net "XM_DATA_12")
	)
	(segment
		(start 186.61888 -51.89093)
		(end 187.432188 -52.704238)
		(width 0.127)
		(layer "In2.Cu")
		(net "XM_DATA_12")
	)
	(segment
		(start 187.713366 -54.500526)
		(end 187.96 -54.253892)
		(width 0.127)
		(layer "In2.Cu")
		(net "XM_DATA_12")
	)
	(segment
		(start 191.056514 -57.80659)
		(end 191.236092 -57.986168)
		(width 0.127)
		(layer "In2.Cu")
		(net "XM_DATA_12")
	)
	(segment
		(start 188.31941 -54.43347)
		(end 188.31941 -54.613302)
		(width 0.127)
		(layer "In2.Cu")
		(net "XM_DATA_12")
	)
	(segment
		(start 187.353956 -54.320948)
		(end 187.533534 -54.500526)
		(width 0.127)
		(layer "In2.Cu")
		(net "XM_DATA_12")
	)
	(segment
		(start 190.588646 -57.375806)
		(end 190.83528 -57.129172)
		(width 0.127)
		(layer "In2.Cu")
		(net "XM_DATA_12")
	)
	(segment
		(start 191.056514 -57.626758)
		(end 191.056514 -57.80659)
		(width 0.127)
		(layer "In2.Cu")
		(net "XM_DATA_12")
	)
	(segment
		(start 188.858652 -54.972712)
		(end 189.03823 -55.15229)
		(width 0.127)
		(layer "In2.Cu")
		(net "XM_DATA_12")
	)
	(segment
		(start 188.791596 -55.758588)
		(end 188.971174 -55.938166)
		(width 0.127)
		(layer "In2.Cu")
		(net "XM_DATA_12")
	)
	(segment
		(start 189.689994 -56.656986)
		(end 189.869826 -56.656986)
		(width 0.127)
		(layer "In2.Cu")
		(net "XM_DATA_12")
	)
	(segment
		(start 188.791596 -55.578756)
		(end 188.791596 -55.758588)
		(width 0.127)
		(layer "In2.Cu")
		(net "XM_DATA_12")
	)
	(segment
		(start 194.35572 -57.981596)
		(end 199.348598 -62.974474)
		(width 0.127)
		(layer "In2.Cu")
		(net "XM_DATA_12")
	)
	(segment
		(start 190.47587 -56.58993)
		(end 190.47587 -56.769762)
		(width 0.127)
		(layer "In2.Cu")
		(net "XM_DATA_12")
	)
	(segment
		(start 188.971174 -55.938166)
		(end 189.151006 -55.938166)
		(width 0.127)
		(layer "In2.Cu")
		(net "XM_DATA_12")
	)
	(segment
		(start 189.869826 -56.656986)
		(end 190.11646 -56.410352)
		(width 0.127)
		(layer "In2.Cu")
		(net "XM_DATA_12")
	)
	(segment
		(start 191.415924 -57.986168)
		(end 191.5541 -57.847992)
		(width 0.127)
		(layer "In2.Cu")
		(net "XM_DATA_12")
	)
	(segment
		(start 188.072776 -55.039768)
		(end 188.252354 -55.219346)
		(width 0.127)
		(layer "In2.Cu")
		(net "XM_DATA_12")
	)
	(segment
		(start 191.19469 -57.30875)
		(end 191.19469 -57.488582)
		(width 0.127)
		(layer "In2.Cu")
		(net "XM_DATA_12")
	)
	(segment
		(start 188.072776 -54.859936)
		(end 188.072776 -55.039768)
		(width 0.127)
		(layer "In2.Cu")
		(net "XM_DATA_12")
	)
	(segment
		(start 188.67882 -54.972712)
		(end 188.858652 -54.972712)
		(width 0.127)
		(layer "In2.Cu")
		(net "XM_DATA_12")
	)
	(segment
		(start 189.75705 -56.050942)
		(end 189.510416 -56.297576)
		(width 0.127)
		(layer "In2.Cu")
		(net "XM_DATA_12")
	)
	(segment
		(start 189.75705 -55.87111)
		(end 189.75705 -56.050942)
		(width 0.127)
		(layer "In2.Cu")
		(net "XM_DATA_12")
	)
	(segment
		(start 186.61888 -45.426122)
		(end 186.61888 -51.89093)
		(width 0.127)
		(layer "In2.Cu")
		(net "XM_DATA_12")
	)
	(segment
		(start 188.31941 -54.613302)
		(end 188.072776 -54.859936)
		(width 0.127)
		(layer "In2.Cu")
		(net "XM_DATA_12")
	)
	(segment
		(start 190.408814 -57.375806)
		(end 190.588646 -57.375806)
		(width 0.127)
		(layer "In2.Cu")
		(net "XM_DATA_12")
	)
	(segment
		(start 188.139832 -54.253892)
		(end 188.31941 -54.43347)
		(width 0.127)
		(layer "In2.Cu")
		(net "XM_DATA_12")
	)
	(segment
		(start 187.60059 -53.894482)
		(end 187.353956 -54.141116)
		(width 0.127)
		(layer "In2.Cu")
		(net "XM_DATA_12")
	)
	(segment
		(start 191.5541 -57.847992)
		(end 191.733932 -57.847992)
		(width 0.127)
		(layer "In2.Cu")
		(net "XM_DATA_12")
	)
	(segment
		(start 189.151006 -55.938166)
		(end 189.39764 -55.691532)
		(width 0.127)
		(layer "In2.Cu")
		(net "XM_DATA_12")
	)
	(segment
		(start 187.432188 -52.704238)
		(end 187.432188 -53.546248)
		(width 0.127)
		(layer "In2.Cu")
		(net "XM_DATA_12")
	)
	(segment
		(start 188.432186 -55.219346)
		(end 188.67882 -54.972712)
		(width 0.127)
		(layer "In2.Cu")
		(net "XM_DATA_12")
	)
	(segment
		(start 191.733932 -57.847992)
		(end 191.867536 -57.981596)
		(width 0.127)
		(layer "In2.Cu")
		(net "XM_DATA_12")
	)
	(segment
		(start 190.11646 -56.410352)
		(end 190.296292 -56.410352)
		(width 0.127)
		(layer "In2.Cu")
		(net "XM_DATA_12")
	)
	(segment
		(start 185.90641 -52.40274)
		(end 185.799984 -52.296314)
		(width 0.127)
		(layer "F.Cu")
		(net "XM_DATA_11")
	)
	(segment
		(start 185.799984 -52.296314)
		(end 185.799984 -51.599846)
		(width 0.127)
		(layer "F.Cu")
		(net "XM_DATA_11")
	)
	(via
		(at 199.348598 -67.028314)
		(size 0.508)
		(drill 0.254)
		(layers "F.Cu" "B.Cu")
		(net "XM_DATA_11")
	)
	(via
		(at 185.90641 -52.40274)
		(size 0.508)
		(drill 0.254)
		(layers "F.Cu" "B.Cu")
		(net "XM_DATA_11")
	)
	(segment
		(start 201.22261 -67.527424)
		(end 203.22032 -67.527424)
		(width 0.127)
		(layer "B.Cu")
		(net "XM_DATA_11")
	)
	(segment
		(start 200.58761 -66.43751)
		(end 200.71461 -66.31051)
		(width 0.127)
		(layer "B.Cu")
		(net "XM_DATA_11")
	)
	(segment
		(start 200.58761 -67.273424)
		(end 200.58761 -66.43751)
		(width 0.127)
		(layer "B.Cu")
		(net "XM_DATA_11")
	)
	(segment
		(start 201.09561 -67.400424)
		(end 201.22261 -67.527424)
		(width 0.127)
		(layer "B.Cu")
		(net "XM_DATA_11")
	)
	(segment
		(start 200.210928 -67.400424)
		(end 200.46061 -67.400424)
		(width 0.127)
		(layer "B.Cu")
		(net "XM_DATA_11")
	)
	(segment
		(start 200.96861 -66.31051)
		(end 201.09561 -66.43751)
		(width 0.127)
		(layer "B.Cu")
		(net "XM_DATA_11")
	)
	(segment
		(start 199.348598 -67.028314)
		(end 199.838818 -67.028314)
		(width 0.127)
		(layer "B.Cu")
		(net "XM_DATA_11")
	)
	(segment
		(start 201.09561 -66.43751)
		(end 201.09561 -67.400424)
		(width 0.127)
		(layer "B.Cu")
		(net "XM_DATA_11")
	)
	(segment
		(start 200.71461 -66.31051)
		(end 200.96861 -66.31051)
		(width 0.127)
		(layer "B.Cu")
		(net "XM_DATA_11")
	)
	(segment
		(start 199.838818 -67.028314)
		(end 200.210928 -67.400424)
		(width 0.127)
		(layer "B.Cu")
		(net "XM_DATA_11")
	)
	(segment
		(start 200.46061 -67.400424)
		(end 200.58761 -67.273424)
		(width 0.127)
		(layer "B.Cu")
		(net "XM_DATA_11")
	)
	(segment
		(start 186.445652 -56.440578)
		(end 186.625484 -56.440578)
		(width 0.127)
		(layer "In2.Cu")
		(net "XM_DATA_11")
	)
	(segment
		(start 186.140344 -54.769258)
		(end 185.843418 -55.06593)
		(width 0.127)
		(layer "In2.Cu")
		(net "XM_DATA_11")
	)
	(segment
		(start 189.479936 -58.792364)
		(end 189.65926 -58.792364)
		(width 0.127)
		(layer "In2.Cu")
		(net "XM_DATA_11")
	)
	(segment
		(start 198.966074 -67.028314)
		(end 199.348598 -67.028314)
		(width 0.127)
		(layer "In2.Cu")
		(net "XM_DATA_11")
	)
	(segment
		(start 186.984894 -56.799988)
		(end 186.984894 -56.97982)
		(width 0.127)
		(layer "In2.Cu")
		(net "XM_DATA_11")
	)
	(segment
		(start 186.984894 -56.97982)
		(end 187.164472 -57.159398)
		(width 0.127)
		(layer "In2.Cu")
		(net "XM_DATA_11")
	)
	(segment
		(start 186.859164 -55.308246)
		(end 186.859164 -55.488078)
		(width 0.127)
		(layer "In2.Cu")
		(net "XM_DATA_11")
	)
	(segment
		(start 186.859164 -55.488078)
		(end 186.266074 -56.081168)
		(width 0.127)
		(layer "In2.Cu")
		(net "XM_DATA_11")
	)
	(segment
		(start 187.703714 -57.518808)
		(end 187.703714 -57.69864)
		(width 0.127)
		(layer "In2.Cu")
		(net "XM_DATA_11")
	)
	(segment
		(start 198.332598 -63.395606)
		(end 198.332598 -66.394838)
		(width 0.127)
		(layer "In2.Cu")
		(net "XM_DATA_11")
	)
	(segment
		(start 185.843418 -55.06593)
		(end 185.843418 -55.245254)
		(width 0.127)
		(layer "In2.Cu")
		(net "XM_DATA_11")
	)
	(segment
		(start 186.203082 -55.425594)
		(end 186.499754 -55.128668)
		(width 0.127)
		(layer "In2.Cu")
		(net "XM_DATA_11")
	)
	(segment
		(start 186.023758 -55.425594)
		(end 186.203082 -55.425594)
		(width 0.127)
		(layer "In2.Cu")
		(net "XM_DATA_11")
	)
	(segment
		(start 189.29985 -58.432954)
		(end 189.29985 -58.612278)
		(width 0.127)
		(layer "In2.Cu")
		(net "XM_DATA_11")
	)
	(segment
		(start 186.679586 -55.128668)
		(end 186.859164 -55.308246)
		(width 0.127)
		(layer "In2.Cu")
		(net "XM_DATA_11")
	)
	(segment
		(start 188.117226 -56.566308)
		(end 188.296804 -56.745886)
		(width 0.127)
		(layer "In2.Cu")
		(net "XM_DATA_11")
	)
	(segment
		(start 189.552072 -58.001154)
		(end 189.552072 -58.180478)
		(width 0.127)
		(layer "In2.Cu")
		(net "XM_DATA_11")
	)
	(segment
		(start 189.65926 -58.792364)
		(end 189.911482 -58.539888)
		(width 0.127)
		(layer "In2.Cu")
		(net "XM_DATA_11")
	)
	(segment
		(start 187.398406 -55.847488)
		(end 187.577984 -56.027066)
		(width 0.127)
		(layer "In2.Cu")
		(net "XM_DATA_11")
	)
	(segment
		(start 187.577984 -56.027066)
		(end 187.577984 -56.206898)
		(width 0.127)
		(layer "In2.Cu")
		(net "XM_DATA_11")
	)
	(segment
		(start 186.499754 -55.128668)
		(end 186.679586 -55.128668)
		(width 0.127)
		(layer "In2.Cu")
		(net "XM_DATA_11")
	)
	(segment
		(start 188.296804 -56.925718)
		(end 187.703714 -57.518808)
		(width 0.127)
		(layer "In2.Cu")
		(net "XM_DATA_11")
	)
	(segment
		(start 189.29985 -58.612278)
		(end 189.479936 -58.792364)
		(width 0.127)
		(layer "In2.Cu")
		(net "XM_DATA_11")
	)
	(segment
		(start 188.656214 -57.285128)
		(end 188.836046 -57.285128)
		(width 0.127)
		(layer "In2.Cu")
		(net "XM_DATA_11")
	)
	(segment
		(start 187.703714 -57.69864)
		(end 187.883292 -57.878218)
		(width 0.127)
		(layer "In2.Cu")
		(net "XM_DATA_11")
	)
	(segment
		(start 187.164472 -57.159398)
		(end 187.344304 -57.159398)
		(width 0.127)
		(layer "In2.Cu")
		(net "XM_DATA_11")
	)
	(segment
		(start 188.063124 -57.878218)
		(end 188.656214 -57.285128)
		(width 0.127)
		(layer "In2.Cu")
		(net "XM_DATA_11")
	)
	(segment
		(start 187.577984 -56.206898)
		(end 186.984894 -56.799988)
		(width 0.127)
		(layer "In2.Cu")
		(net "XM_DATA_11")
	)
	(segment
		(start 188.836046 -57.285128)
		(end 189.552072 -58.001154)
		(width 0.127)
		(layer "In2.Cu")
		(net "XM_DATA_11")
	)
	(segment
		(start 185.90641 -52.40274)
		(end 185.90641 -54.355492)
		(width 0.127)
		(layer "In2.Cu")
		(net "XM_DATA_11")
	)
	(segment
		(start 185.90641 -54.355492)
		(end 186.140344 -54.589426)
		(width 0.127)
		(layer "In2.Cu")
		(net "XM_DATA_11")
	)
	(segment
		(start 198.332598 -66.394838)
		(end 198.966074 -67.028314)
		(width 0.127)
		(layer "In2.Cu")
		(net "XM_DATA_11")
	)
	(segment
		(start 189.911482 -58.539888)
		(end 190.090806 -58.539888)
		(width 0.127)
		(layer "In2.Cu")
		(net "XM_DATA_11")
	)
	(segment
		(start 186.625484 -56.440578)
		(end 187.218574 -55.847488)
		(width 0.127)
		(layer "In2.Cu")
		(net "XM_DATA_11")
	)
	(segment
		(start 186.266074 -56.261)
		(end 186.445652 -56.440578)
		(width 0.127)
		(layer "In2.Cu")
		(net "XM_DATA_11")
	)
	(segment
		(start 186.140344 -54.589426)
		(end 186.140344 -54.769258)
		(width 0.127)
		(layer "In2.Cu")
		(net "XM_DATA_11")
	)
	(segment
		(start 187.883292 -57.878218)
		(end 188.063124 -57.878218)
		(width 0.127)
		(layer "In2.Cu")
		(net "XM_DATA_11")
	)
	(segment
		(start 190.090806 -58.539888)
		(end 190.583312 -59.032394)
		(width 0.127)
		(layer "In2.Cu")
		(net "XM_DATA_11")
	)
	(segment
		(start 186.266074 -56.081168)
		(end 186.266074 -56.261)
		(width 0.127)
		(layer "In2.Cu")
		(net "XM_DATA_11")
	)
	(segment
		(start 193.969386 -59.032394)
		(end 198.332598 -63.395606)
		(width 0.127)
		(layer "In2.Cu")
		(net "XM_DATA_11")
	)
	(segment
		(start 187.344304 -57.159398)
		(end 187.937394 -56.566308)
		(width 0.127)
		(layer "In2.Cu")
		(net "XM_DATA_11")
	)
	(segment
		(start 188.296804 -56.745886)
		(end 188.296804 -56.925718)
		(width 0.127)
		(layer "In2.Cu")
		(net "XM_DATA_11")
	)
	(segment
		(start 189.552072 -58.180478)
		(end 189.29985 -58.432954)
		(width 0.127)
		(layer "In2.Cu")
		(net "XM_DATA_11")
	)
	(segment
		(start 187.937394 -56.566308)
		(end 188.117226 -56.566308)
		(width 0.127)
		(layer "In2.Cu")
		(net "XM_DATA_11")
	)
	(segment
		(start 187.218574 -55.847488)
		(end 187.398406 -55.847488)
		(width 0.127)
		(layer "In2.Cu")
		(net "XM_DATA_11")
	)
	(segment
		(start 190.583312 -59.032394)
		(end 193.969386 -59.032394)
		(width 0.127)
		(layer "In2.Cu")
		(net "XM_DATA_11")
	)
	(segment
		(start 185.843418 -55.245254)
		(end 186.023758 -55.425594)
		(width 0.127)
		(layer "In2.Cu")
		(net "XM_DATA_11")
	)
	(segment
		(start 182.599838 -49.9999)
		(end 182.999634 -50.399696)
		(width 0.127)
		(layer "F.Cu")
		(net "XM_DATA_10")
	)
	(via
		(at 182.999634 -50.399696)
		(size 0.508)
		(drill 0.254)
		(layers "F.Cu" "B.Cu")
		(net "XM_DATA_10")
	)
	(via
		(at 198.332598 -68.027804)
		(size 0.508)
		(drill 0.254)
		(layers "F.Cu" "B.Cu")
		(net "XM_DATA_10")
	)
	(segment
		(start 199.637904 -67.557904)
		(end 198.802498 -67.557904)
		(width 0.127)
		(layer "B.Cu")
		(net "XM_DATA_10")
	)
	(segment
		(start 203.22032 -68.526914)
		(end 200.606914 -68.526914)
		(width 0.127)
		(layer "B.Cu")
		(net "XM_DATA_10")
	)
	(segment
		(start 200.606914 -68.526914)
		(end 199.637904 -67.557904)
		(width 0.127)
		(layer "B.Cu")
		(net "XM_DATA_10")
	)
	(segment
		(start 198.802498 -67.557904)
		(end 198.332598 -68.027804)
		(width 0.127)
		(layer "B.Cu")
		(net "XM_DATA_10")
	)
	(segment
		(start 186.371992 -58.580274)
		(end 185.954162 -58.998104)
		(width 0.127)
		(layer "In2.Cu")
		(net "XM_DATA_10")
	)
	(segment
		(start 185.235342 -58.279284)
		(end 185.235342 -58.459116)
		(width 0.127)
		(layer "In2.Cu")
		(net "XM_DATA_10")
	)
	(segment
		(start 187.090812 -59.299094)
		(end 186.672982 -59.716924)
		(width 0.127)
		(layer "In2.Cu")
		(net "XM_DATA_10")
	)
	(segment
		(start 187.630054 -59.658504)
		(end 188.03747 -60.06592)
		(width 0.127)
		(layer "In2.Cu")
		(net "XM_DATA_10")
	)
	(segment
		(start 185.653172 -57.681622)
		(end 185.653172 -57.861454)
		(width 0.127)
		(layer "In2.Cu")
		(net "XM_DATA_10")
	)
	(segment
		(start 185.473594 -57.502044)
		(end 185.653172 -57.681622)
		(width 0.127)
		(layer "In2.Cu")
		(net "XM_DATA_10")
	)
	(segment
		(start 194.231514 -60.731654)
		(end 197.316598 -63.816738)
		(width 0.127)
		(layer "In2.Cu")
		(net "XM_DATA_10")
	)
	(segment
		(start 184.646062 -57.431178)
		(end 184.646062 -57.610502)
		(width 0.127)
		(layer "In2.Cu")
		(net "XM_DATA_10")
	)
	(segment
		(start 188.03747 -60.06592)
		(end 191.01308 -60.06592)
		(width 0.127)
		(layer "In2.Cu")
		(net "XM_DATA_10")
	)
	(segment
		(start 185.005218 -57.790334)
		(end 185.293762 -57.502044)
		(width 0.127)
		(layer "In2.Cu")
		(net "XM_DATA_10")
	)
	(segment
		(start 185.954162 -59.177936)
		(end 186.13374 -59.357514)
		(width 0.127)
		(layer "In2.Cu")
		(net "XM_DATA_10")
	)
	(segment
		(start 186.672982 -59.896756)
		(end 186.85256 -60.076334)
		(width 0.127)
		(layer "In2.Cu")
		(net "XM_DATA_10")
	)
	(segment
		(start 186.313572 -59.357514)
		(end 186.731402 -58.939684)
		(width 0.127)
		(layer "In2.Cu")
		(net "XM_DATA_10")
	)
	(segment
		(start 186.012582 -58.220864)
		(end 186.192414 -58.220864)
		(width 0.127)
		(layer "In2.Cu")
		(net "XM_DATA_10")
	)
	(segment
		(start 186.672982 -59.716924)
		(end 186.672982 -59.896756)
		(width 0.127)
		(layer "In2.Cu")
		(net "XM_DATA_10")
	)
	(segment
		(start 186.371992 -58.400442)
		(end 186.371992 -58.580274)
		(width 0.127)
		(layer "In2.Cu")
		(net "XM_DATA_10")
	)
	(segment
		(start 191.678814 -60.731654)
		(end 194.231514 -60.731654)
		(width 0.127)
		(layer "In2.Cu")
		(net "XM_DATA_10")
	)
	(segment
		(start 182.999634 -51.758342)
		(end 183.674004 -52.432712)
		(width 0.127)
		(layer "In2.Cu")
		(net "XM_DATA_10")
	)
	(segment
		(start 186.85256 -60.076334)
		(end 187.032392 -60.076334)
		(width 0.127)
		(layer "In2.Cu")
		(net "XM_DATA_10")
	)
	(segment
		(start 185.235342 -58.459116)
		(end 185.41492 -58.638694)
		(width 0.127)
		(layer "In2.Cu")
		(net "XM_DATA_10")
	)
	(segment
		(start 183.674004 -52.432712)
		(end 183.674004 -55.702454)
		(width 0.127)
		(layer "In2.Cu")
		(net "XM_DATA_10")
	)
	(segment
		(start 186.13374 -59.357514)
		(end 186.313572 -59.357514)
		(width 0.127)
		(layer "In2.Cu")
		(net "XM_DATA_10")
	)
	(segment
		(start 197.316598 -67.011804)
		(end 198.332598 -68.027804)
		(width 0.127)
		(layer "In2.Cu")
		(net "XM_DATA_10")
	)
	(segment
		(start 185.653172 -57.861454)
		(end 185.235342 -58.279284)
		(width 0.127)
		(layer "In2.Cu")
		(net "XM_DATA_10")
	)
	(segment
		(start 187.032392 -60.076334)
		(end 187.450222 -59.658504)
		(width 0.127)
		(layer "In2.Cu")
		(net "XM_DATA_10")
	)
	(segment
		(start 184.646062 -57.610502)
		(end 184.825894 -57.790334)
		(width 0.127)
		(layer "In2.Cu")
		(net "XM_DATA_10")
	)
	(segment
		(start 185.293762 -57.502044)
		(end 185.473594 -57.502044)
		(width 0.127)
		(layer "In2.Cu")
		(net "XM_DATA_10")
	)
	(segment
		(start 186.192414 -58.220864)
		(end 186.371992 -58.400442)
		(width 0.127)
		(layer "In2.Cu")
		(net "XM_DATA_10")
	)
	(segment
		(start 186.911234 -58.939684)
		(end 187.090812 -59.119262)
		(width 0.127)
		(layer "In2.Cu")
		(net "XM_DATA_10")
	)
	(segment
		(start 182.999634 -50.399696)
		(end 182.999634 -51.758342)
		(width 0.127)
		(layer "In2.Cu")
		(net "XM_DATA_10")
	)
	(segment
		(start 184.934352 -57.142634)
		(end 184.646062 -57.431178)
		(width 0.127)
		(layer "In2.Cu")
		(net "XM_DATA_10")
	)
	(segment
		(start 187.450222 -59.658504)
		(end 187.630054 -59.658504)
		(width 0.127)
		(layer "In2.Cu")
		(net "XM_DATA_10")
	)
	(segment
		(start 183.674004 -55.702454)
		(end 184.934352 -56.962802)
		(width 0.127)
		(layer "In2.Cu")
		(net "XM_DATA_10")
	)
	(segment
		(start 185.594752 -58.638694)
		(end 186.012582 -58.220864)
		(width 0.127)
		(layer "In2.Cu")
		(net "XM_DATA_10")
	)
	(segment
		(start 187.090812 -59.119262)
		(end 187.090812 -59.299094)
		(width 0.127)
		(layer "In2.Cu")
		(net "XM_DATA_10")
	)
	(segment
		(start 184.934352 -56.962802)
		(end 184.934352 -57.142634)
		(width 0.127)
		(layer "In2.Cu")
		(net "XM_DATA_10")
	)
	(segment
		(start 197.316598 -63.816738)
		(end 197.316598 -67.011804)
		(width 0.127)
		(layer "In2.Cu")
		(net "XM_DATA_10")
	)
	(segment
		(start 191.01308 -60.06592)
		(end 191.678814 -60.731654)
		(width 0.127)
		(layer "In2.Cu")
		(net "XM_DATA_10")
	)
	(segment
		(start 184.825894 -57.790334)
		(end 185.005218 -57.790334)
		(width 0.127)
		(layer "In2.Cu")
		(net "XM_DATA_10")
	)
	(segment
		(start 185.41492 -58.638694)
		(end 185.594752 -58.638694)
		(width 0.127)
		(layer "In2.Cu")
		(net "XM_DATA_10")
	)
	(segment
		(start 186.731402 -58.939684)
		(end 186.911234 -58.939684)
		(width 0.127)
		(layer "In2.Cu")
		(net "XM_DATA_10")
	)
	(segment
		(start 185.954162 -58.998104)
		(end 185.954162 -59.177936)
		(width 0.127)
		(layer "In2.Cu")
		(net "XM_DATA_10")
	)
	(segment
		(start 187.493656 -44.399962)
		(end 186.59983 -44.399962)
		(width 0.127)
		(layer "F.Cu")
		(net "XM_DATA_1")
	)
	(segment
		(start 187.541408 -44.35221)
		(end 187.493656 -44.399962)
		(width 0.127)
		(layer "F.Cu")
		(net "XM_DATA_1")
	)
	(via
		(at 187.541408 -44.35221)
		(size 0.508)
		(drill 0.254)
		(layers "F.Cu" "B.Cu")
		(net "XM_DATA_1")
	)
	(via
		(at 201.634598 -70.026784)
		(size 0.508)
		(drill 0.254)
		(layers "F.Cu" "B.Cu")
		(net "XM_DATA_1")
	)
	(segment
		(start 203.22032 -70.026784)
		(end 201.634598 -70.026784)
		(width 0.127)
		(layer "B.Cu")
		(net "XM_DATA_1")
	)
	(segment
		(start 200.326498 -60.87999)
		(end 200.326498 -60.207398)
		(width 0.127)
		(layer "In2.Cu")
		(net "XM_DATA_1")
	)
	(segment
		(start 189.222888 -46.693328)
		(end 189.461648 -46.454568)
		(width 0.127)
		(layer "In2.Cu")
		(net "XM_DATA_1")
	)
	(segment
		(start 187.541408 -44.564046)
		(end 187.541408 -44.35221)
		(width 0.127)
		(layer "In2.Cu")
		(net "XM_DATA_1")
	)
	(segment
		(start 190.180468 -47.173388)
		(end 190.180468 -46.993556)
		(width 0.127)
		(layer "In2.Cu")
		(net "XM_DATA_1")
	)
	(segment
		(start 191.428116 -53.278024)
		(end 191.428116 -48.241204)
		(width 0.127)
		(layer "In2.Cu")
		(net "XM_DATA_1")
	)
	(segment
		(start 190.180468 -46.993556)
		(end 190.00089 -46.813978)
		(width 0.127)
		(layer "In2.Cu")
		(net "XM_DATA_1")
	)
	(segment
		(start 202.108308 -65.337944)
		(end 202.108308 -63.581026)
		(width 0.127)
		(layer "In2.Cu")
		(net "XM_DATA_1")
	)
	(segment
		(start 190.00089 -46.813978)
		(end 189.821058 -46.813978)
		(width 0.127)
		(layer "In2.Cu")
		(net "XM_DATA_1")
	)
	(segment
		(start 190.71971 -47.532798)
		(end 190.539878 -47.532798)
		(width 0.127)
		(layer "In2.Cu")
		(net "XM_DATA_1")
	)
	(segment
		(start 190.121286 -47.771558)
		(end 189.941708 -47.59198)
		(width 0.127)
		(layer "In2.Cu")
		(net "XM_DATA_1")
	)
	(segment
		(start 189.821058 -46.813978)
		(end 189.582298 -47.052738)
		(width 0.127)
		(layer "In2.Cu")
		(net "XM_DATA_1")
	)
	(segment
		(start 201.791316 -68.519294)
		(end 201.46137 -68.519294)
		(width 0.127)
		(layer "In2.Cu")
		(net "XM_DATA_1")
	)
	(segment
		(start 201.164698 -68.222622)
		(end 201.164698 -66.281554)
		(width 0.127)
		(layer "In2.Cu")
		(net "XM_DATA_1")
	)
	(segment
		(start 188.796168 -45.609256)
		(end 188.586618 -45.609256)
		(width 0.127)
		(layer "In2.Cu")
		(net "XM_DATA_1")
	)
	(segment
		(start 201.46137 -68.519294)
		(end 201.164698 -68.222622)
		(width 0.127)
		(layer "In2.Cu")
		(net "XM_DATA_1")
	)
	(segment
		(start 190.301118 -47.771558)
		(end 190.121286 -47.771558)
		(width 0.127)
		(layer "In2.Cu")
		(net "XM_DATA_1")
	)
	(segment
		(start 202.104498 -69.556884)
		(end 202.104498 -68.832476)
		(width 0.127)
		(layer "In2.Cu")
		(net "XM_DATA_1")
	)
	(segment
		(start 189.461648 -46.454568)
		(end 189.461648 -46.274736)
		(width 0.127)
		(layer "In2.Cu")
		(net "XM_DATA_1")
	)
	(segment
		(start 201.164698 -66.281554)
		(end 202.108308 -65.337944)
		(width 0.127)
		(layer "In2.Cu")
		(net "XM_DATA_1")
	)
	(segment
		(start 201.634598 -70.026784)
		(end 202.104498 -69.556884)
		(width 0.127)
		(layer "In2.Cu")
		(net "XM_DATA_1")
	)
	(segment
		(start 189.222888 -46.87316)
		(end 189.222888 -46.693328)
		(width 0.127)
		(layer "In2.Cu")
		(net "XM_DATA_1")
	)
	(segment
		(start 188.586618 -45.609256)
		(end 187.541408 -44.564046)
		(width 0.127)
		(layer "In2.Cu")
		(net "XM_DATA_1")
	)
	(segment
		(start 189.582298 -47.052738)
		(end 189.402466 -47.052738)
		(width 0.127)
		(layer "In2.Cu")
		(net "XM_DATA_1")
	)
	(segment
		(start 201.57694 -63.049658)
		(end 201.57694 -62.130432)
		(width 0.127)
		(layer "In2.Cu")
		(net "XM_DATA_1")
	)
	(segment
		(start 191.428116 -48.241204)
		(end 190.71971 -47.532798)
		(width 0.127)
		(layer "In2.Cu")
		(net "XM_DATA_1")
	)
	(segment
		(start 202.104498 -68.832476)
		(end 201.791316 -68.519294)
		(width 0.127)
		(layer "In2.Cu")
		(net "XM_DATA_1")
	)
	(segment
		(start 189.941708 -47.412148)
		(end 190.180468 -47.173388)
		(width 0.127)
		(layer "In2.Cu")
		(net "XM_DATA_1")
	)
	(segment
		(start 194.073272 -55.92318)
		(end 191.428116 -53.278024)
		(width 0.127)
		(layer "In2.Cu")
		(net "XM_DATA_1")
	)
	(segment
		(start 189.461648 -46.274736)
		(end 188.796168 -45.609256)
		(width 0.127)
		(layer "In2.Cu")
		(net "XM_DATA_1")
	)
	(segment
		(start 189.941708 -47.59198)
		(end 189.941708 -47.412148)
		(width 0.127)
		(layer "In2.Cu")
		(net "XM_DATA_1")
	)
	(segment
		(start 190.539878 -47.532798)
		(end 190.301118 -47.771558)
		(width 0.127)
		(layer "In2.Cu")
		(net "XM_DATA_1")
	)
	(segment
		(start 202.108308 -63.581026)
		(end 201.57694 -63.049658)
		(width 0.127)
		(layer "In2.Cu")
		(net "XM_DATA_1")
	)
	(segment
		(start 189.402466 -47.052738)
		(end 189.222888 -46.87316)
		(width 0.127)
		(layer "In2.Cu")
		(net "XM_DATA_1")
	)
	(segment
		(start 196.04228 -55.92318)
		(end 194.073272 -55.92318)
		(width 0.127)
		(layer "In2.Cu")
		(net "XM_DATA_1")
	)
	(segment
		(start 201.57694 -62.130432)
		(end 200.326498 -60.87999)
		(width 0.127)
		(layer "In2.Cu")
		(net "XM_DATA_1")
	)
	(segment
		(start 200.326498 -60.207398)
		(end 196.04228 -55.92318)
		(width 0.127)
		(layer "In2.Cu")
		(net "XM_DATA_1")
	)
	(segment
		(start 184.999884 -45.999908)
		(end 185.399934 -45.599858)
		(width 0.127)
		(layer "F.Cu")
		(net "XM_DATA_0")
	)
	(via
		(at 185.399934 -45.599858)
		(size 0.508)
		(drill 0.254)
		(layers "F.Cu" "B.Cu")
		(net "XM_DATA_0")
	)
	(via
		(at 201.634598 -71.027544)
		(size 0.508)
		(drill 0.254)
		(layers "F.Cu" "B.Cu")
		(net "XM_DATA_0")
	)
	(segment
		(start 203.22032 -71.027544)
		(end 201.634598 -71.027544)
		(width 0.127)
		(layer "B.Cu")
		(net "XM_DATA_0")
	)
	(segment
		(start 190.776352 -58.506868)
		(end 194.162426 -58.506868)
		(width 0.127)
		(layer "In2.Cu")
		(net "XM_DATA_0")
	)
	(segment
		(start 200.640188 -70.519544)
		(end 200.227184 -70.519544)
		(width 0.127)
		(layer "In2.Cu")
		(net "XM_DATA_0")
	)
	(segment
		(start 186.32551 -46.525434)
		(end 186.32551 -52.783232)
		(width 0.127)
		(layer "In2.Cu")
		(net "XM_DATA_0")
	)
	(segment
		(start 199.17664 -66.520314)
		(end 199.941434 -66.520314)
		(width 0.127)
		(layer "In2.Cu")
		(net "XM_DATA_0")
	)
	(segment
		(start 186.74461 -53.202332)
		(end 186.74461 -54.475126)
		(width 0.127)
		(layer "In2.Cu")
		(net "XM_DATA_0")
	)
	(segment
		(start 200.227184 -70.519544)
		(end 200.100184 -70.646544)
		(width 0.127)
		(layer "In2.Cu")
		(net "XM_DATA_0")
	)
	(segment
		(start 200.100184 -70.900544)
		(end 200.227184 -71.027544)
		(width 0.127)
		(layer "In2.Cu")
		(net "XM_DATA_0")
	)
	(segment
		(start 200.767188 -70.392544)
		(end 200.640188 -70.519544)
		(width 0.127)
		(layer "In2.Cu")
		(net "XM_DATA_0")
	)
	(segment
		(start 194.162426 -58.506868)
		(end 198.840598 -63.18504)
		(width 0.127)
		(layer "In2.Cu")
		(net "XM_DATA_0")
	)
	(segment
		(start 199.941434 -66.520314)
		(end 200.068434 -66.647314)
		(width 0.127)
		(layer "In2.Cu")
		(net "XM_DATA_0")
	)
	(segment
		(start 200.640188 -70.011544)
		(end 200.767188 -70.138544)
		(width 0.127)
		(layer "In2.Cu")
		(net "XM_DATA_0")
	)
	(segment
		(start 200.068434 -66.647314)
		(end 200.068434 -69.884544)
		(width 0.127)
		(layer "In2.Cu")
		(net "XM_DATA_0")
	)
	(segment
		(start 200.068434 -69.884544)
		(end 200.195434 -70.011544)
		(width 0.127)
		(layer "In2.Cu")
		(net "XM_DATA_0")
	)
	(segment
		(start 200.767188 -70.138544)
		(end 200.767188 -70.392544)
		(width 0.127)
		(layer "In2.Cu")
		(net "XM_DATA_0")
	)
	(segment
		(start 186.32551 -52.783232)
		(end 186.74461 -53.202332)
		(width 0.127)
		(layer "In2.Cu")
		(net "XM_DATA_0")
	)
	(segment
		(start 198.840598 -63.18504)
		(end 198.840598 -66.184272)
		(width 0.127)
		(layer "In2.Cu")
		(net "XM_DATA_0")
	)
	(segment
		(start 200.227184 -71.027544)
		(end 201.634598 -71.027544)
		(width 0.127)
		(layer "In2.Cu")
		(net "XM_DATA_0")
	)
	(segment
		(start 186.74461 -54.475126)
		(end 190.776352 -58.506868)
		(width 0.127)
		(layer "In2.Cu")
		(net "XM_DATA_0")
	)
	(segment
		(start 200.100184 -70.646544)
		(end 200.100184 -70.900544)
		(width 0.127)
		(layer "In2.Cu")
		(net "XM_DATA_0")
	)
	(segment
		(start 198.840598 -66.184272)
		(end 199.17664 -66.520314)
		(width 0.127)
		(layer "In2.Cu")
		(net "XM_DATA_0")
	)
	(segment
		(start 200.195434 -70.011544)
		(end 200.640188 -70.011544)
		(width 0.127)
		(layer "In2.Cu")
		(net "XM_DATA_0")
	)
	(segment
		(start 185.399934 -45.599858)
		(end 186.32551 -46.525434)
		(width 0.127)
		(layer "In2.Cu")
		(net "XM_DATA_0")
	)
	(segment
		(start 181.03088 -57.52084)
		(end 178.816 -55.30596)
		(width 0.127)
		(layer "F.Cu")
		(net "XM_CS0_N")
	)
	(segment
		(start 181.03088 -59.530488)
		(end 181.03088 -58.335164)
		(width 0.127)
		(layer "F.Cu")
		(net "XM_CS0_N")
	)
	(segment
		(start 177.8 -50.809398)
		(end 177.8 -50.8)
		(width 0.127)
		(layer "F.Cu")
		(net "XM_CS0_N")
	)
	(segment
		(start 178.683158 -52.50053)
		(end 178.1429 -51.960272)
		(width 0.127)
		(layer "F.Cu")
		(net "XM_CS0_N")
	)
	(segment
		(start 178.683158 -54.223158)
		(end 178.683158 -52.50053)
		(width 0.127)
		(layer "F.Cu")
		(net "XM_CS0_N")
	)
	(segment
		(start 181.03088 -58.335164)
		(end 181.03088 -57.52084)
		(width 0.127)
		(layer "F.Cu")
		(net "XM_CS0_N")
	)
	(segment
		(start 178.816 -54.356)
		(end 178.683158 -54.223158)
		(width 0.127)
		(layer "F.Cu")
		(net "XM_CS0_N")
	)
	(segment
		(start 178.1429 -51.960272)
		(end 178.1429 -51.152298)
		(width 0.127)
		(layer "F.Cu")
		(net "XM_CS0_N")
	)
	(segment
		(start 178.1429 -51.152298)
		(end 177.8 -50.809398)
		(width 0.127)
		(layer "F.Cu")
		(net "XM_CS0_N")
	)
	(segment
		(start 178.816 -55.30596)
		(end 178.816 -54.356)
		(width 0.127)
		(layer "F.Cu")
		(net "XM_CS0_N")
	)
	(via
		(at 181.03088 -58.335164)
		(size 0.6604)
		(drill 0.3302)
		(layers "F.Cu" "B.Cu")
		(net "XM_CS0_N")
	)
	(segment
		(start 180.999892 -49.9999)
		(end 181.399942 -50.39995)
		(width 0.127)
		(layer "F.Cu")
		(net "XM_CLE")
	)
	(via
		(at 181.399942 -50.39995)
		(size 0.508)
		(drill 0.254)
		(layers "F.Cu" "B.Cu")
		(net "XM_CLE")
	)
	(segment
		(start 180.514498 -51.285394)
		(end 180.514498 -51.451256)
		(width 0.127)
		(layer "B.Cu")
		(net "XM_CLE")
	)
	(segment
		(start 181.399942 -50.39995)
		(end 180.514498 -51.285394)
		(width 0.127)
		(layer "B.Cu")
		(net "XM_CLE")
	)
	(segment
		(start 183.043322 -51.156616)
		(end 183.399938 -50.8)
		(width 0.127)
		(layer "F.Cu")
		(net "XM_ALE")
	)
	(segment
		(start 183.043322 -52.531772)
		(end 183.043322 -51.156616)
		(width 0.127)
		(layer "F.Cu")
		(net "XM_ALE")
	)
	(segment
		(start 182.970678 -52.604416)
		(end 183.043322 -52.531772)
		(width 0.127)
		(layer "F.Cu")
		(net "XM_ALE")
	)
	(via
		(at 182.970678 -52.604416)
		(size 0.508)
		(drill 0.254)
		(layers "F.Cu" "B.Cu")
		(net "XM_ALE")
	)
	(segment
		(start 183.320436 -52.254658)
		(end 184.36717 -52.254658)
		(width 0.127)
		(layer "B.Cu")
		(net "XM_ALE")
	)
	(segment
		(start 184.36717 -52.254658)
		(end 184.412128 -52.299616)
		(width 0.127)
		(layer "B.Cu")
		(net "XM_ALE")
	)
	(segment
		(start 182.970678 -52.604416)
		(end 183.320436 -52.254658)
		(width 0.127)
		(layer "B.Cu")
		(net "XM_ALE")
	)
	(segment
		(start 184.999884 -49.1998)
		(end 185.39968 -48.800004)
		(width 0.127)
		(layer "F.Cu")
		(net "XM_ADDR_9")
	)
	(via
		(at 190.930022 -65.92316)
		(size 0.508)
		(drill 0.254)
		(layers "F.Cu" "B.Cu")
		(net "XM_ADDR_9")
	)
	(via
		(at 185.39968 -48.800004)
		(size 0.508)
		(drill 0.254)
		(layers "F.Cu" "B.Cu")
		(net "XM_ADDR_9")
	)
	(segment
		(start 190.930022 -65.92316)
		(end 186.115706 -65.92316)
		(width 0.127)
		(layer "B.Cu")
		(net "XM_ADDR_9")
	)
	(segment
		(start 185.21934 -65.026794)
		(end 183.99252 -65.026794)
		(width 0.127)
		(layer "B.Cu")
		(net "XM_ADDR_9")
	)
	(segment
		(start 186.115706 -65.92316)
		(end 185.21934 -65.026794)
		(width 0.127)
		(layer "B.Cu")
		(net "XM_ADDR_9")
	)
	(segment
		(start 192.927732 -63.526162)
		(end 192.927732 -68.617846)
		(width 0.127)
		(layer "In5.Cu")
		(net "XM_ADDR_9")
	)
	(segment
		(start 192.398396 -68.109846)
		(end 192.398396 -67.855846)
		(width 0.127)
		(layer "In5.Cu")
		(net "XM_ADDR_9")
	)
	(segment
		(start 192.25006 -66.712846)
		(end 191.057022 -66.712846)
		(width 0.127)
		(layer "In5.Cu")
		(net "XM_ADDR_9")
	)
	(segment
		(start 191.911732 -58.820558)
		(end 191.911732 -62.510162)
		(width 0.127)
		(layer "In5.Cu")
		(net "XM_ADDR_9")
	)
	(segment
		(start 190.930022 -66.585846)
		(end 190.930022 -65.92316)
		(width 0.127)
		(layer "In5.Cu")
		(net "XM_ADDR_9")
	)
	(segment
		(start 190.422022 -68.363846)
		(end 190.549022 -68.236846)
		(width 0.127)
		(layer "In5.Cu")
		(net "XM_ADDR_9")
	)
	(segment
		(start 191.057022 -66.712846)
		(end 190.930022 -66.585846)
		(width 0.127)
		(layer "In5.Cu")
		(net "XM_ADDR_9")
	)
	(segment
		(start 192.927732 -68.617846)
		(end 192.800732 -68.744846)
		(width 0.127)
		(layer "In5.Cu")
		(net "XM_ADDR_9")
	)
	(segment
		(start 192.800732 -68.744846)
		(end 190.549022 -68.744846)
		(width 0.127)
		(layer "In5.Cu")
		(net "XM_ADDR_9")
	)
	(segment
		(start 190.549022 -68.236846)
		(end 192.271396 -68.236846)
		(width 0.127)
		(layer "In5.Cu")
		(net "XM_ADDR_9")
	)
	(segment
		(start 190.422022 -68.617846)
		(end 190.422022 -68.363846)
		(width 0.127)
		(layer "In5.Cu")
		(net "XM_ADDR_9")
	)
	(segment
		(start 190.422022 -67.601846)
		(end 190.422022 -67.347846)
		(width 0.127)
		(layer "In5.Cu")
		(net "XM_ADDR_9")
	)
	(segment
		(start 190.549022 -67.728846)
		(end 190.422022 -67.601846)
		(width 0.127)
		(layer "In5.Cu")
		(net "XM_ADDR_9")
	)
	(segment
		(start 190.422022 -67.347846)
		(end 190.549022 -67.220846)
		(width 0.127)
		(layer "In5.Cu")
		(net "XM_ADDR_9")
	)
	(segment
		(start 188.772292 -49.874424)
		(end 188.772292 -51.520598)
		(width 0.127)
		(layer "In5.Cu")
		(net "XM_ADDR_9")
	)
	(segment
		(start 192.271396 -67.728846)
		(end 190.549022 -67.728846)
		(width 0.127)
		(layer "In5.Cu")
		(net "XM_ADDR_9")
	)
	(segment
		(start 192.37706 -66.839846)
		(end 192.25006 -66.712846)
		(width 0.127)
		(layer "In5.Cu")
		(net "XM_ADDR_9")
	)
	(segment
		(start 189.697106 -54.040532)
		(end 189.697106 -56.605932)
		(width 0.127)
		(layer "In5.Cu")
		(net "XM_ADDR_9")
	)
	(segment
		(start 190.549022 -68.744846)
		(end 190.422022 -68.617846)
		(width 0.127)
		(layer "In5.Cu")
		(net "XM_ADDR_9")
	)
	(segment
		(start 188.772292 -51.520598)
		(end 189.164214 -51.91252)
		(width 0.127)
		(layer "In5.Cu")
		(net "XM_ADDR_9")
	)
	(segment
		(start 189.164214 -51.91252)
		(end 189.164214 -53.50764)
		(width 0.127)
		(layer "In5.Cu")
		(net "XM_ADDR_9")
	)
	(segment
		(start 189.164214 -53.50764)
		(end 189.697106 -54.040532)
		(width 0.127)
		(layer "In5.Cu")
		(net "XM_ADDR_9")
	)
	(segment
		(start 191.911732 -62.510162)
		(end 192.927732 -63.526162)
		(width 0.127)
		(layer "In5.Cu")
		(net "XM_ADDR_9")
	)
	(segment
		(start 192.398396 -67.855846)
		(end 192.271396 -67.728846)
		(width 0.127)
		(layer "In5.Cu")
		(net "XM_ADDR_9")
	)
	(segment
		(start 190.549022 -67.220846)
		(end 192.25006 -67.220846)
		(width 0.127)
		(layer "In5.Cu")
		(net "XM_ADDR_9")
	)
	(segment
		(start 185.39968 -48.800004)
		(end 185.47715 -48.877474)
		(width 0.127)
		(layer "In5.Cu")
		(net "XM_ADDR_9")
	)
	(segment
		(start 192.25006 -67.220846)
		(end 192.37706 -67.093846)
		(width 0.127)
		(layer "In5.Cu")
		(net "XM_ADDR_9")
	)
	(segment
		(start 192.37706 -67.093846)
		(end 192.37706 -66.839846)
		(width 0.127)
		(layer "In5.Cu")
		(net "XM_ADDR_9")
	)
	(segment
		(start 192.271396 -68.236846)
		(end 192.398396 -68.109846)
		(width 0.127)
		(layer "In5.Cu")
		(net "XM_ADDR_9")
	)
	(segment
		(start 185.47715 -48.877474)
		(end 187.775342 -48.877474)
		(width 0.127)
		(layer "In5.Cu")
		(net "XM_ADDR_9")
	)
	(segment
		(start 189.697106 -56.605932)
		(end 191.911732 -58.820558)
		(width 0.127)
		(layer "In5.Cu")
		(net "XM_ADDR_9")
	)
	(segment
		(start 187.775342 -48.877474)
		(end 188.772292 -49.874424)
		(width 0.127)
		(layer "In5.Cu")
		(net "XM_ADDR_9")
	)
	(segment
		(start 185.799984 -51.078892)
		(end 186.32551 -51.604418)
		(width 0.127)
		(layer "F.Cu")
		(net "XM_ADDR_8")
	)
	(segment
		(start 189.841378 -53.95214)
		(end 190.296038 -54.4068)
		(width 0.127)
		(layer "F.Cu")
		(net "XM_ADDR_8")
	)
	(segment
		(start 186.32551 -53.386736)
		(end 186.890914 -53.95214)
		(width 0.127)
		(layer "F.Cu")
		(net "XM_ADDR_8")
	)
	(segment
		(start 186.890914 -53.95214)
		(end 189.841378 -53.95214)
		(width 0.127)
		(layer "F.Cu")
		(net "XM_ADDR_8")
	)
	(segment
		(start 190.296038 -54.4068)
		(end 191.40932 -54.4068)
		(width 0.127)
		(layer "F.Cu")
		(net "XM_ADDR_8")
	)
	(segment
		(start 185.799984 -50.8)
		(end 185.799984 -51.078892)
		(width 0.127)
		(layer "F.Cu")
		(net "XM_ADDR_8")
	)
	(segment
		(start 186.32551 -51.604418)
		(end 186.32551 -53.386736)
		(width 0.127)
		(layer "F.Cu")
		(net "XM_ADDR_8")
	)
	(via
		(at 186.598052 -70.026784)
		(size 0.508)
		(drill 0.254)
		(layers "F.Cu" "B.Cu")
		(net "XM_ADDR_8")
	)
	(via
		(at 186.32551 -53.386736)
		(size 0.508)
		(drill 0.254)
		(layers "F.Cu" "B.Cu")
		(net "XM_ADDR_8")
	)
	(segment
		(start 186.293252 -69.721984)
		(end 186.598052 -70.026784)
		(width 0.127)
		(layer "B.Cu")
		(net "XM_ADDR_8")
	)
	(segment
		(start 185.334656 -70.026784)
		(end 185.639456 -69.721984)
		(width 0.127)
		(layer "B.Cu")
		(net "XM_ADDR_8")
	)
	(segment
		(start 183.99252 -70.026784)
		(end 185.334656 -70.026784)
		(width 0.127)
		(layer "B.Cu")
		(net "XM_ADDR_8")
	)
	(segment
		(start 185.639456 -69.721984)
		(end 186.293252 -69.721984)
		(width 0.127)
		(layer "B.Cu")
		(net "XM_ADDR_8")
	)
	(segment
		(start 185.126376 -57.475628)
		(end 184.553098 -58.048906)
		(width 0.127)
		(layer "In5.Cu")
		(net "XM_ADDR_8")
	)
	(segment
		(start 184.934098 -70.01891)
		(end 185.061098 -69.89191)
		(width 0.127)
		(layer "In5.Cu")
		(net "XM_ADDR_8")
	)
	(segment
		(start 184.100724 -59.982608)
		(end 184.553098 -60.434982)
		(width 0.127)
		(layer "In5.Cu")
		(net "XM_ADDR_8")
	)
	(segment
		(start 185.569098 -69.899784)
		(end 185.696098 -70.026784)
		(width 0.127)
		(layer "In5.Cu")
		(net "XM_ADDR_8")
	)
	(segment
		(start 184.553098 -60.434982)
		(end 184.553098 -69.89191)
		(width 0.127)
		(layer "In5.Cu")
		(net "XM_ADDR_8")
	)
	(segment
		(start 184.553098 -59.104784)
		(end 184.100724 -59.557158)
		(width 0.127)
		(layer "In5.Cu")
		(net "XM_ADDR_8")
	)
	(segment
		(start 185.696098 -70.026784)
		(end 186.598052 -70.026784)
		(width 0.127)
		(layer "In5.Cu")
		(net "XM_ADDR_8")
	)
	(segment
		(start 184.100724 -59.557158)
		(end 184.100724 -59.982608)
		(width 0.127)
		(layer "In5.Cu")
		(net "XM_ADDR_8")
	)
	(segment
		(start 184.553098 -69.89191)
		(end 184.680098 -70.01891)
		(width 0.127)
		(layer "In5.Cu")
		(net "XM_ADDR_8")
	)
	(segment
		(start 185.442098 -60.869068)
		(end 185.569098 -60.996068)
		(width 0.127)
		(layer "In5.Cu")
		(net "XM_ADDR_8")
	)
	(segment
		(start 185.569098 -56.378602)
		(end 185.126376 -56.821324)
		(width 0.127)
		(layer "In5.Cu")
		(net "XM_ADDR_8")
	)
	(segment
		(start 185.061098 -69.89191)
		(end 185.061098 -60.996068)
		(width 0.127)
		(layer "In5.Cu")
		(net "XM_ADDR_8")
	)
	(segment
		(start 184.553098 -58.048906)
		(end 184.553098 -59.104784)
		(width 0.127)
		(layer "In5.Cu")
		(net "XM_ADDR_8")
	)
	(segment
		(start 184.680098 -70.01891)
		(end 184.934098 -70.01891)
		(width 0.127)
		(layer "In5.Cu")
		(net "XM_ADDR_8")
	)
	(segment
		(start 186.32551 -54.211474)
		(end 185.569098 -54.967886)
		(width 0.127)
		(layer "In5.Cu")
		(net "XM_ADDR_8")
	)
	(segment
		(start 185.126376 -56.821324)
		(end 185.126376 -57.475628)
		(width 0.127)
		(layer "In5.Cu")
		(net "XM_ADDR_8")
	)
	(segment
		(start 185.569098 -54.967886)
		(end 185.569098 -56.378602)
		(width 0.127)
		(layer "In5.Cu")
		(net "XM_ADDR_8")
	)
	(segment
		(start 185.569098 -60.996068)
		(end 185.569098 -69.899784)
		(width 0.127)
		(layer "In5.Cu")
		(net "XM_ADDR_8")
	)
	(segment
		(start 185.188098 -60.869068)
		(end 185.442098 -60.869068)
		(width 0.127)
		(layer "In5.Cu")
		(net "XM_ADDR_8")
	)
	(segment
		(start 185.061098 -60.996068)
		(end 185.188098 -60.869068)
		(width 0.127)
		(layer "In5.Cu")
		(net "XM_ADDR_8")
	)
	(segment
		(start 186.32551 -53.386736)
		(end 186.32551 -54.211474)
		(width 0.127)
		(layer "In5.Cu")
		(net "XM_ADDR_8")
	)
	(segment
		(start 186.860434 -51.060604)
		(end 186.860434 -51.539648)
		(width 0.127)
		(layer "F.Cu")
		(net "XM_ADDR_7")
	)
	(segment
		(start 187.695586 -52.3748)
		(end 191.40932 -52.3748)
		(width 0.127)
		(layer "F.Cu")
		(net "XM_ADDR_7")
	)
	(segment
		(start 186.860434 -51.539648)
		(end 187.665106 -52.34432)
		(width 0.127)
		(layer "F.Cu")
		(net "XM_ADDR_7")
	)
	(segment
		(start 187.665106 -52.34432)
		(end 187.695586 -52.3748)
		(width 0.127)
		(layer "F.Cu")
		(net "XM_ADDR_7")
	)
	(segment
		(start 186.59983 -50.8)
		(end 186.860434 -51.060604)
		(width 0.127)
		(layer "F.Cu")
		(net "XM_ADDR_7")
	)
	(via
		(at 187.665106 -52.34432)
		(size 0.508)
		(drill 0.254)
		(layers "F.Cu" "B.Cu")
		(net "XM_ADDR_7")
	)
	(via
		(at 187.786772 -72.027034)
		(size 0.508)
		(drill 0.254)
		(layers "F.Cu" "B.Cu")
		(net "XM_ADDR_7")
	)
	(segment
		(start 186.358784 -71.021194)
		(end 186.780932 -71.021194)
		(width 0.127)
		(layer "B.Cu")
		(net "XM_ADDR_7")
	)
	(segment
		(start 185.864754 -70.527164)
		(end 186.358784 -71.021194)
		(width 0.127)
		(layer "B.Cu")
		(net "XM_ADDR_7")
	)
	(segment
		(start 186.780932 -71.021194)
		(end 187.786772 -72.027034)
		(width 0.127)
		(layer "B.Cu")
		(net "XM_ADDR_7")
	)
	(segment
		(start 183.99252 -70.527164)
		(end 185.864754 -70.527164)
		(width 0.127)
		(layer "B.Cu")
		(net "XM_ADDR_7")
	)
	(segment
		(start 189.046104 -74.880216)
		(end 188.919104 -74.753216)
		(width 0.127)
		(layer "In5.Cu")
		(net "XM_ADDR_7")
	)
	(segment
		(start 188.294772 -72.154034)
		(end 188.294772 -76.277216)
		(width 0.127)
		(layer "In5.Cu")
		(net "XM_ADDR_7")
	)
	(segment
		(start 189.046104 -73.864216)
		(end 188.919104 -73.737216)
		(width 0.127)
		(layer "In5.Cu")
		(net "XM_ADDR_7")
	)
	(segment
		(start 188.919104 -74.753216)
		(end 188.919104 -74.499216)
		(width 0.127)
		(layer "In5.Cu")
		(net "XM_ADDR_7")
	)
	(segment
		(start 189.54242 -74.372216)
		(end 189.66942 -74.245216)
		(width 0.127)
		(layer "In5.Cu")
		(net "XM_ADDR_7")
	)
	(segment
		(start 188.802772 -70.767194)
		(end 188.675772 -70.640194)
		(width 0.127)
		(layer "In5.Cu")
		(net "XM_ADDR_7")
	)
	(segment
		(start 187.665106 -56.111394)
		(end 187.665106 -52.34432)
		(width 0.127)
		(layer "In5.Cu")
		(net "XM_ADDR_7")
	)
	(segment
		(start 186.911234 -63.660782)
		(end 186.911234 -60.133992)
		(width 0.127)
		(layer "In5.Cu")
		(net "XM_ADDR_7")
	)
	(segment
		(start 188.167772 -71.227696)
		(end 187.913772 -71.227696)
		(width 0.127)
		(layer "In5.Cu")
		(net "XM_ADDR_7")
	)
	(segment
		(start 189.046104 -75.896216)
		(end 188.919104 -75.769216)
		(width 0.127)
		(layer "In5.Cu")
		(net "XM_ADDR_7")
	)
	(segment
		(start 188.919104 -75.769216)
		(end 188.919104 -75.515216)
		(width 0.127)
		(layer "In5.Cu")
		(net "XM_ADDR_7")
	)
	(segment
		(start 189.54242 -76.404216)
		(end 189.66942 -76.277216)
		(width 0.127)
		(layer "In5.Cu")
		(net "XM_ADDR_7")
	)
	(segment
		(start 188.294772 -76.277216)
		(end 188.421772 -76.404216)
		(width 0.127)
		(layer "In5.Cu")
		(net "XM_ADDR_7")
	)
	(segment
		(start 188.167772 -72.027034)
		(end 188.294772 -72.154034)
		(width 0.127)
		(layer "In5.Cu")
		(net "XM_ADDR_7")
	)
	(segment
		(start 189.54242 -72.340216)
		(end 189.66942 -72.213216)
		(width 0.127)
		(layer "In5.Cu")
		(net "XM_ADDR_7")
	)
	(segment
		(start 189.66942 -73.229216)
		(end 189.66942 -72.975216)
		(width 0.127)
		(layer "In5.Cu")
		(net "XM_ADDR_7")
	)
	(segment
		(start 188.294772 -70.767194)
		(end 188.294772 -71.100696)
		(width 0.127)
		(layer "In5.Cu")
		(net "XM_ADDR_7")
	)
	(segment
		(start 189.66942 -73.991216)
		(end 189.54242 -73.864216)
		(width 0.127)
		(layer "In5.Cu")
		(net "XM_ADDR_7")
	)
	(segment
		(start 188.919104 -72.721216)
		(end 188.919104 -72.467216)
		(width 0.127)
		(layer "In5.Cu")
		(net "XM_ADDR_7")
	)
	(segment
		(start 189.046104 -73.356216)
		(end 189.54242 -73.356216)
		(width 0.127)
		(layer "In5.Cu")
		(net "XM_ADDR_7")
	)
	(segment
		(start 187.786772 -72.027034)
		(end 188.167772 -72.027034)
		(width 0.127)
		(layer "In5.Cu")
		(net "XM_ADDR_7")
	)
	(segment
		(start 188.675772 -70.640194)
		(end 188.421772 -70.640194)
		(width 0.127)
		(layer "In5.Cu")
		(net "XM_ADDR_7")
	)
	(segment
		(start 187.786772 -71.100696)
		(end 187.786772 -64.53632)
		(width 0.127)
		(layer "In5.Cu")
		(net "XM_ADDR_7")
	)
	(segment
		(start 188.929772 -71.832216)
		(end 188.802772 -71.705216)
		(width 0.127)
		(layer "In5.Cu")
		(net "XM_ADDR_7")
	)
	(segment
		(start 189.66942 -75.007216)
		(end 189.54242 -74.880216)
		(width 0.127)
		(layer "In5.Cu")
		(net "XM_ADDR_7")
	)
	(segment
		(start 189.54242 -73.356216)
		(end 189.66942 -73.229216)
		(width 0.127)
		(layer "In5.Cu")
		(net "XM_ADDR_7")
	)
	(segment
		(start 189.54242 -74.880216)
		(end 189.046104 -74.880216)
		(width 0.127)
		(layer "In5.Cu")
		(net "XM_ADDR_7")
	)
	(segment
		(start 188.919104 -75.515216)
		(end 189.046104 -75.388216)
		(width 0.127)
		(layer "In5.Cu")
		(net "XM_ADDR_7")
	)
	(segment
		(start 188.919104 -74.499216)
		(end 189.046104 -74.372216)
		(width 0.127)
		(layer "In5.Cu")
		(net "XM_ADDR_7")
	)
	(segment
		(start 189.54242 -72.848216)
		(end 189.046104 -72.848216)
		(width 0.127)
		(layer "In5.Cu")
		(net "XM_ADDR_7")
	)
	(segment
		(start 189.54242 -71.832216)
		(end 188.929772 -71.832216)
		(width 0.127)
		(layer "In5.Cu")
		(net "XM_ADDR_7")
	)
	(segment
		(start 187.786772 -64.53632)
		(end 186.911234 -63.660782)
		(width 0.127)
		(layer "In5.Cu")
		(net "XM_ADDR_7")
	)
	(segment
		(start 189.66942 -74.245216)
		(end 189.66942 -73.991216)
		(width 0.127)
		(layer "In5.Cu")
		(net "XM_ADDR_7")
	)
	(segment
		(start 186.589162 -59.81192)
		(end 186.589162 -57.187338)
		(width 0.127)
		(layer "In5.Cu")
		(net "XM_ADDR_7")
	)
	(segment
		(start 188.919104 -73.737216)
		(end 188.919104 -73.483216)
		(width 0.127)
		(layer "In5.Cu")
		(net "XM_ADDR_7")
	)
	(segment
		(start 189.046104 -72.340216)
		(end 189.54242 -72.340216)
		(width 0.127)
		(layer "In5.Cu")
		(net "XM_ADDR_7")
	)
	(segment
		(start 189.66942 -76.023216)
		(end 189.54242 -75.896216)
		(width 0.127)
		(layer "In5.Cu")
		(net "XM_ADDR_7")
	)
	(segment
		(start 189.66942 -71.959216)
		(end 189.54242 -71.832216)
		(width 0.127)
		(layer "In5.Cu")
		(net "XM_ADDR_7")
	)
	(segment
		(start 188.421772 -76.404216)
		(end 189.54242 -76.404216)
		(width 0.127)
		(layer "In5.Cu")
		(net "XM_ADDR_7")
	)
	(segment
		(start 189.54242 -75.896216)
		(end 189.046104 -75.896216)
		(width 0.127)
		(layer "In5.Cu")
		(net "XM_ADDR_7")
	)
	(segment
		(start 189.66942 -75.261216)
		(end 189.66942 -75.007216)
		(width 0.127)
		(layer "In5.Cu")
		(net "XM_ADDR_7")
	)
	(segment
		(start 188.802772 -71.705216)
		(end 188.802772 -70.767194)
		(width 0.127)
		(layer "In5.Cu")
		(net "XM_ADDR_7")
	)
	(segment
		(start 188.919104 -73.483216)
		(end 189.046104 -73.356216)
		(width 0.127)
		(layer "In5.Cu")
		(net "XM_ADDR_7")
	)
	(segment
		(start 189.046104 -74.372216)
		(end 189.54242 -74.372216)
		(width 0.127)
		(layer "In5.Cu")
		(net "XM_ADDR_7")
	)
	(segment
		(start 186.589162 -57.187338)
		(end 187.665106 -56.111394)
		(width 0.127)
		(layer "In5.Cu")
		(net "XM_ADDR_7")
	)
	(segment
		(start 189.54242 -75.388216)
		(end 189.66942 -75.261216)
		(width 0.127)
		(layer "In5.Cu")
		(net "XM_ADDR_7")
	)
	(segment
		(start 188.421772 -70.640194)
		(end 188.294772 -70.767194)
		(width 0.127)
		(layer "In5.Cu")
		(net "XM_ADDR_7")
	)
	(segment
		(start 189.046104 -72.848216)
		(end 188.919104 -72.721216)
		(width 0.127)
		(layer "In5.Cu")
		(net "XM_ADDR_7")
	)
	(segment
		(start 189.66942 -72.213216)
		(end 189.66942 -71.959216)
		(width 0.127)
		(layer "In5.Cu")
		(net "XM_ADDR_7")
	)
	(segment
		(start 188.919104 -72.467216)
		(end 189.046104 -72.340216)
		(width 0.127)
		(layer "In5.Cu")
		(net "XM_ADDR_7")
	)
	(segment
		(start 186.911234 -60.133992)
		(end 186.589162 -59.81192)
		(width 0.127)
		(layer "In5.Cu")
		(net "XM_ADDR_7")
	)
	(segment
		(start 189.66942 -72.975216)
		(end 189.54242 -72.848216)
		(width 0.127)
		(layer "In5.Cu")
		(net "XM_ADDR_7")
	)
	(segment
		(start 189.54242 -73.864216)
		(end 189.046104 -73.864216)
		(width 0.127)
		(layer "In5.Cu")
		(net "XM_ADDR_7")
	)
	(segment
		(start 188.294772 -71.100696)
		(end 188.167772 -71.227696)
		(width 0.127)
		(layer "In5.Cu")
		(net "XM_ADDR_7")
	)
	(segment
		(start 189.046104 -75.388216)
		(end 189.54242 -75.388216)
		(width 0.127)
		(layer "In5.Cu")
		(net "XM_ADDR_7")
	)
	(segment
		(start 189.66942 -76.277216)
		(end 189.66942 -76.023216)
		(width 0.127)
		(layer "In5.Cu")
		(net "XM_ADDR_7")
	)
	(segment
		(start 187.913772 -71.227696)
		(end 187.786772 -71.100696)
		(width 0.127)
		(layer "In5.Cu")
		(net "XM_ADDR_7")
	)
	(segment
		(start 187.070492 -54.317392)
		(end 188.8744 -56.1213)
		(width 0.127)
		(layer "F.Cu")
		(net "XM_ADDR_6")
	)
	(segment
		(start 185.200544 -52.211224)
		(end 185.368184 -52.043584)
		(width 0.127)
		(layer "F.Cu")
		(net "XM_ADDR_6")
	)
	(segment
		(start 185.647584 -52.937156)
		(end 185.647584 -53.32984)
		(width 0.127)
		(layer "F.Cu")
		(net "XM_ADDR_6")
	)
	(segment
		(start 185.368184 -52.043584)
		(end 185.368184 -51.408584)
		(width 0.127)
		(layer "F.Cu")
		(net "XM_ADDR_6")
	)
	(segment
		(start 185.200544 -52.490116)
		(end 185.200544 -52.211224)
		(width 0.127)
		(layer "F.Cu")
		(net "XM_ADDR_6")
	)
	(segment
		(start 184.999884 -51.040284)
		(end 184.999884 -50.8)
		(width 0.127)
		(layer "F.Cu")
		(net "XM_ADDR_6")
	)
	(segment
		(start 185.200544 -52.490116)
		(end 185.647584 -52.937156)
		(width 0.127)
		(layer "F.Cu")
		(net "XM_ADDR_6")
	)
	(segment
		(start 185.368184 -51.408584)
		(end 184.999884 -51.040284)
		(width 0.127)
		(layer "F.Cu")
		(net "XM_ADDR_6")
	)
	(segment
		(start 186.635136 -54.317392)
		(end 187.070492 -54.317392)
		(width 0.127)
		(layer "F.Cu")
		(net "XM_ADDR_6")
	)
	(segment
		(start 185.647584 -53.32984)
		(end 186.635136 -54.317392)
		(width 0.127)
		(layer "F.Cu")
		(net "XM_ADDR_6")
	)
	(via
		(at 185.200544 -52.490116)
		(size 0.508)
		(drill 0.254)
		(layers "F.Cu" "B.Cu")
		(net "XM_ADDR_6")
	)
	(via
		(at 185.71337 -71.027544)
		(size 0.508)
		(drill 0.254)
		(layers "F.Cu" "B.Cu")
		(net "XM_ADDR_6")
	)
	(segment
		(start 185.71337 -71.027544)
		(end 183.99252 -71.027544)
		(width 0.127)
		(layer "B.Cu")
		(net "XM_ADDR_6")
	)
	(segment
		(start 184.045098 -58.793888)
		(end 184.045098 -57.717944)
		(width 0.127)
		(layer "In5.Cu")
		(net "XM_ADDR_6")
	)
	(segment
		(start 183.410098 -56.785256)
		(end 183.537098 -56.912256)
		(width 0.127)
		(layer "In5.Cu")
		(net "XM_ADDR_6")
	)
	(segment
		(start 184.045098 -60.787534)
		(end 183.918098 -60.660534)
		(width 0.127)
		(layer "In5.Cu")
		(net "XM_ADDR_6")
	)
	(segment
		(start 183.664098 -60.660534)
		(end 183.537098 -60.787534)
		(width 0.127)
		(layer "In5.Cu")
		(net "XM_ADDR_6")
	)
	(segment
		(start 184.703974 -71.027544)
		(end 184.045098 -70.368668)
		(width 0.127)
		(layer "In5.Cu")
		(net "XM_ADDR_6")
	)
	(segment
		(start 185.71337 -71.027544)
		(end 184.703974 -71.027544)
		(width 0.127)
		(layer "In5.Cu")
		(net "XM_ADDR_6")
	)
	(segment
		(start 184.61101 -55.686706)
		(end 184.48401 -55.559706)
		(width 0.127)
		(layer "In5.Cu")
		(net "XM_ADDR_6")
	)
	(segment
		(start 184.045098 -70.368668)
		(end 184.045098 -60.787534)
		(width 0.127)
		(layer "In5.Cu")
		(net "XM_ADDR_6")
	)
	(segment
		(start 183.156098 -56.785256)
		(end 183.410098 -56.785256)
		(width 0.127)
		(layer "In5.Cu")
		(net "XM_ADDR_6")
	)
	(segment
		(start 185.035444 -56.067706)
		(end 185.035444 -55.813706)
		(width 0.127)
		(layer "In5.Cu")
		(net "XM_ADDR_6")
	)
	(segment
		(start 184.48401 -57.279032)
		(end 184.48401 -56.321706)
		(width 0.127)
		(layer "In5.Cu")
		(net "XM_ADDR_6")
	)
	(segment
		(start 183.918098 -58.920888)
		(end 184.045098 -58.793888)
		(width 0.127)
		(layer "In5.Cu")
		(net "XM_ADDR_6")
	)
	(segment
		(start 183.410098 -66.820034)
		(end 183.156098 -66.820034)
		(width 0.127)
		(layer "In5.Cu")
		(net "XM_ADDR_6")
	)
	(segment
		(start 183.029098 -56.912256)
		(end 183.156098 -56.785256)
		(width 0.127)
		(layer "In5.Cu")
		(net "XM_ADDR_6")
	)
	(segment
		(start 184.908444 -56.194706)
		(end 185.035444 -56.067706)
		(width 0.127)
		(layer "In5.Cu")
		(net "XM_ADDR_6")
	)
	(segment
		(start 185.647584 -52.937156)
		(end 185.200544 -52.490116)
		(width 0.127)
		(layer "In5.Cu")
		(net "XM_ADDR_6")
	)
	(segment
		(start 183.537098 -60.787534)
		(end 183.537098 -66.693034)
		(width 0.127)
		(layer "In5.Cu")
		(net "XM_ADDR_6")
	)
	(segment
		(start 183.156098 -66.820034)
		(end 183.029098 -66.693034)
		(width 0.127)
		(layer "In5.Cu")
		(net "XM_ADDR_6")
	)
	(segment
		(start 184.908444 -55.686706)
		(end 184.61101 -55.686706)
		(width 0.127)
		(layer "In5.Cu")
		(net "XM_ADDR_6")
	)
	(segment
		(start 185.035444 -55.813706)
		(end 184.908444 -55.686706)
		(width 0.127)
		(layer "In5.Cu")
		(net "XM_ADDR_6")
	)
	(segment
		(start 184.48401 -55.334408)
		(end 185.647584 -54.170834)
		(width 0.127)
		(layer "In5.Cu")
		(net "XM_ADDR_6")
	)
	(segment
		(start 183.537098 -58.793888)
		(end 183.664098 -58.920888)
		(width 0.127)
		(layer "In5.Cu")
		(net "XM_ADDR_6")
	)
	(segment
		(start 183.664098 -58.920888)
		(end 183.918098 -58.920888)
		(width 0.127)
		(layer "In5.Cu")
		(net "XM_ADDR_6")
	)
	(segment
		(start 184.48401 -55.559706)
		(end 184.48401 -55.334408)
		(width 0.127)
		(layer "In5.Cu")
		(net "XM_ADDR_6")
	)
	(segment
		(start 183.537098 -56.912256)
		(end 183.537098 -58.793888)
		(width 0.127)
		(layer "In5.Cu")
		(net "XM_ADDR_6")
	)
	(segment
		(start 184.61101 -56.194706)
		(end 184.908444 -56.194706)
		(width 0.127)
		(layer "In5.Cu")
		(net "XM_ADDR_6")
	)
	(segment
		(start 184.045098 -57.717944)
		(end 184.48401 -57.279032)
		(width 0.127)
		(layer "In5.Cu")
		(net "XM_ADDR_6")
	)
	(segment
		(start 183.537098 -66.693034)
		(end 183.410098 -66.820034)
		(width 0.127)
		(layer "In5.Cu")
		(net "XM_ADDR_6")
	)
	(segment
		(start 183.029098 -66.693034)
		(end 183.029098 -56.912256)
		(width 0.127)
		(layer "In5.Cu")
		(net "XM_ADDR_6")
	)
	(segment
		(start 184.48401 -56.321706)
		(end 184.61101 -56.194706)
		(width 0.127)
		(layer "In5.Cu")
		(net "XM_ADDR_6")
	)
	(segment
		(start 183.918098 -60.660534)
		(end 183.664098 -60.660534)
		(width 0.127)
		(layer "In5.Cu")
		(net "XM_ADDR_6")
	)
	(segment
		(start 185.647584 -54.170834)
		(end 185.647584 -52.937156)
		(width 0.127)
		(layer "In5.Cu")
		(net "XM_ADDR_6")
	)
	(segment
		(start 187.013088 -52.865528)
		(end 186.606434 -52.458874)
		(width 0.127)
		(layer "F.Cu")
		(net "XM_ADDR_5")
	)
	(segment
		(start 186.606434 -52.458874)
		(end 186.606434 -51.370738)
		(width 0.127)
		(layer "F.Cu")
		(net "XM_ADDR_5")
	)
	(segment
		(start 185.939938 -50.419)
		(end 185.418984 -50.419)
		(width 0.127)
		(layer "F.Cu")
		(net "XM_ADDR_5")
	)
	(segment
		(start 191.40932 -53.3908)
		(end 187.53836 -53.3908)
		(width 0.127)
		(layer "F.Cu")
		(net "XM_ADDR_5")
	)
	(segment
		(start 185.418984 -50.419)
		(end 184.999884 -49.9999)
		(width 0.127)
		(layer "F.Cu")
		(net "XM_ADDR_5")
	)
	(segment
		(start 187.025534 -52.877974)
		(end 187.013088 -52.877974)
		(width 0.127)
		(layer "F.Cu")
		(net "XM_ADDR_5")
	)
	(segment
		(start 187.013088 -52.877974)
		(end 187.013088 -52.865528)
		(width 0.127)
		(layer "F.Cu")
		(net "XM_ADDR_5")
	)
	(segment
		(start 186.2074 -50.971704)
		(end 186.2074 -50.686462)
		(width 0.127)
		(layer "F.Cu")
		(net "XM_ADDR_5")
	)
	(segment
		(start 186.2074 -50.686462)
		(end 185.939938 -50.419)
		(width 0.127)
		(layer "F.Cu")
		(net "XM_ADDR_5")
	)
	(segment
		(start 186.606434 -51.370738)
		(end 186.2074 -50.971704)
		(width 0.127)
		(layer "F.Cu")
		(net "XM_ADDR_5")
	)
	(segment
		(start 187.53836 -53.3908)
		(end 187.025534 -52.877974)
		(width 0.127)
		(layer "F.Cu")
		(net "XM_ADDR_5")
	)
	(via
		(at 187.013088 -52.877974)
		(size 0.508)
		(drill 0.254)
		(layers "F.Cu" "B.Cu")
		(net "XM_ADDR_5")
	)
	(via
		(at 186.770772 -72.027034)
		(size 0.508)
		(drill 0.254)
		(layers "F.Cu" "B.Cu")
		(net "XM_ADDR_5")
	)
	(segment
		(start 186.270392 -71.526654)
		(end 186.770772 -72.027034)
		(width 0.127)
		(layer "B.Cu")
		(net "XM_ADDR_5")
	)
	(segment
		(start 183.99252 -71.526654)
		(end 186.270392 -71.526654)
		(width 0.127)
		(layer "B.Cu")
		(net "XM_ADDR_5")
	)
	(segment
		(start 186.712098 -64.510666)
		(end 186.585098 -64.637666)
		(width 0.127)
		(layer "In5.Cu")
		(net "XM_ADDR_5")
	)
	(segment
		(start 185.061098 -58.259472)
		(end 185.188098 -58.132472)
		(width 0.127)
		(layer "In5.Cu")
		(net "XM_ADDR_5")
	)
	(segment
		(start 186.204098 -69.422264)
		(end 186.077098 -69.295264)
		(width 0.127)
		(layer "In5.Cu")
		(net "XM_ADDR_5")
	)
	(segment
		(start 185.950098 -60.223146)
		(end 185.188098 -60.223146)
		(width 0.127)
		(layer "In5.Cu")
		(net "XM_ADDR_5")
	)
	(segment
		(start 186.077098 -55.178452)
		(end 186.204098 -55.051452)
		(width 0.127)
		(layer "In5.Cu")
		(net "XM_ADDR_5")
	)
	(segment
		(start 185.188098 -60.223146)
		(end 185.061098 -60.096146)
		(width 0.127)
		(layer "In5.Cu")
		(net "XM_ADDR_5")
	)
	(segment
		(start 186.204098 -55.051452)
		(end 186.458098 -55.051452)
		(width 0.127)
		(layer "In5.Cu")
		(net "XM_ADDR_5")
	)
	(segment
		(start 186.585098 -64.637666)
		(end 186.585098 -69.295264)
		(width 0.127)
		(layer "In5.Cu")
		(net "XM_ADDR_5")
	)
	(segment
		(start 186.077098 -58.005472)
		(end 186.077098 -55.178452)
		(width 0.127)
		(layer "In5.Cu")
		(net "XM_ADDR_5")
	)
	(segment
		(start 187.093098 -71.704708)
		(end 187.093098 -64.637666)
		(width 0.127)
		(layer "In5.Cu")
		(net "XM_ADDR_5")
	)
	(segment
		(start 186.712098 -56.083708)
		(end 186.966098 -56.083708)
		(width 0.127)
		(layer "In5.Cu")
		(net "XM_ADDR_5")
	)
	(segment
		(start 186.585098 -55.178452)
		(end 186.585098 -55.956708)
		(width 0.127)
		(layer "In5.Cu")
		(net "XM_ADDR_5")
	)
	(segment
		(start 187.093098 -55.956708)
		(end 187.093098 -52.957984)
		(width 0.127)
		(layer "In5.Cu")
		(net "XM_ADDR_5")
	)
	(segment
		(start 185.940954 -58.640472)
		(end 185.188098 -58.640472)
		(width 0.127)
		(layer "In5.Cu")
		(net "XM_ADDR_5")
	)
	(segment
		(start 185.188098 -59.148472)
		(end 185.940954 -59.148472)
		(width 0.127)
		(layer "In5.Cu")
		(net "XM_ADDR_5")
	)
	(segment
		(start 185.950098 -58.132472)
		(end 186.077098 -58.005472)
		(width 0.127)
		(layer "In5.Cu")
		(net "XM_ADDR_5")
	)
	(segment
		(start 185.188098 -58.132472)
		(end 185.950098 -58.132472)
		(width 0.127)
		(layer "In5.Cu")
		(net "XM_ADDR_5")
	)
	(segment
		(start 186.585098 -69.295264)
		(end 186.458098 -69.422264)
		(width 0.127)
		(layer "In5.Cu")
		(net "XM_ADDR_5")
	)
	(segment
		(start 185.061098 -60.096146)
		(end 185.061098 -59.275472)
		(width 0.127)
		(layer "In5.Cu")
		(net "XM_ADDR_5")
	)
	(segment
		(start 186.458098 -69.422264)
		(end 186.204098 -69.422264)
		(width 0.127)
		(layer "In5.Cu")
		(net "XM_ADDR_5")
	)
	(segment
		(start 185.940954 -59.148472)
		(end 186.067954 -59.021472)
		(width 0.127)
		(layer "In5.Cu")
		(net "XM_ADDR_5")
	)
	(segment
		(start 185.061098 -59.275472)
		(end 185.188098 -59.148472)
		(width 0.127)
		(layer "In5.Cu")
		(net "XM_ADDR_5")
	)
	(segment
		(start 186.077098 -60.350146)
		(end 185.950098 -60.223146)
		(width 0.127)
		(layer "In5.Cu")
		(net "XM_ADDR_5")
	)
	(segment
		(start 185.188098 -58.640472)
		(end 185.061098 -58.513472)
		(width 0.127)
		(layer "In5.Cu")
		(net "XM_ADDR_5")
	)
	(segment
		(start 186.966098 -56.083708)
		(end 187.093098 -55.956708)
		(width 0.127)
		(layer "In5.Cu")
		(net "XM_ADDR_5")
	)
	(segment
		(start 186.770772 -72.011794)
		(end 186.786012 -72.011794)
		(width 0.127)
		(layer "In5.Cu")
		(net "XM_ADDR_5")
	)
	(segment
		(start 185.061098 -58.513472)
		(end 185.061098 -58.259472)
		(width 0.127)
		(layer "In5.Cu")
		(net "XM_ADDR_5")
	)
	(segment
		(start 186.770772 -72.027034)
		(end 186.770772 -72.011794)
		(width 0.127)
		(layer "In5.Cu")
		(net "XM_ADDR_5")
	)
	(segment
		(start 187.093098 -64.637666)
		(end 186.966098 -64.510666)
		(width 0.127)
		(layer "In5.Cu")
		(net "XM_ADDR_5")
	)
	(segment
		(start 186.585098 -55.956708)
		(end 186.712098 -56.083708)
		(width 0.127)
		(layer "In5.Cu")
		(net "XM_ADDR_5")
	)
	(segment
		(start 187.093098 -52.957984)
		(end 187.013088 -52.877974)
		(width 0.127)
		(layer "In5.Cu")
		(net "XM_ADDR_5")
	)
	(segment
		(start 186.786012 -72.011794)
		(end 187.093098 -71.704708)
		(width 0.127)
		(layer "In5.Cu")
		(net "XM_ADDR_5")
	)
	(segment
		(start 186.077098 -69.295264)
		(end 186.077098 -60.350146)
		(width 0.127)
		(layer "In5.Cu")
		(net "XM_ADDR_5")
	)
	(segment
		(start 186.067954 -59.021472)
		(end 186.067954 -58.767472)
		(width 0.127)
		(layer "In5.Cu")
		(net "XM_ADDR_5")
	)
	(segment
		(start 186.067954 -58.767472)
		(end 185.940954 -58.640472)
		(width 0.127)
		(layer "In5.Cu")
		(net "XM_ADDR_5")
	)
	(segment
		(start 186.458098 -55.051452)
		(end 186.585098 -55.178452)
		(width 0.127)
		(layer "In5.Cu")
		(net "XM_ADDR_5")
	)
	(segment
		(start 186.966098 -64.510666)
		(end 186.712098 -64.510666)
		(width 0.127)
		(layer "In5.Cu")
		(net "XM_ADDR_5")
	)
	(segment
		(start 187.29325 -56.66105)
		(end 187.833 -56.1213)
		(width 0.127)
		(layer "F.Cu")
		(net "XM_ADDR_4")
	)
	(segment
		(start 184.760108 -52.70627)
		(end 185.228484 -53.174646)
		(width 0.127)
		(layer "F.Cu")
		(net "XM_ADDR_4")
	)
	(segment
		(start 184.999884 -51.599846)
		(end 184.999884 -51.966876)
		(width 0.127)
		(layer "F.Cu")
		(net "XM_ADDR_4")
	)
	(segment
		(start 187.651644 -58.032142)
		(end 187.651644 -57.827164)
		(width 0.127)
		(layer "F.Cu")
		(net "XM_ADDR_4")
	)
	(segment
		(start 184.760108 -52.206652)
		(end 184.760108 -52.70627)
		(width 0.127)
		(layer "F.Cu")
		(net "XM_ADDR_4")
	)
	(segment
		(start 185.228484 -53.174646)
		(end 185.228484 -53.325014)
		(width 0.127)
		(layer "F.Cu")
		(net "XM_ADDR_4")
	)
	(segment
		(start 184.999884 -51.966876)
		(end 184.760108 -52.206652)
		(width 0.127)
		(layer "F.Cu")
		(net "XM_ADDR_4")
	)
	(segment
		(start 185.228484 -53.325014)
		(end 185.228484 -53.516784)
		(width 0.127)
		(layer "F.Cu")
		(net "XM_ADDR_4")
	)
	(segment
		(start 185.228484 -53.516784)
		(end 187.833 -56.1213)
		(width 0.127)
		(layer "F.Cu")
		(net "XM_ADDR_4")
	)
	(segment
		(start 187.651644 -57.827164)
		(end 187.29325 -57.46877)
		(width 0.127)
		(layer "F.Cu")
		(net "XM_ADDR_4")
	)
	(segment
		(start 187.29325 -57.46877)
		(end 187.29325 -56.66105)
		(width 0.127)
		(layer "F.Cu")
		(net "XM_ADDR_4")
	)
	(via
		(at 185.754772 -72.027034)
		(size 0.508)
		(drill 0.254)
		(layers "F.Cu" "B.Cu")
		(net "XM_ADDR_4")
	)
	(via
		(at 185.228484 -53.325014)
		(size 0.508)
		(drill 0.254)
		(layers "F.Cu" "B.Cu")
		(net "XM_ADDR_4")
	)
	(segment
		(start 183.99252 -72.027034)
		(end 185.754772 -72.027034)
		(width 0.127)
		(layer "B.Cu")
		(net "XM_ADDR_4")
	)
	(segment
		(start 183.494934 -68.52285)
		(end 182.521098 -67.549014)
		(width 0.127)
		(layer "In5.Cu")
		(net "XM_ADDR_4")
	)
	(segment
		(start 185.228484 -53.820822)
		(end 185.228484 -53.325014)
		(width 0.127)
		(layer "In5.Cu")
		(net "XM_ADDR_4")
	)
	(segment
		(start 181.632098 -66.790316)
		(end 181.505098 -66.663316)
		(width 0.127)
		(layer "In5.Cu")
		(net "XM_ADDR_4")
	)
	(segment
		(start 182.013098 -57.60085)
		(end 182.013098 -58.924444)
		(width 0.127)
		(layer "In5.Cu")
		(net "XM_ADDR_4")
	)
	(segment
		(start 182.394098 -60.205366)
		(end 182.140098 -60.205366)
		(width 0.127)
		(layer "In5.Cu")
		(net "XM_ADDR_4")
	)
	(segment
		(start 182.521098 -58.924444)
		(end 182.521098 -56.528208)
		(width 0.127)
		(layer "In5.Cu")
		(net "XM_ADDR_4")
	)
	(segment
		(start 182.013098 -58.924444)
		(end 182.140098 -59.051444)
		(width 0.127)
		(layer "In5.Cu")
		(net "XM_ADDR_4")
	)
	(segment
		(start 182.013098 -66.663316)
		(end 181.886098 -66.790316)
		(width 0.127)
		(layer "In5.Cu")
		(net "XM_ADDR_4")
	)
	(segment
		(start 183.494934 -70.53707)
		(end 183.494934 -68.52285)
		(width 0.127)
		(layer "In5.Cu")
		(net "XM_ADDR_4")
	)
	(segment
		(start 182.394098 -59.051444)
		(end 182.521098 -58.924444)
		(width 0.127)
		(layer "In5.Cu")
		(net "XM_ADDR_4")
	)
	(segment
		(start 181.886098 -66.790316)
		(end 181.632098 -66.790316)
		(width 0.127)
		(layer "In5.Cu")
		(net "XM_ADDR_4")
	)
	(segment
		(start 185.754772 -72.027034)
		(end 184.984898 -72.027034)
		(width 0.127)
		(layer "In5.Cu")
		(net "XM_ADDR_4")
	)
	(segment
		(start 181.505098 -57.60085)
		(end 181.632098 -57.47385)
		(width 0.127)
		(layer "In5.Cu")
		(net "XM_ADDR_4")
	)
	(segment
		(start 182.521098 -60.332366)
		(end 182.394098 -60.205366)
		(width 0.127)
		(layer "In5.Cu")
		(net "XM_ADDR_4")
	)
	(segment
		(start 181.632098 -57.47385)
		(end 181.886098 -57.47385)
		(width 0.127)
		(layer "In5.Cu")
		(net "XM_ADDR_4")
	)
	(segment
		(start 182.521098 -56.528208)
		(end 185.228484 -53.820822)
		(width 0.127)
		(layer "In5.Cu")
		(net "XM_ADDR_4")
	)
	(segment
		(start 184.984898 -72.027034)
		(end 183.494934 -70.53707)
		(width 0.127)
		(layer "In5.Cu")
		(net "XM_ADDR_4")
	)
	(segment
		(start 181.886098 -57.47385)
		(end 182.013098 -57.60085)
		(width 0.127)
		(layer "In5.Cu")
		(net "XM_ADDR_4")
	)
	(segment
		(start 182.521098 -67.549014)
		(end 182.521098 -60.332366)
		(width 0.127)
		(layer "In5.Cu")
		(net "XM_ADDR_4")
	)
	(segment
		(start 182.013098 -60.332366)
		(end 182.013098 -66.663316)
		(width 0.127)
		(layer "In5.Cu")
		(net "XM_ADDR_4")
	)
	(segment
		(start 182.140098 -60.205366)
		(end 182.013098 -60.332366)
		(width 0.127)
		(layer "In5.Cu")
		(net "XM_ADDR_4")
	)
	(segment
		(start 182.140098 -59.051444)
		(end 182.394098 -59.051444)
		(width 0.127)
		(layer "In5.Cu")
		(net "XM_ADDR_4")
	)
	(segment
		(start 181.505098 -66.663316)
		(end 181.505098 -57.60085)
		(width 0.127)
		(layer "In5.Cu")
		(net "XM_ADDR_4")
	)
	(segment
		(start 183.399938 -52.977288)
		(end 183.399938 -51.599846)
		(width 0.127)
		(layer "F.Cu")
		(net "XM_ADDR_3")
	)
	(segment
		(start 183.088026 -53.2892)
		(end 183.399938 -52.977288)
		(width 0.127)
		(layer "F.Cu")
		(net "XM_ADDR_3")
	)
	(via
		(at 183.088026 -53.2892)
		(size 0.508)
		(drill 0.254)
		(layers "F.Cu" "B.Cu")
		(net "XM_ADDR_3")
	)
	(via
		(at 186.7662 -73.053194)
		(size 0.508)
		(drill 0.254)
		(layers "F.Cu" "B.Cu")
		(net "XM_ADDR_3")
	)
	(segment
		(start 183.99252 -72.527414)
		(end 186.24042 -72.527414)
		(width 0.127)
		(layer "B.Cu")
		(net "XM_ADDR_3")
	)
	(segment
		(start 186.24042 -72.527414)
		(end 186.7662 -73.053194)
		(width 0.127)
		(layer "B.Cu")
		(net "XM_ADDR_3")
	)
	(segment
		(start 185.19521 -74.393044)
		(end 187.062872 -74.393044)
		(width 0.127)
		(layer "In5.Cu")
		(net "XM_ADDR_3")
	)
	(segment
		(start 187.047124 -75.409044)
		(end 187.174124 -75.536044)
		(width 0.127)
		(layer "In5.Cu")
		(net "XM_ADDR_3")
	)
	(segment
		(start 181.007512 -54.056788)
		(end 180.827934 -54.236366)
		(width 0.127)
		(layer "In5.Cu")
		(net "XM_ADDR_3")
	)
	(segment
		(start 187.650374 -73.56729)
		(end 186.8932 -73.56729)
		(width 0.127)
		(layer "In5.Cu")
		(net "XM_ADDR_3")
	)
	(segment
		(start 179.80406 -56.447436)
		(end 179.503832 -56.747664)
		(width 0.127)
		(layer "In5.Cu")
		(net "XM_ADDR_3")
	)
	(segment
		(start 186.2582 -75.409044)
		(end 187.047124 -75.409044)
		(width 0.127)
		(layer "In5.Cu")
		(net "XM_ADDR_3")
	)
	(segment
		(start 187.777374 -73.69429)
		(end 187.650374 -73.56729)
		(width 0.127)
		(layer "In5.Cu")
		(net "XM_ADDR_3")
	)
	(segment
		(start 181.780942 -54.470554)
		(end 181.60111 -54.470554)
		(width 0.127)
		(layer "In5.Cu")
		(net "XM_ADDR_3")
	)
	(segment
		(start 181.2417 -55.009796)
		(end 181.062122 -55.189374)
		(width 0.127)
		(layer "In5.Cu")
		(net "XM_ADDR_3")
	)
	(segment
		(start 186.1312 -75.282044)
		(end 186.2582 -75.409044)
		(width 0.127)
		(layer "In5.Cu")
		(net "XM_ADDR_3")
	)
	(segment
		(start 187.189872 -74.774044)
		(end 187.062872 -74.901044)
		(width 0.127)
		(layer "In5.Cu")
		(net "XM_ADDR_3")
	)
	(segment
		(start 187.777374 -76.298044)
		(end 187.777374 -73.69429)
		(width 0.127)
		(layer "In5.Cu")
		(net "XM_ADDR_3")
	)
	(segment
		(start 180.16347 -55.908194)
		(end 179.905914 -55.650638)
		(width 0.127)
		(layer "In5.Cu")
		(net "XM_ADDR_3")
	)
	(segment
		(start 181.062122 -55.189374)
		(end 180.88229 -55.189374)
		(width 0.127)
		(layer "In5.Cu")
		(net "XM_ADDR_3")
	)
	(segment
		(start 187.062872 -74.901044)
		(end 186.2582 -74.901044)
		(width 0.127)
		(layer "In5.Cu")
		(net "XM_ADDR_3")
	)
	(segment
		(start 187.650374 -76.425044)
		(end 187.777374 -76.298044)
		(width 0.127)
		(layer "In5.Cu")
		(net "XM_ADDR_3")
	)
	(segment
		(start 180.827934 -54.236366)
		(end 180.827934 -54.416198)
		(width 0.127)
		(layer "In5.Cu")
		(net "XM_ADDR_3")
	)
	(segment
		(start 181.187344 -54.056788)
		(end 181.007512 -54.056788)
		(width 0.127)
		(layer "In5.Cu")
		(net "XM_ADDR_3")
	)
	(segment
		(start 180.52288 -55.548784)
		(end 180.52288 -55.728616)
		(width 0.127)
		(layer "In5.Cu")
		(net "XM_ADDR_3")
	)
	(segment
		(start 181.2417 -54.829964)
		(end 181.2417 -55.009796)
		(width 0.127)
		(layer "In5.Cu")
		(net "XM_ADDR_3")
	)
	(segment
		(start 180.343302 -55.908194)
		(end 180.16347 -55.908194)
		(width 0.127)
		(layer "In5.Cu")
		(net "XM_ADDR_3")
	)
	(segment
		(start 179.503832 -68.701666)
		(end 185.19521 -74.393044)
		(width 0.127)
		(layer "In5.Cu")
		(net "XM_ADDR_3")
	)
	(segment
		(start 180.52288 -55.728616)
		(end 180.343302 -55.908194)
		(width 0.127)
		(layer "In5.Cu")
		(net "XM_ADDR_3")
	)
	(segment
		(start 187.062872 -74.393044)
		(end 187.189872 -74.520044)
		(width 0.127)
		(layer "In5.Cu")
		(net "XM_ADDR_3")
	)
	(segment
		(start 186.2582 -74.901044)
		(end 186.1312 -75.028044)
		(width 0.127)
		(layer "In5.Cu")
		(net "XM_ADDR_3")
	)
	(segment
		(start 186.1312 -75.028044)
		(end 186.1312 -75.282044)
		(width 0.127)
		(layer "In5.Cu")
		(net "XM_ADDR_3")
	)
	(segment
		(start 180.109114 -54.955186)
		(end 180.109114 -55.135018)
		(width 0.127)
		(layer "In5.Cu")
		(net "XM_ADDR_3")
	)
	(segment
		(start 186.7662 -73.44029)
		(end 186.7662 -73.053194)
		(width 0.127)
		(layer "In5.Cu")
		(net "XM_ADDR_3")
	)
	(segment
		(start 187.174124 -76.298044)
		(end 187.301124 -76.425044)
		(width 0.127)
		(layer "In5.Cu")
		(net "XM_ADDR_3")
	)
	(segment
		(start 180.288692 -54.775608)
		(end 180.109114 -54.955186)
		(width 0.127)
		(layer "In5.Cu")
		(net "XM_ADDR_3")
	)
	(segment
		(start 182.962296 -53.2892)
		(end 181.780942 -54.470554)
		(width 0.127)
		(layer "In5.Cu")
		(net "XM_ADDR_3")
	)
	(segment
		(start 187.189872 -74.520044)
		(end 187.189872 -74.774044)
		(width 0.127)
		(layer "In5.Cu")
		(net "XM_ADDR_3")
	)
	(segment
		(start 180.109114 -55.135018)
		(end 180.52288 -55.548784)
		(width 0.127)
		(layer "In5.Cu")
		(net "XM_ADDR_3")
	)
	(segment
		(start 179.726082 -55.650638)
		(end 179.546504 -55.830216)
		(width 0.127)
		(layer "In5.Cu")
		(net "XM_ADDR_3")
	)
	(segment
		(start 187.301124 -76.425044)
		(end 187.650374 -76.425044)
		(width 0.127)
		(layer "In5.Cu")
		(net "XM_ADDR_3")
	)
	(segment
		(start 179.546504 -56.010048)
		(end 179.80406 -56.267604)
		(width 0.127)
		(layer "In5.Cu")
		(net "XM_ADDR_3")
	)
	(segment
		(start 187.174124 -75.536044)
		(end 187.174124 -76.298044)
		(width 0.127)
		(layer "In5.Cu")
		(net "XM_ADDR_3")
	)
	(segment
		(start 186.8932 -73.56729)
		(end 186.7662 -73.44029)
		(width 0.127)
		(layer "In5.Cu")
		(net "XM_ADDR_3")
	)
	(segment
		(start 179.546504 -55.830216)
		(end 179.546504 -56.010048)
		(width 0.127)
		(layer "In5.Cu")
		(net "XM_ADDR_3")
	)
	(segment
		(start 183.088026 -53.2892)
		(end 182.962296 -53.2892)
		(width 0.127)
		(layer "In5.Cu")
		(net "XM_ADDR_3")
	)
	(segment
		(start 180.827934 -54.416198)
		(end 181.2417 -54.829964)
		(width 0.127)
		(layer "In5.Cu")
		(net "XM_ADDR_3")
	)
	(segment
		(start 179.80406 -56.267604)
		(end 179.80406 -56.447436)
		(width 0.127)
		(layer "In5.Cu")
		(net "XM_ADDR_3")
	)
	(segment
		(start 180.88229 -55.189374)
		(end 180.468524 -54.775608)
		(width 0.127)
		(layer "In5.Cu")
		(net "XM_ADDR_3")
	)
	(segment
		(start 180.468524 -54.775608)
		(end 180.288692 -54.775608)
		(width 0.127)
		(layer "In5.Cu")
		(net "XM_ADDR_3")
	)
	(segment
		(start 179.503832 -56.747664)
		(end 179.503832 -68.701666)
		(width 0.127)
		(layer "In5.Cu")
		(net "XM_ADDR_3")
	)
	(segment
		(start 181.60111 -54.470554)
		(end 181.187344 -54.056788)
		(width 0.127)
		(layer "In5.Cu")
		(net "XM_ADDR_3")
	)
	(segment
		(start 179.905914 -55.650638)
		(end 179.726082 -55.650638)
		(width 0.127)
		(layer "In5.Cu")
		(net "XM_ADDR_3")
	)
	(segment
		(start 186.19978 -45.599858)
		(end 185.799984 -45.999654)
		(width 0.127)
		(layer "F.Cu")
		(net "XM_ADDR_25")
	)
	(segment
		(start 185.799984 -45.999654)
		(end 185.799984 -45.999908)
		(width 0.127)
		(layer "F.Cu")
		(net "XM_ADDR_25")
	)
	(via
		(at 186.19978 -45.599858)
		(size 0.508)
		(drill 0.254)
		(layers "F.Cu" "B.Cu")
		(net "XM_ADDR_25")
	)
	(segment
		(start 186.19978 -45.599858)
		(end 186.767978 -46.168056)
		(width 0.127)
		(layer "B.Cu")
		(net "XM_ADDR_25")
	)
	(segment
		(start 186.767978 -46.168056)
		(end 186.963812 -46.168056)
		(width 0.127)
		(layer "B.Cu")
		(net "XM_ADDR_25")
	)
	(segment
		(start 186.59983 -45.199808)
		(end 187.27801 -45.199808)
		(width 0.127)
		(layer "F.Cu")
		(net "XM_ADDR_24")
	)
	(via
		(at 187.27801 -45.199808)
		(size 0.508)
		(drill 0.254)
		(layers "F.Cu" "B.Cu")
		(net "XM_ADDR_24")
	)
	(segment
		(start 187.037472 -45.199808)
		(end 186.383168 -44.545504)
		(width 0.127)
		(layer "B.Cu")
		(net "XM_ADDR_24")
	)
	(segment
		(start 187.27801 -45.199808)
		(end 187.037472 -45.199808)
		(width 0.127)
		(layer "B.Cu")
		(net "XM_ADDR_24")
	)
	(segment
		(start 186.142884 -44.057062)
		(end 187.24372 -44.057062)
		(width 0.127)
		(layer "F.Cu")
		(net "XM_ADDR_23")
	)
	(segment
		(start 185.799984 -44.399962)
		(end 186.142884 -44.057062)
		(width 0.127)
		(layer "F.Cu")
		(net "XM_ADDR_23")
	)
	(segment
		(start 191.406272 -46.520862)
		(end 191.00546 -46.520862)
		(width 0.127)
		(layer "F.Cu")
		(net "XM_ADDR_23")
	)
	(segment
		(start 188.252608 -43.97121)
		(end 188.455808 -43.97121)
		(width 0.127)
		(layer "F.Cu")
		(net "XM_ADDR_23")
	)
	(segment
		(start 188.214508 -43.93311)
		(end 188.252608 -43.97121)
		(width 0.127)
		(layer "F.Cu")
		(net "XM_ADDR_23")
	)
	(segment
		(start 191.00546 -46.520862)
		(end 188.455808 -43.97121)
		(width 0.127)
		(layer "F.Cu")
		(net "XM_ADDR_23")
	)
	(segment
		(start 187.24372 -44.057062)
		(end 187.367672 -43.93311)
		(width 0.127)
		(layer "F.Cu")
		(net "XM_ADDR_23")
	)
	(segment
		(start 187.367672 -43.93311)
		(end 188.214508 -43.93311)
		(width 0.127)
		(layer "F.Cu")
		(net "XM_ADDR_23")
	)
	(via
		(at 188.455808 -43.97121)
		(size 0.508)
		(drill 0.254)
		(layers "F.Cu" "B.Cu")
		(net "XM_ADDR_23")
	)
	(via
		(at 200.841356 -60.276232)
		(size 0.508)
		(drill 0.254)
		(layers "F.Cu" "B.Cu")
		(net "XM_ADDR_23")
	)
	(segment
		(start 185.049922 -61.027564)
		(end 186.380628 -59.696858)
		(width 0.127)
		(layer "B.Cu")
		(net "XM_ADDR_23")
	)
	(segment
		(start 200.261982 -59.696858)
		(end 200.841356 -60.276232)
		(width 0.127)
		(layer "B.Cu")
		(net "XM_ADDR_23")
	)
	(segment
		(start 183.99252 -61.027564)
		(end 185.049922 -61.027564)
		(width 0.127)
		(layer "B.Cu")
		(net "XM_ADDR_23")
	)
	(segment
		(start 186.380628 -59.696858)
		(end 200.261982 -59.696858)
		(width 0.127)
		(layer "B.Cu")
		(net "XM_ADDR_23")
	)
	(segment
		(start 199.883014 -59.31789)
		(end 199.883014 -56.22798)
		(width 0.127)
		(layer "In5.Cu")
		(net "XM_ADDR_23")
	)
	(segment
		(start 195.300092 -51.645058)
		(end 195.300092 -49.190656)
		(width 0.127)
		(layer "In5.Cu")
		(net "XM_ADDR_23")
	)
	(segment
		(start 195.300092 -49.190656)
		(end 190.080646 -43.97121)
		(width 0.127)
		(layer "In5.Cu")
		(net "XM_ADDR_23")
	)
	(segment
		(start 199.883014 -56.22798)
		(end 195.300092 -51.645058)
		(width 0.127)
		(layer "In5.Cu")
		(net "XM_ADDR_23")
	)
	(segment
		(start 200.841356 -60.276232)
		(end 199.883014 -59.31789)
		(width 0.127)
		(layer "In5.Cu")
		(net "XM_ADDR_23")
	)
	(segment
		(start 190.080646 -43.97121)
		(end 188.455808 -43.97121)
		(width 0.127)
		(layer "In5.Cu")
		(net "XM_ADDR_23")
	)
	(segment
		(start 191.13246 -47.562262)
		(end 188.532008 -44.96181)
		(width 0.127)
		(layer "F.Cu")
		(net "XM_ADDR_22")
	)
	(segment
		(start 191.406272 -47.562262)
		(end 191.13246 -47.562262)
		(width 0.127)
		(layer "F.Cu")
		(net "XM_ADDR_22")
	)
	(segment
		(start 185.799984 -45.199808)
		(end 186.219592 -44.7802)
		(width 0.127)
		(layer "F.Cu")
		(net "XM_ADDR_22")
	)
	(segment
		(start 188.350398 -44.7802)
		(end 188.532008 -44.96181)
		(width 0.127)
		(layer "F.Cu")
		(net "XM_ADDR_22")
	)
	(segment
		(start 186.219592 -44.7802)
		(end 188.350398 -44.7802)
		(width 0.127)
		(layer "F.Cu")
		(net "XM_ADDR_22")
	)
	(via
		(at 196.757798 -66.991484)
		(size 0.508)
		(drill 0.254)
		(layers "F.Cu" "B.Cu")
		(net "XM_ADDR_22")
	)
	(via
		(at 188.532008 -44.96181)
		(size 0.508)
		(drill 0.254)
		(layers "F.Cu" "B.Cu")
		(net "XM_ADDR_22")
	)
	(segment
		(start 194.3354 -67.527424)
		(end 194.87134 -66.991484)
		(width 0.127)
		(layer "B.Cu")
		(net "XM_ADDR_22")
	)
	(segment
		(start 183.99252 -67.527424)
		(end 194.3354 -67.527424)
		(width 0.127)
		(layer "B.Cu")
		(net "XM_ADDR_22")
	)
	(segment
		(start 194.87134 -66.991484)
		(end 196.757798 -66.991484)
		(width 0.127)
		(layer "B.Cu")
		(net "XM_ADDR_22")
	)
	(segment
		(start 190.35268 -44.96181)
		(end 188.532008 -44.96181)
		(width 0.127)
		(layer "In5.Cu")
		(net "XM_ADDR_22")
	)
	(segment
		(start 199.348598 -56.41213)
		(end 194.777106 -51.840638)
		(width 0.127)
		(layer "In5.Cu")
		(net "XM_ADDR_22")
	)
	(segment
		(start 197.17893 -66.991484)
		(end 199.348598 -64.821816)
		(width 0.127)
		(layer "In5.Cu")
		(net "XM_ADDR_22")
	)
	(segment
		(start 196.757798 -66.991484)
		(end 197.17893 -66.991484)
		(width 0.127)
		(layer "In5.Cu")
		(net "XM_ADDR_22")
	)
	(segment
		(start 194.777106 -49.386236)
		(end 190.35268 -44.96181)
		(width 0.127)
		(layer "In5.Cu")
		(net "XM_ADDR_22")
	)
	(segment
		(start 199.348598 -64.821816)
		(end 199.348598 -56.41213)
		(width 0.127)
		(layer "In5.Cu")
		(net "XM_ADDR_22")
	)
	(segment
		(start 194.777106 -51.840638)
		(end 194.777106 -49.386236)
		(width 0.127)
		(layer "In5.Cu")
		(net "XM_ADDR_22")
	)
	(segment
		(start 187.867544 -46.37151)
		(end 187.905644 -46.40961)
		(width 0.127)
		(layer "F.Cu")
		(net "XM_ADDR_21")
	)
	(segment
		(start 187.905644 -46.40961)
		(end 188.595508 -46.40961)
		(width 0.127)
		(layer "F.Cu")
		(net "XM_ADDR_21")
	)
	(segment
		(start 186.228482 -46.37151)
		(end 187.867544 -46.37151)
		(width 0.127)
		(layer "F.Cu")
		(net "XM_ADDR_21")
	)
	(segment
		(start 185.799984 -46.800008)
		(end 186.228482 -46.37151)
		(width 0.127)
		(layer "F.Cu")
		(net "XM_ADDR_21")
	)
	(via
		(at 196.757798 -65.975484)
		(size 0.508)
		(drill 0.254)
		(layers "F.Cu" "B.Cu")
		(net "XM_ADDR_21")
	)
	(via
		(at 188.595508 -46.40961)
		(size 0.508)
		(drill 0.254)
		(layers "F.Cu" "B.Cu")
		(net "XM_ADDR_21")
	)
	(segment
		(start 185.774838 -67.019424)
		(end 184.782968 -66.027554)
		(width 0.127)
		(layer "B.Cu")
		(net "XM_ADDR_21")
	)
	(segment
		(start 184.782968 -66.027554)
		(end 183.99252 -66.027554)
		(width 0.127)
		(layer "B.Cu")
		(net "XM_ADDR_21")
	)
	(segment
		(start 196.757798 -65.975484)
		(end 195.108576 -65.975484)
		(width 0.127)
		(layer "B.Cu")
		(net "XM_ADDR_21")
	)
	(segment
		(start 188.595508 -46.40961)
		(end 189.124844 -46.40961)
		(width 0.127)
		(layer "B.Cu")
		(net "XM_ADDR_21")
	)
	(segment
		(start 195.108576 -65.975484)
		(end 194.064636 -67.019424)
		(width 0.127)
		(layer "B.Cu")
		(net "XM_ADDR_21")
	)
	(segment
		(start 189.124844 -46.40961)
		(end 189.397386 -46.682152)
		(width 0.127)
		(layer "B.Cu")
		(net "XM_ADDR_21")
	)
	(segment
		(start 194.064636 -67.019424)
		(end 185.774838 -67.019424)
		(width 0.127)
		(layer "B.Cu")
		(net "XM_ADDR_21")
	)
	(segment
		(start 197.79615 -62.418214)
		(end 197.79615 -62.672214)
		(width 0.127)
		(layer "In5.Cu")
		(net "XM_ADDR_21")
	)
	(segment
		(start 198.143114 -62.799214)
		(end 198.270114 -62.926214)
		(width 0.127)
		(layer "In5.Cu")
		(net "XM_ADDR_21")
	)
	(segment
		(start 197.92315 -64.323214)
		(end 197.79615 -64.450214)
		(width 0.127)
		(layer "In5.Cu")
		(net "XM_ADDR_21")
	)
	(segment
		(start 198.143114 -63.307214)
		(end 197.92315 -63.307214)
		(width 0.127)
		(layer "In5.Cu")
		(net "XM_ADDR_21")
	)
	(segment
		(start 194.200526 -53.456586)
		(end 194.200526 -54.4957)
		(width 0.127)
		(layer "In5.Cu")
		(net "XM_ADDR_21")
	)
	(segment
		(start 197.79615 -62.672214)
		(end 197.92315 -62.799214)
		(width 0.127)
		(layer "In5.Cu")
		(net "XM_ADDR_21")
	)
	(segment
		(start 192.69583 -51.95189)
		(end 194.200526 -53.456586)
		(width 0.127)
		(layer "In5.Cu")
		(net "XM_ADDR_21")
	)
	(segment
		(start 189.835282 -46.60011)
		(end 192.69583 -49.460658)
		(width 0.127)
		(layer "In5.Cu")
		(net "XM_ADDR_21")
	)
	(segment
		(start 197.79615 -64.937132)
		(end 196.757798 -65.975484)
		(width 0.127)
		(layer "In5.Cu")
		(net "XM_ADDR_21")
	)
	(segment
		(start 197.92315 -63.307214)
		(end 197.79615 -63.434214)
		(width 0.127)
		(layer "In5.Cu")
		(net "XM_ADDR_21")
	)
	(segment
		(start 188.595508 -46.40961)
		(end 188.786008 -46.60011)
		(width 0.127)
		(layer "In5.Cu")
		(net "XM_ADDR_21")
	)
	(segment
		(start 197.79615 -61.656214)
		(end 197.92315 -61.783214)
		(width 0.127)
		(layer "In5.Cu")
		(net "XM_ADDR_21")
	)
	(segment
		(start 198.143114 -63.815214)
		(end 198.270114 -63.942214)
		(width 0.127)
		(layer "In5.Cu")
		(net "XM_ADDR_21")
	)
	(segment
		(start 196.422264 -55.74411)
		(end 197.79615 -57.117996)
		(width 0.127)
		(layer "In5.Cu")
		(net "XM_ADDR_21")
	)
	(segment
		(start 198.270114 -64.196214)
		(end 198.143114 -64.323214)
		(width 0.127)
		(layer "In5.Cu")
		(net "XM_ADDR_21")
	)
	(segment
		(start 198.143114 -61.783214)
		(end 198.270114 -61.910214)
		(width 0.127)
		(layer "In5.Cu")
		(net "XM_ADDR_21")
	)
	(segment
		(start 198.270114 -63.942214)
		(end 198.270114 -64.196214)
		(width 0.127)
		(layer "In5.Cu")
		(net "XM_ADDR_21")
	)
	(segment
		(start 198.270114 -63.180214)
		(end 198.143114 -63.307214)
		(width 0.127)
		(layer "In5.Cu")
		(net "XM_ADDR_21")
	)
	(segment
		(start 195.448936 -55.74411)
		(end 196.422264 -55.74411)
		(width 0.127)
		(layer "In5.Cu")
		(net "XM_ADDR_21")
	)
	(segment
		(start 198.270114 -61.910214)
		(end 198.270114 -62.164214)
		(width 0.127)
		(layer "In5.Cu")
		(net "XM_ADDR_21")
	)
	(segment
		(start 197.79615 -64.450214)
		(end 197.79615 -64.937132)
		(width 0.127)
		(layer "In5.Cu")
		(net "XM_ADDR_21")
	)
	(segment
		(start 194.200526 -54.4957)
		(end 195.448936 -55.74411)
		(width 0.127)
		(layer "In5.Cu")
		(net "XM_ADDR_21")
	)
	(segment
		(start 198.270114 -62.164214)
		(end 198.143114 -62.291214)
		(width 0.127)
		(layer "In5.Cu")
		(net "XM_ADDR_21")
	)
	(segment
		(start 197.92315 -61.783214)
		(end 198.143114 -61.783214)
		(width 0.127)
		(layer "In5.Cu")
		(net "XM_ADDR_21")
	)
	(segment
		(start 198.143114 -62.291214)
		(end 197.92315 -62.291214)
		(width 0.127)
		(layer "In5.Cu")
		(net "XM_ADDR_21")
	)
	(segment
		(start 198.143114 -64.323214)
		(end 197.92315 -64.323214)
		(width 0.127)
		(layer "In5.Cu")
		(net "XM_ADDR_21")
	)
	(segment
		(start 197.79615 -63.434214)
		(end 197.79615 -63.688214)
		(width 0.127)
		(layer "In5.Cu")
		(net "XM_ADDR_21")
	)
	(segment
		(start 192.69583 -49.460658)
		(end 192.69583 -51.95189)
		(width 0.127)
		(layer "In5.Cu")
		(net "XM_ADDR_21")
	)
	(segment
		(start 197.92315 -62.799214)
		(end 198.143114 -62.799214)
		(width 0.127)
		(layer "In5.Cu")
		(net "XM_ADDR_21")
	)
	(segment
		(start 197.92315 -63.815214)
		(end 198.143114 -63.815214)
		(width 0.127)
		(layer "In5.Cu")
		(net "XM_ADDR_21")
	)
	(segment
		(start 197.79615 -57.117996)
		(end 197.79615 -61.656214)
		(width 0.127)
		(layer "In5.Cu")
		(net "XM_ADDR_21")
	)
	(segment
		(start 188.786008 -46.60011)
		(end 189.835282 -46.60011)
		(width 0.127)
		(layer "In5.Cu")
		(net "XM_ADDR_21")
	)
	(segment
		(start 197.79615 -63.688214)
		(end 197.92315 -63.815214)
		(width 0.127)
		(layer "In5.Cu")
		(net "XM_ADDR_21")
	)
	(segment
		(start 198.270114 -62.926214)
		(end 198.270114 -63.180214)
		(width 0.127)
		(layer "In5.Cu")
		(net "XM_ADDR_21")
	)
	(segment
		(start 197.92315 -62.291214)
		(end 197.79615 -62.418214)
		(width 0.127)
		(layer "In5.Cu")
		(net "XM_ADDR_21")
	)
	(segment
		(start 188.913008 -47.52721)
		(end 188.840364 -47.599854)
		(width 0.127)
		(layer "F.Cu")
		(net "XM_ADDR_20")
	)
	(segment
		(start 188.840364 -47.599854)
		(end 186.59983 -47.599854)
		(width 0.127)
		(layer "F.Cu")
		(net "XM_ADDR_20")
	)
	(via
		(at 188.913008 -47.52721)
		(size 0.508)
		(drill 0.254)
		(layers "F.Cu" "B.Cu")
		(net "XM_ADDR_20")
	)
	(via
		(at 193.456052 -65.94729)
		(size 0.508)
		(drill 0.254)
		(layers "F.Cu" "B.Cu")
		(net "XM_ADDR_20")
	)
	(segment
		(start 192.891918 -66.511424)
		(end 185.985404 -66.511424)
		(width 0.127)
		(layer "B.Cu")
		(net "XM_ADDR_20")
	)
	(segment
		(start 193.456052 -65.94729)
		(end 192.891918 -66.511424)
		(width 0.127)
		(layer "B.Cu")
		(net "XM_ADDR_20")
	)
	(segment
		(start 188.913008 -47.52721)
		(end 189.532006 -48.146208)
		(width 0.127)
		(layer "B.Cu")
		(net "XM_ADDR_20")
	)
	(segment
		(start 189.532006 -48.146208)
		(end 189.659514 -48.146208)
		(width 0.127)
		(layer "B.Cu")
		(net "XM_ADDR_20")
	)
	(segment
		(start 185.001154 -65.527174)
		(end 183.99252 -65.527174)
		(width 0.127)
		(layer "B.Cu")
		(net "XM_ADDR_20")
	)
	(segment
		(start 185.985404 -66.511424)
		(end 185.001154 -65.527174)
		(width 0.127)
		(layer "B.Cu")
		(net "XM_ADDR_20")
	)
	(segment
		(start 195.690744 -60.106052)
		(end 195.690744 -59.852052)
		(width 0.127)
		(layer "In5.Cu")
		(net "XM_ADDR_20")
	)
	(segment
		(start 196.548502 -58.328052)
		(end 196.421502 -58.201052)
		(width 0.127)
		(layer "In5.Cu")
		(net "XM_ADDR_20")
	)
	(segment
		(start 195.690744 -60.868052)
		(end 195.817744 -60.741052)
		(width 0.127)
		(layer "In5.Cu")
		(net "XM_ADDR_20")
	)
	(segment
		(start 196.633084 -57.40146)
		(end 196.217794 -56.98617)
		(width 0.127)
		(layer "In5.Cu")
		(net "XM_ADDR_20")
	)
	(segment
		(start 196.633084 -62.392052)
		(end 196.506084 -62.265052)
		(width 0.127)
		(layer "In5.Cu")
		(net "XM_ADDR_20")
	)
	(segment
		(start 196.508878 -61.376052)
		(end 196.381878 -61.249052)
		(width 0.127)
		(layer "In5.Cu")
		(net "XM_ADDR_20")
	)
	(segment
		(start 192.237106 -52.930298)
		(end 191.67983 -52.373022)
		(width 0.127)
		(layer "In5.Cu")
		(net "XM_ADDR_20")
	)
	(segment
		(start 196.548502 -59.344052)
		(end 196.421502 -59.217052)
		(width 0.127)
		(layer "In5.Cu")
		(net "XM_ADDR_20")
	)
	(segment
		(start 196.545962 -60.614052)
		(end 196.545962 -60.360052)
		(width 0.127)
		(layer "In5.Cu")
		(net "XM_ADDR_20")
	)
	(segment
		(start 195.817744 -61.757052)
		(end 196.381878 -61.757052)
		(width 0.127)
		(layer "In5.Cu")
		(net "XM_ADDR_20")
	)
	(segment
		(start 195.233798 -64.920876)
		(end 195.233798 -64.015112)
		(width 0.127)
		(layer "In5.Cu")
		(net "XM_ADDR_20")
	)
	(segment
		(start 195.233798 -64.015112)
		(end 196.633084 -62.615826)
		(width 0.127)
		(layer "In5.Cu")
		(net "XM_ADDR_20")
	)
	(segment
		(start 196.633084 -62.615826)
		(end 196.633084 -62.392052)
		(width 0.127)
		(layer "In5.Cu")
		(net "XM_ADDR_20")
	)
	(segment
		(start 195.817744 -57.693052)
		(end 196.506084 -57.693052)
		(width 0.127)
		(layer "In5.Cu")
		(net "XM_ADDR_20")
	)
	(segment
		(start 196.381878 -61.249052)
		(end 195.817744 -61.249052)
		(width 0.127)
		(layer "In5.Cu")
		(net "XM_ADDR_20")
	)
	(segment
		(start 195.817744 -62.265052)
		(end 195.690744 -62.138052)
		(width 0.127)
		(layer "In5.Cu")
		(net "XM_ADDR_20")
	)
	(segment
		(start 195.817744 -61.249052)
		(end 195.690744 -61.122052)
		(width 0.127)
		(layer "In5.Cu")
		(net "XM_ADDR_20")
	)
	(segment
		(start 195.127626 -56.98617)
		(end 192.237106 -54.09565)
		(width 0.127)
		(layer "In5.Cu")
		(net "XM_ADDR_20")
	)
	(segment
		(start 196.506084 -57.693052)
		(end 196.633084 -57.566052)
		(width 0.127)
		(layer "In5.Cu")
		(net "XM_ADDR_20")
	)
	(segment
		(start 191.67983 -52.373022)
		(end 191.67983 -49.88179)
		(width 0.127)
		(layer "In5.Cu")
		(net "XM_ADDR_20")
	)
	(segment
		(start 195.817744 -59.217052)
		(end 195.690744 -59.090052)
		(width 0.127)
		(layer "In5.Cu")
		(net "XM_ADDR_20")
	)
	(segment
		(start 195.817744 -58.201052)
		(end 195.690744 -58.074052)
		(width 0.127)
		(layer "In5.Cu")
		(net "XM_ADDR_20")
	)
	(segment
		(start 196.548502 -59.598052)
		(end 196.548502 -59.344052)
		(width 0.127)
		(layer "In5.Cu")
		(net "XM_ADDR_20")
	)
	(segment
		(start 196.508878 -61.630052)
		(end 196.508878 -61.376052)
		(width 0.127)
		(layer "In5.Cu")
		(net "XM_ADDR_20")
	)
	(segment
		(start 195.690744 -61.122052)
		(end 195.690744 -60.868052)
		(width 0.127)
		(layer "In5.Cu")
		(net "XM_ADDR_20")
	)
	(segment
		(start 196.421502 -59.217052)
		(end 195.817744 -59.217052)
		(width 0.127)
		(layer "In5.Cu")
		(net "XM_ADDR_20")
	)
	(segment
		(start 196.633084 -57.566052)
		(end 196.633084 -57.40146)
		(width 0.127)
		(layer "In5.Cu")
		(net "XM_ADDR_20")
	)
	(segment
		(start 193.456052 -65.94729)
		(end 194.207384 -65.94729)
		(width 0.127)
		(layer "In5.Cu")
		(net "XM_ADDR_20")
	)
	(segment
		(start 195.690744 -57.820052)
		(end 195.817744 -57.693052)
		(width 0.127)
		(layer "In5.Cu")
		(net "XM_ADDR_20")
	)
	(segment
		(start 196.418962 -60.233052)
		(end 195.817744 -60.233052)
		(width 0.127)
		(layer "In5.Cu")
		(net "XM_ADDR_20")
	)
	(segment
		(start 196.421502 -59.725052)
		(end 196.548502 -59.598052)
		(width 0.127)
		(layer "In5.Cu")
		(net "XM_ADDR_20")
	)
	(segment
		(start 196.548502 -58.582052)
		(end 196.548502 -58.328052)
		(width 0.127)
		(layer "In5.Cu")
		(net "XM_ADDR_20")
	)
	(segment
		(start 195.690744 -59.090052)
		(end 195.690744 -58.836052)
		(width 0.127)
		(layer "In5.Cu")
		(net "XM_ADDR_20")
	)
	(segment
		(start 196.381878 -61.757052)
		(end 196.508878 -61.630052)
		(width 0.127)
		(layer "In5.Cu")
		(net "XM_ADDR_20")
	)
	(segment
		(start 195.690744 -59.852052)
		(end 195.817744 -59.725052)
		(width 0.127)
		(layer "In5.Cu")
		(net "XM_ADDR_20")
	)
	(segment
		(start 196.421502 -58.201052)
		(end 195.817744 -58.201052)
		(width 0.127)
		(layer "In5.Cu")
		(net "XM_ADDR_20")
	)
	(segment
		(start 196.421502 -58.709052)
		(end 196.548502 -58.582052)
		(width 0.127)
		(layer "In5.Cu")
		(net "XM_ADDR_20")
	)
	(segment
		(start 195.817744 -60.233052)
		(end 195.690744 -60.106052)
		(width 0.127)
		(layer "In5.Cu")
		(net "XM_ADDR_20")
	)
	(segment
		(start 195.690744 -61.884052)
		(end 195.817744 -61.757052)
		(width 0.127)
		(layer "In5.Cu")
		(net "XM_ADDR_20")
	)
	(segment
		(start 192.237106 -54.09565)
		(end 192.237106 -52.930298)
		(width 0.127)
		(layer "In5.Cu")
		(net "XM_ADDR_20")
	)
	(segment
		(start 195.817744 -58.709052)
		(end 196.421502 -58.709052)
		(width 0.127)
		(layer "In5.Cu")
		(net "XM_ADDR_20")
	)
	(segment
		(start 195.817744 -59.725052)
		(end 196.421502 -59.725052)
		(width 0.127)
		(layer "In5.Cu")
		(net "XM_ADDR_20")
	)
	(segment
		(start 194.207384 -65.94729)
		(end 195.233798 -64.920876)
		(width 0.127)
		(layer "In5.Cu")
		(net "XM_ADDR_20")
	)
	(segment
		(start 196.545962 -60.360052)
		(end 196.418962 -60.233052)
		(width 0.127)
		(layer "In5.Cu")
		(net "XM_ADDR_20")
	)
	(segment
		(start 195.690744 -58.074052)
		(end 195.690744 -57.820052)
		(width 0.127)
		(layer "In5.Cu")
		(net "XM_ADDR_20")
	)
	(segment
		(start 196.418962 -60.741052)
		(end 196.545962 -60.614052)
		(width 0.127)
		(layer "In5.Cu")
		(net "XM_ADDR_20")
	)
	(segment
		(start 196.217794 -56.98617)
		(end 195.127626 -56.98617)
		(width 0.127)
		(layer "In5.Cu")
		(net "XM_ADDR_20")
	)
	(segment
		(start 189.32525 -47.52721)
		(end 188.913008 -47.52721)
		(width 0.127)
		(layer "In5.Cu")
		(net "XM_ADDR_20")
	)
	(segment
		(start 191.67983 -49.88179)
		(end 189.32525 -47.52721)
		(width 0.127)
		(layer "In5.Cu")
		(net "XM_ADDR_20")
	)
	(segment
		(start 195.817744 -60.741052)
		(end 196.418962 -60.741052)
		(width 0.127)
		(layer "In5.Cu")
		(net "XM_ADDR_20")
	)
	(segment
		(start 196.506084 -62.265052)
		(end 195.817744 -62.265052)
		(width 0.127)
		(layer "In5.Cu")
		(net "XM_ADDR_20")
	)
	(segment
		(start 195.690744 -62.138052)
		(end 195.690744 -61.884052)
		(width 0.127)
		(layer "In5.Cu")
		(net "XM_ADDR_20")
	)
	(segment
		(start 195.690744 -58.836052)
		(end 195.817744 -58.709052)
		(width 0.127)
		(layer "In5.Cu")
		(net "XM_ADDR_20")
	)
	(segment
		(start 186.508644 -56.127142)
		(end 186.508644 -55.746142)
		(width 0.127)
		(layer "F.Cu")
		(net "XM_ADDR_2")
	)
	(segment
		(start 184.093104 -53.330602)
		(end 184.093104 -52.40528)
		(width 0.127)
		(layer "F.Cu")
		(net "XM_ADDR_2")
	)
	(segment
		(start 184.542684 -51.9557)
		(end 184.542684 -50.3428)
		(width 0.127)
		(layer "F.Cu")
		(net "XM_ADDR_2")
	)
	(segment
		(start 184.093104 -52.40528)
		(end 184.542684 -51.9557)
		(width 0.127)
		(layer "F.Cu")
		(net "XM_ADDR_2")
	)
	(segment
		(start 186.508644 -55.746142)
		(end 184.093104 -53.330602)
		(width 0.127)
		(layer "F.Cu")
		(net "XM_ADDR_2")
	)
	(segment
		(start 184.542684 -50.3428)
		(end 184.199784 -49.9999)
		(width 0.127)
		(layer "F.Cu")
		(net "XM_ADDR_2")
	)
	(via
		(at 185.7502 -73.053194)
		(size 0.508)
		(drill 0.254)
		(layers "F.Cu" "B.Cu")
		(net "XM_ADDR_2")
	)
	(via
		(at 184.093104 -53.330602)
		(size 0.508)
		(drill 0.254)
		(layers "F.Cu" "B.Cu")
		(net "XM_ADDR_2")
	)
	(segment
		(start 185.7248 -73.027794)
		(end 183.99252 -73.027794)
		(width 0.127)
		(layer "B.Cu")
		(net "XM_ADDR_2")
	)
	(segment
		(start 185.7502 -73.053194)
		(end 185.7248 -73.027794)
		(width 0.127)
		(layer "B.Cu")
		(net "XM_ADDR_2")
	)
	(segment
		(start 180.430424 -66.368676)
		(end 180.430424 -66.622676)
		(width 0.127)
		(layer "In5.Cu")
		(net "XM_ADDR_2")
	)
	(segment
		(start 180.138832 -63.193676)
		(end 180.36159 -63.193676)
		(width 0.127)
		(layer "In5.Cu")
		(net "XM_ADDR_2")
	)
	(segment
		(start 183.105298 -54.044088)
		(end 182.925974 -54.044088)
		(width 0.127)
		(layer "In5.Cu")
		(net "XM_ADDR_2")
	)
	(segment
		(start 180.36159 -64.209676)
		(end 180.48859 -64.336676)
		(width 0.127)
		(layer "In5.Cu")
		(net "XM_ADDR_2")
	)
	(segment
		(start 180.862224 -56.28767)
		(end 180.989224 -56.41467)
		(width 0.127)
		(layer "In5.Cu")
		(net "XM_ADDR_2")
	)
	(segment
		(start 180.478176 -58.916062)
		(end 180.351176 -59.043062)
		(width 0.127)
		(layer "In5.Cu")
		(net "XM_ADDR_2")
	)
	(segment
		(start 180.48859 -64.590676)
		(end 180.36159 -64.717676)
		(width 0.127)
		(layer "In5.Cu")
		(net "XM_ADDR_2")
	)
	(segment
		(start 180.48859 -62.558676)
		(end 180.36159 -62.685676)
		(width 0.127)
		(layer "In5.Cu")
		(net "XM_ADDR_2")
	)
	(segment
		(start 183.63946 -53.330602)
		(end 183.464708 -53.505354)
		(width 0.127)
		(layer "In5.Cu")
		(net "XM_ADDR_2")
	)
	(segment
		(start 180.36159 -62.177676)
		(end 180.48859 -62.304676)
		(width 0.127)
		(layer "In5.Cu")
		(net "XM_ADDR_2")
	)
	(segment
		(start 180.351176 -59.043062)
		(end 180.138832 -59.043062)
		(width 0.127)
		(layer "In5.Cu")
		(net "XM_ADDR_2")
	)
	(segment
		(start 183.585358 -53.805074)
		(end 183.585358 -53.984398)
		(width 0.127)
		(layer "In5.Cu")
		(net "XM_ADDR_2")
	)
	(segment
		(start 180.011832 -59.170062)
		(end 180.011832 -59.424062)
		(width 0.127)
		(layer "In5.Cu")
		(net "XM_ADDR_2")
	)
	(segment
		(start 182.745888 -54.403498)
		(end 182.866538 -54.523894)
		(width 0.127)
		(layer "In5.Cu")
		(net "XM_ADDR_2")
	)
	(segment
		(start 180.809646 -56.77408)
		(end 180.629814 -56.77408)
		(width 0.127)
		(layer "In5.Cu")
		(net "XM_ADDR_2")
	)
	(segment
		(start 180.011832 -58.408062)
		(end 180.138832 -58.535062)
		(width 0.127)
		(layer "In5.Cu")
		(net "XM_ADDR_2")
	)
	(segment
		(start 180.011832 -65.098676)
		(end 180.138832 -65.225676)
		(width 0.127)
		(layer "In5.Cu")
		(net "XM_ADDR_2")
	)
	(segment
		(start 180.011832 -66.876676)
		(end 180.011832 -67.05346)
		(width 0.127)
		(layer "In5.Cu")
		(net "XM_ADDR_2")
	)
	(segment
		(start 180.138832 -63.701676)
		(end 180.011832 -63.828676)
		(width 0.127)
		(layer "In5.Cu")
		(net "XM_ADDR_2")
	)
	(segment
		(start 180.478176 -59.932062)
		(end 180.351176 -60.059062)
		(width 0.127)
		(layer "In5.Cu")
		(net "XM_ADDR_2")
	)
	(segment
		(start 180.36159 -65.225676)
		(end 180.48859 -65.352676)
		(width 0.127)
		(layer "In5.Cu")
		(net "XM_ADDR_2")
	)
	(segment
		(start 180.011832 -66.114676)
		(end 180.138832 -66.241676)
		(width 0.127)
		(layer "In5.Cu")
		(net "XM_ADDR_2")
	)
	(segment
		(start 180.351176 -58.535062)
		(end 180.478176 -58.662062)
		(width 0.127)
		(layer "In5.Cu")
		(net "XM_ADDR_2")
	)
	(segment
		(start 180.351176 -60.059062)
		(end 180.138832 -60.059062)
		(width 0.127)
		(layer "In5.Cu")
		(net "XM_ADDR_2")
	)
	(segment
		(start 180.478176 -57.646062)
		(end 180.478176 -57.900062)
		(width 0.127)
		(layer "In5.Cu")
		(net "XM_ADDR_2")
	)
	(segment
		(start 183.405272 -54.164484)
		(end 183.225948 -54.164484)
		(width 0.127)
		(layer "In5.Cu")
		(net "XM_ADDR_2")
	)
	(segment
		(start 182.866538 -54.703218)
		(end 182.686452 -54.883304)
		(width 0.127)
		(layer "In5.Cu")
		(net "XM_ADDR_2")
	)
	(segment
		(start 180.138832 -58.535062)
		(end 180.351176 -58.535062)
		(width 0.127)
		(layer "In5.Cu")
		(net "XM_ADDR_2")
	)
	(segment
		(start 180.02123 -68.500498)
		(end 184.573926 -73.053194)
		(width 0.127)
		(layer "In5.Cu")
		(net "XM_ADDR_2")
	)
	(segment
		(start 183.225948 -54.164484)
		(end 183.105298 -54.044088)
		(width 0.127)
		(layer "In5.Cu")
		(net "XM_ADDR_2")
	)
	(segment
		(start 180.478176 -57.900062)
		(end 180.351176 -58.027062)
		(width 0.127)
		(layer "In5.Cu")
		(net "XM_ADDR_2")
	)
	(segment
		(start 181.488334 -55.481728)
		(end 180.862224 -56.107838)
		(width 0.127)
		(layer "In5.Cu")
		(net "XM_ADDR_2")
	)
	(segment
		(start 180.138832 -60.059062)
		(end 180.011832 -60.186062)
		(width 0.127)
		(layer "In5.Cu")
		(net "XM_ADDR_2")
	)
	(segment
		(start 183.464708 -53.505354)
		(end 183.464708 -53.684678)
		(width 0.127)
		(layer "In5.Cu")
		(net "XM_ADDR_2")
	)
	(segment
		(start 180.48859 -65.352676)
		(end 180.48859 -65.606676)
		(width 0.127)
		(layer "In5.Cu")
		(net "XM_ADDR_2")
	)
	(segment
		(start 182.686452 -54.883304)
		(end 182.507128 -54.883304)
		(width 0.127)
		(layer "In5.Cu")
		(net "XM_ADDR_2")
	)
	(segment
		(start 180.629814 -56.77408)
		(end 180.502814 -56.64708)
		(width 0.127)
		(layer "In5.Cu")
		(net "XM_ADDR_2")
	)
	(segment
		(start 181.788308 -55.602124)
		(end 181.667658 -55.481728)
		(width 0.127)
		(layer "In5.Cu")
		(net "XM_ADDR_2")
	)
	(segment
		(start 180.138832 -59.043062)
		(end 180.011832 -59.170062)
		(width 0.127)
		(layer "In5.Cu")
		(net "XM_ADDR_2")
	)
	(segment
		(start 180.011832 -67.05346)
		(end 182.422546 -69.464174)
		(width 0.127)
		(layer "In5.Cu")
		(net "XM_ADDR_2")
	)
	(segment
		(start 180.011832 -57.392062)
		(end 180.138832 -57.519062)
		(width 0.127)
		(layer "In5.Cu")
		(net "XM_ADDR_2")
	)
	(segment
		(start 180.138832 -66.749676)
		(end 180.011832 -66.876676)
		(width 0.127)
		(layer "In5.Cu")
		(net "XM_ADDR_2")
	)
	(segment
		(start 182.027068 -55.122318)
		(end 182.147718 -55.242714)
		(width 0.127)
		(layer "In5.Cu")
		(net "XM_ADDR_2")
	)
	(segment
		(start 180.200808 -68.141088)
		(end 180.02123 -68.320666)
		(width 0.127)
		(layer "In5.Cu")
		(net "XM_ADDR_2")
	)
	(segment
		(start 180.011832 -59.424062)
		(end 180.138832 -59.551062)
		(width 0.127)
		(layer "In5.Cu")
		(net "XM_ADDR_2")
	)
	(segment
		(start 180.303424 -66.749676)
		(end 180.138832 -66.749676)
		(width 0.127)
		(layer "In5.Cu")
		(net "XM_ADDR_2")
	)
	(segment
		(start 184.093104 -53.330602)
		(end 183.63946 -53.330602)
		(width 0.127)
		(layer "In5.Cu")
		(net "XM_ADDR_2")
	)
	(segment
		(start 182.027068 -54.942994)
		(end 182.027068 -55.122318)
		(width 0.127)
		(layer "In5.Cu")
		(net "XM_ADDR_2")
	)
	(segment
		(start 180.138832 -65.733676)
		(end 180.011832 -65.860676)
		(width 0.127)
		(layer "In5.Cu")
		(net "XM_ADDR_2")
	)
	(segment
		(start 180.36159 -64.717676)
		(end 180.138832 -64.717676)
		(width 0.127)
		(layer "In5.Cu")
		(net "XM_ADDR_2")
	)
	(segment
		(start 180.502814 -56.64708)
		(end 180.322982 -56.64708)
		(width 0.127)
		(layer "In5.Cu")
		(net "XM_ADDR_2")
	)
	(segment
		(start 182.422546 -69.644006)
		(end 182.242968 -69.823584)
		(width 0.127)
		(layer "In5.Cu")
		(net "XM_ADDR_2")
	)
	(segment
		(start 180.138832 -64.209676)
		(end 180.36159 -64.209676)
		(width 0.127)
		(layer "In5.Cu")
		(net "XM_ADDR_2")
	)
	(segment
		(start 180.48859 -63.574676)
		(end 180.36159 -63.701676)
		(width 0.127)
		(layer "In5.Cu")
		(net "XM_ADDR_2")
	)
	(segment
		(start 180.989224 -56.41467)
		(end 180.989224 -56.594502)
		(width 0.127)
		(layer "In5.Cu")
		(net "XM_ADDR_2")
	)
	(segment
		(start 180.351176 -59.551062)
		(end 180.478176 -59.678062)
		(width 0.127)
		(layer "In5.Cu")
		(net "XM_ADDR_2")
	)
	(segment
		(start 180.138832 -62.177676)
		(end 180.36159 -62.177676)
		(width 0.127)
		(layer "In5.Cu")
		(net "XM_ADDR_2")
	)
	(segment
		(start 180.322982 -56.64708)
		(end 180.011832 -56.95823)
		(width 0.127)
		(layer "In5.Cu")
		(net "XM_ADDR_2")
	)
	(segment
		(start 180.138832 -59.551062)
		(end 180.351176 -59.551062)
		(width 0.127)
		(layer "In5.Cu")
		(net "XM_ADDR_2")
	)
	(segment
		(start 180.02123 -68.320666)
		(end 180.02123 -68.500498)
		(width 0.127)
		(layer "In5.Cu")
		(net "XM_ADDR_2")
	)
	(segment
		(start 180.38064 -68.141088)
		(end 180.200808 -68.141088)
		(width 0.127)
		(layer "In5.Cu")
		(net "XM_ADDR_2")
	)
	(segment
		(start 180.862224 -56.107838)
		(end 180.862224 -56.28767)
		(width 0.127)
		(layer "In5.Cu")
		(net "XM_ADDR_2")
	)
	(segment
		(start 180.138832 -64.717676)
		(end 180.011832 -64.844676)
		(width 0.127)
		(layer "In5.Cu")
		(net "XM_ADDR_2")
	)
	(segment
		(start 180.138832 -66.241676)
		(end 180.303424 -66.241676)
		(width 0.127)
		(layer "In5.Cu")
		(net "XM_ADDR_2")
	)
	(segment
		(start 182.866538 -54.523894)
		(end 182.866538 -54.703218)
		(width 0.127)
		(layer "In5.Cu")
		(net "XM_ADDR_2")
	)
	(segment
		(start 182.925974 -54.044088)
		(end 182.745888 -54.224174)
		(width 0.127)
		(layer "In5.Cu")
		(net "XM_ADDR_2")
	)
	(segment
		(start 183.585358 -53.984398)
		(end 183.405272 -54.164484)
		(width 0.127)
		(layer "In5.Cu")
		(net "XM_ADDR_2")
	)
	(segment
		(start 180.011832 -60.186062)
		(end 180.011832 -62.050676)
		(width 0.127)
		(layer "In5.Cu")
		(net "XM_ADDR_2")
	)
	(segment
		(start 182.147718 -55.422038)
		(end 181.967632 -55.602124)
		(width 0.127)
		(layer "In5.Cu")
		(net "XM_ADDR_2")
	)
	(segment
		(start 180.011832 -56.95823)
		(end 180.011832 -57.392062)
		(width 0.127)
		(layer "In5.Cu")
		(net "XM_ADDR_2")
	)
	(segment
		(start 180.138832 -58.027062)
		(end 180.011832 -58.154062)
		(width 0.127)
		(layer "In5.Cu")
		(net "XM_ADDR_2")
	)
	(segment
		(start 180.011832 -63.828676)
		(end 180.011832 -64.082676)
		(width 0.127)
		(layer "In5.Cu")
		(net "XM_ADDR_2")
	)
	(segment
		(start 182.147718 -55.242714)
		(end 182.147718 -55.422038)
		(width 0.127)
		(layer "In5.Cu")
		(net "XM_ADDR_2")
	)
	(segment
		(start 180.48859 -63.320676)
		(end 180.48859 -63.574676)
		(width 0.127)
		(layer "In5.Cu")
		(net "XM_ADDR_2")
	)
	(segment
		(start 180.011832 -62.812676)
		(end 180.011832 -63.066676)
		(width 0.127)
		(layer "In5.Cu")
		(net "XM_ADDR_2")
	)
	(segment
		(start 180.138832 -57.519062)
		(end 180.351176 -57.519062)
		(width 0.127)
		(layer "In5.Cu")
		(net "XM_ADDR_2")
	)
	(segment
		(start 182.386478 -54.762908)
		(end 182.207154 -54.762908)
		(width 0.127)
		(layer "In5.Cu")
		(net "XM_ADDR_2")
	)
	(segment
		(start 180.011832 -63.066676)
		(end 180.138832 -63.193676)
		(width 0.127)
		(layer "In5.Cu")
		(net "XM_ADDR_2")
	)
	(segment
		(start 180.48859 -62.304676)
		(end 180.48859 -62.558676)
		(width 0.127)
		(layer "In5.Cu")
		(net "XM_ADDR_2")
	)
	(segment
		(start 180.989224 -56.594502)
		(end 180.809646 -56.77408)
		(width 0.127)
		(layer "In5.Cu")
		(net "XM_ADDR_2")
	)
	(segment
		(start 184.573926 -73.053194)
		(end 185.7502 -73.053194)
		(width 0.127)
		(layer "In5.Cu")
		(net "XM_ADDR_2")
	)
	(segment
		(start 182.242968 -69.823584)
		(end 182.063136 -69.823584)
		(width 0.127)
		(layer "In5.Cu")
		(net "XM_ADDR_2")
	)
	(segment
		(start 180.011832 -65.860676)
		(end 180.011832 -66.114676)
		(width 0.127)
		(layer "In5.Cu")
		(net "XM_ADDR_2")
	)
	(segment
		(start 180.011832 -62.050676)
		(end 180.138832 -62.177676)
		(width 0.127)
		(layer "In5.Cu")
		(net "XM_ADDR_2")
	)
	(segment
		(start 180.011832 -64.844676)
		(end 180.011832 -65.098676)
		(width 0.127)
		(layer "In5.Cu")
		(net "XM_ADDR_2")
	)
	(segment
		(start 180.36159 -63.193676)
		(end 180.48859 -63.320676)
		(width 0.127)
		(layer "In5.Cu")
		(net "XM_ADDR_2")
	)
	(segment
		(start 180.48859 -64.336676)
		(end 180.48859 -64.590676)
		(width 0.127)
		(layer "In5.Cu")
		(net "XM_ADDR_2")
	)
	(segment
		(start 182.507128 -54.883304)
		(end 182.386478 -54.762908)
		(width 0.127)
		(layer "In5.Cu")
		(net "XM_ADDR_2")
	)
	(segment
		(start 182.422546 -69.464174)
		(end 182.422546 -69.644006)
		(width 0.127)
		(layer "In5.Cu")
		(net "XM_ADDR_2")
	)
	(segment
		(start 181.667658 -55.481728)
		(end 181.488334 -55.481728)
		(width 0.127)
		(layer "In5.Cu")
		(net "XM_ADDR_2")
	)
	(segment
		(start 180.478176 -59.678062)
		(end 180.478176 -59.932062)
		(width 0.127)
		(layer "In5.Cu")
		(net "XM_ADDR_2")
	)
	(segment
		(start 180.351176 -58.027062)
		(end 180.138832 -58.027062)
		(width 0.127)
		(layer "In5.Cu")
		(net "XM_ADDR_2")
	)
	(segment
		(start 180.138832 -65.225676)
		(end 180.36159 -65.225676)
		(width 0.127)
		(layer "In5.Cu")
		(net "XM_ADDR_2")
	)
	(segment
		(start 180.011832 -64.082676)
		(end 180.138832 -64.209676)
		(width 0.127)
		(layer "In5.Cu")
		(net "XM_ADDR_2")
	)
	(segment
		(start 182.207154 -54.762908)
		(end 182.027068 -54.942994)
		(width 0.127)
		(layer "In5.Cu")
		(net "XM_ADDR_2")
	)
	(segment
		(start 180.48859 -65.606676)
		(end 180.36159 -65.733676)
		(width 0.127)
		(layer "In5.Cu")
		(net "XM_ADDR_2")
	)
	(segment
		(start 183.464708 -53.684678)
		(end 183.585358 -53.805074)
		(width 0.127)
		(layer "In5.Cu")
		(net "XM_ADDR_2")
	)
	(segment
		(start 182.063136 -69.823584)
		(end 180.38064 -68.141088)
		(width 0.127)
		(layer "In5.Cu")
		(net "XM_ADDR_2")
	)
	(segment
		(start 180.36159 -63.701676)
		(end 180.138832 -63.701676)
		(width 0.127)
		(layer "In5.Cu")
		(net "XM_ADDR_2")
	)
	(segment
		(start 180.303424 -66.241676)
		(end 180.430424 -66.368676)
		(width 0.127)
		(layer "In5.Cu")
		(net "XM_ADDR_2")
	)
	(segment
		(start 180.36159 -65.733676)
		(end 180.138832 -65.733676)
		(width 0.127)
		(layer "In5.Cu")
		(net "XM_ADDR_2")
	)
	(segment
		(start 180.478176 -58.662062)
		(end 180.478176 -58.916062)
		(width 0.127)
		(layer "In5.Cu")
		(net "XM_ADDR_2")
	)
	(segment
		(start 180.011832 -58.154062)
		(end 180.011832 -58.408062)
		(width 0.127)
		(layer "In5.Cu")
		(net "XM_ADDR_2")
	)
	(segment
		(start 182.745888 -54.224174)
		(end 182.745888 -54.403498)
		(width 0.127)
		(layer "In5.Cu")
		(net "XM_ADDR_2")
	)
	(segment
		(start 181.967632 -55.602124)
		(end 181.788308 -55.602124)
		(width 0.127)
		(layer "In5.Cu")
		(net "XM_ADDR_2")
	)
	(segment
		(start 180.138832 -62.685676)
		(end 180.011832 -62.812676)
		(width 0.127)
		(layer "In5.Cu")
		(net "XM_ADDR_2")
	)
	(segment
		(start 180.36159 -62.685676)
		(end 180.138832 -62.685676)
		(width 0.127)
		(layer "In5.Cu")
		(net "XM_ADDR_2")
	)
	(segment
		(start 180.351176 -57.519062)
		(end 180.478176 -57.646062)
		(width 0.127)
		(layer "In5.Cu")
		(net "XM_ADDR_2")
	)
	(segment
		(start 180.430424 -66.622676)
		(end 180.303424 -66.749676)
		(width 0.127)
		(layer "In5.Cu")
		(net "XM_ADDR_2")
	)
	(segment
		(start 184.999884 -47.599854)
		(end 185.39968 -47.200058)
		(width 0.127)
		(layer "F.Cu")
		(net "XM_ADDR_19")
	)
	(via
		(at 195.741798 -68.007484)
		(size 0.508)
		(drill 0.254)
		(layers "F.Cu" "B.Cu")
		(net "XM_ADDR_19")
	)
	(via
		(at 185.39968 -47.200058)
		(size 0.508)
		(drill 0.254)
		(layers "F.Cu" "B.Cu")
		(net "XM_ADDR_19")
	)
	(segment
		(start 185.631582 -68.322698)
		(end 195.426584 -68.322698)
		(width 0.127)
		(layer "B.Cu")
		(net "XM_ADDR_19")
	)
	(segment
		(start 186.090306 -47.200058)
		(end 186.446922 -47.556674)
		(width 0.127)
		(layer "B.Cu")
		(net "XM_ADDR_19")
	)
	(segment
		(start 184.926986 -69.027294)
		(end 185.631582 -68.322698)
		(width 0.127)
		(layer "B.Cu")
		(net "XM_ADDR_19")
	)
	(segment
		(start 195.426584 -68.322698)
		(end 195.741798 -68.007484)
		(width 0.127)
		(layer "B.Cu")
		(net "XM_ADDR_19")
	)
	(segment
		(start 185.39968 -47.200058)
		(end 186.090306 -47.200058)
		(width 0.127)
		(layer "B.Cu")
		(net "XM_ADDR_19")
	)
	(segment
		(start 183.99252 -69.027294)
		(end 184.926986 -69.027294)
		(width 0.127)
		(layer "B.Cu")
		(net "XM_ADDR_19")
	)
	(segment
		(start 193.691764 -54.02072)
		(end 193.531744 -53.8607)
		(width 0.127)
		(layer "In5.Cu")
		(net "XM_ADDR_19")
	)
	(segment
		(start 192.18783 -49.671224)
		(end 189.624716 -47.10811)
		(width 0.127)
		(layer "In5.Cu")
		(net "XM_ADDR_19")
	)
	(segment
		(start 193.691764 -54.705504)
		(end 193.691764 -54.02072)
		(width 0.127)
		(layer "In5.Cu")
		(net "XM_ADDR_19")
	)
	(segment
		(start 189.624716 -47.10811)
		(end 188.739272 -47.10811)
		(width 0.127)
		(layer "In5.Cu")
		(net "XM_ADDR_19")
	)
	(segment
		(start 195.741798 -68.007484)
		(end 195.25742 -67.523106)
		(width 0.127)
		(layer "In5.Cu")
		(net "XM_ADDR_19")
	)
	(segment
		(start 195.25742 -67.523106)
		(end 195.25742 -65.76949)
		(width 0.127)
		(layer "In5.Cu")
		(net "XM_ADDR_19")
	)
	(segment
		(start 195.317364 -56.331104)
		(end 193.691764 -54.705504)
		(width 0.127)
		(layer "In5.Cu")
		(net "XM_ADDR_19")
	)
	(segment
		(start 188.739272 -47.10811)
		(end 188.637672 -47.20971)
		(width 0.127)
		(layer "In5.Cu")
		(net "XM_ADDR_19")
	)
	(segment
		(start 196.290692 -56.331104)
		(end 195.317364 -56.331104)
		(width 0.127)
		(layer "In5.Cu")
		(net "XM_ADDR_19")
	)
	(segment
		(start 187.520072 -47.20971)
		(end 187.51042 -47.200058)
		(width 0.127)
		(layer "In5.Cu")
		(net "XM_ADDR_19")
	)
	(segment
		(start 195.25742 -65.76949)
		(end 195.741798 -65.285112)
		(width 0.127)
		(layer "In5.Cu")
		(net "XM_ADDR_19")
	)
	(segment
		(start 192.919858 -53.8607)
		(end 192.745106 -53.685948)
		(width 0.127)
		(layer "In5.Cu")
		(net "XM_ADDR_19")
	)
	(segment
		(start 188.637672 -47.20971)
		(end 187.520072 -47.20971)
		(width 0.127)
		(layer "In5.Cu")
		(net "XM_ADDR_19")
	)
	(segment
		(start 197.21068 -57.251092)
		(end 196.290692 -56.331104)
		(width 0.127)
		(layer "In5.Cu")
		(net "XM_ADDR_19")
	)
	(segment
		(start 195.741798 -64.225678)
		(end 197.21068 -62.756796)
		(width 0.127)
		(layer "In5.Cu")
		(net "XM_ADDR_19")
	)
	(segment
		(start 192.745106 -52.719732)
		(end 192.18783 -52.162456)
		(width 0.127)
		(layer "In5.Cu")
		(net "XM_ADDR_19")
	)
	(segment
		(start 187.51042 -47.200058)
		(end 185.39968 -47.200058)
		(width 0.127)
		(layer "In5.Cu")
		(net "XM_ADDR_19")
	)
	(segment
		(start 193.531744 -53.8607)
		(end 192.919858 -53.8607)
		(width 0.127)
		(layer "In5.Cu")
		(net "XM_ADDR_19")
	)
	(segment
		(start 197.21068 -62.756796)
		(end 197.21068 -57.251092)
		(width 0.127)
		(layer "In5.Cu")
		(net "XM_ADDR_19")
	)
	(segment
		(start 192.745106 -53.685948)
		(end 192.745106 -52.719732)
		(width 0.127)
		(layer "In5.Cu")
		(net "XM_ADDR_19")
	)
	(segment
		(start 192.18783 -52.162456)
		(end 192.18783 -49.671224)
		(width 0.127)
		(layer "In5.Cu")
		(net "XM_ADDR_19")
	)
	(segment
		(start 195.741798 -65.285112)
		(end 195.741798 -64.225678)
		(width 0.127)
		(layer "In5.Cu")
		(net "XM_ADDR_19")
	)
	(segment
		(start 186.850528 -45.74921)
		(end 186.59983 -45.999908)
		(width 0.127)
		(layer "F.Cu")
		(net "XM_ADDR_18")
	)
	(segment
		(start 188.049408 -45.74921)
		(end 186.850528 -45.74921)
		(width 0.127)
		(layer "F.Cu")
		(net "XM_ADDR_18")
	)
	(via
		(at 196.757798 -68.007484)
		(size 0.508)
		(drill 0.254)
		(layers "F.Cu" "B.Cu")
		(net "XM_ADDR_18")
	)
	(via
		(at 188.049408 -45.74921)
		(size 0.508)
		(drill 0.254)
		(layers "F.Cu" "B.Cu")
		(net "XM_ADDR_18")
	)
	(segment
		(start 195.934584 -68.830698)
		(end 196.757798 -68.007484)
		(width 0.127)
		(layer "B.Cu")
		(net "XM_ADDR_18")
	)
	(segment
		(start 188.942218 -45.74921)
		(end 189.427612 -45.263816)
		(width 0.127)
		(layer "B.Cu")
		(net "XM_ADDR_18")
	)
	(segment
		(start 185.193178 -69.527674)
		(end 185.890154 -68.830698)
		(width 0.127)
		(layer "B.Cu")
		(net "XM_ADDR_18")
	)
	(segment
		(start 188.049408 -45.74921)
		(end 188.942218 -45.74921)
		(width 0.127)
		(layer "B.Cu")
		(net "XM_ADDR_18")
	)
	(segment
		(start 185.890154 -68.830698)
		(end 195.934584 -68.830698)
		(width 0.127)
		(layer "B.Cu")
		(net "XM_ADDR_18")
	)
	(segment
		(start 183.99252 -69.527674)
		(end 185.193178 -69.527674)
		(width 0.127)
		(layer "B.Cu")
		(net "XM_ADDR_18")
	)
	(segment
		(start 195.283582 -53.10251)
		(end 194.269106 -52.088034)
		(width 0.127)
		(layer "In5.Cu")
		(net "XM_ADDR_18")
	)
	(segment
		(start 196.547232 -66.483484)
		(end 196.968364 -66.483484)
		(width 0.127)
		(layer "In5.Cu")
		(net "XM_ADDR_18")
	)
	(segment
		(start 196.968364 -66.483484)
		(end 198.840598 -64.61125)
		(width 0.127)
		(layer "In5.Cu")
		(net "XM_ADDR_18")
	)
	(segment
		(start 190.154814 -45.48251)
		(end 188.316108 -45.48251)
		(width 0.127)
		(layer "In5.Cu")
		(net "XM_ADDR_18")
	)
	(segment
		(start 188.316108 -45.48251)
		(end 188.049408 -45.74921)
		(width 0.127)
		(layer "In5.Cu")
		(net "XM_ADDR_18")
	)
	(segment
		(start 194.269106 -49.596802)
		(end 190.154814 -45.48251)
		(width 0.127)
		(layer "In5.Cu")
		(net "XM_ADDR_18")
	)
	(segment
		(start 198.840598 -64.61125)
		(end 198.840598 -56.698896)
		(width 0.127)
		(layer "In5.Cu")
		(net "XM_ADDR_18")
	)
	(segment
		(start 198.840598 -56.698896)
		(end 196.63156 -54.489858)
		(width 0.127)
		(layer "In5.Cu")
		(net "XM_ADDR_18")
	)
	(segment
		(start 196.63156 -54.489858)
		(end 195.631816 -54.489858)
		(width 0.127)
		(layer "In5.Cu")
		(net "XM_ADDR_18")
	)
	(segment
		(start 196.757798 -68.007484)
		(end 196.249798 -67.499484)
		(width 0.127)
		(layer "In5.Cu")
		(net "XM_ADDR_18")
	)
	(segment
		(start 196.249798 -66.780918)
		(end 196.547232 -66.483484)
		(width 0.127)
		(layer "In5.Cu")
		(net "XM_ADDR_18")
	)
	(segment
		(start 195.283582 -54.141624)
		(end 195.283582 -53.10251)
		(width 0.127)
		(layer "In5.Cu")
		(net "XM_ADDR_18")
	)
	(segment
		(start 195.631816 -54.489858)
		(end 195.283582 -54.141624)
		(width 0.127)
		(layer "In5.Cu")
		(net "XM_ADDR_18")
	)
	(segment
		(start 194.269106 -52.088034)
		(end 194.269106 -49.596802)
		(width 0.127)
		(layer "In5.Cu")
		(net "XM_ADDR_18")
	)
	(segment
		(start 196.249798 -67.499484)
		(end 196.249798 -66.780918)
		(width 0.127)
		(layer "In5.Cu")
		(net "XM_ADDR_18")
	)
	(segment
		(start 189.35319 -51.224942)
		(end 188.394848 -50.2666)
		(width 0.127)
		(layer "F.Cu")
		(net "XM_ADDR_17")
	)
	(segment
		(start 187.66663 -50.2666)
		(end 186.59983 -49.1998)
		(width 0.127)
		(layer "F.Cu")
		(net "XM_ADDR_17")
	)
	(segment
		(start 188.394848 -50.2666)
		(end 187.66663 -50.2666)
		(width 0.127)
		(layer "F.Cu")
		(net "XM_ADDR_17")
	)
	(via
		(at 189.35319 -51.224942)
		(size 0.508)
		(drill 0.254)
		(layers "F.Cu" "B.Cu")
		(net "XM_ADDR_17")
	)
	(via
		(at 192.927732 -62.807596)
		(size 0.508)
		(drill 0.254)
		(layers "F.Cu" "B.Cu")
		(net "XM_ADDR_17")
	)
	(segment
		(start 195.046854 -62.70371)
		(end 194.919854 -62.83071)
		(width 0.127)
		(layer "B.Cu")
		(net "XM_ADDR_17")
	)
	(segment
		(start 194.919854 -62.83071)
		(end 194.665854 -62.83071)
		(width 0.127)
		(layer "B.Cu")
		(net "XM_ADDR_17")
	)
	(segment
		(start 194.538854 -62.296294)
		(end 194.411854 -62.169294)
		(width 0.127)
		(layer "B.Cu")
		(net "XM_ADDR_17")
	)
	(segment
		(start 197.586854 -61.059314)
		(end 197.459854 -60.932314)
		(width 0.127)
		(layer "B.Cu")
		(net "XM_ADDR_17")
	)
	(segment
		(start 198.602854 -61.81979)
		(end 198.475854 -61.69279)
		(width 0.127)
		(layer "B.Cu")
		(net "XM_ADDR_17")
	)
	(segment
		(start 195.681854 -62.446154)
		(end 195.554854 -62.319154)
		(width 0.127)
		(layer "B.Cu")
		(net "XM_ADDR_17")
	)
	(segment
		(start 201.650854 -60.995814)
		(end 201.523854 -60.868814)
		(width 0.127)
		(layer "B.Cu")
		(net "XM_ADDR_17")
	)
	(segment
		(start 201.650854 -61.399674)
		(end 201.650854 -60.995814)
		(width 0.127)
		(layer "B.Cu")
		(net "XM_ADDR_17")
	)
	(segment
		(start 188.716412 -51.86172)
		(end 189.35319 -51.224942)
		(width 0.127)
		(layer "B.Cu")
		(net "XM_ADDR_17")
	)
	(segment
		(start 201.142854 -62.319154)
		(end 201.015854 -62.446154)
		(width 0.127)
		(layer "B.Cu")
		(net "XM_ADDR_17")
	)
	(segment
		(start 196.570854 -62.319154)
		(end 196.570854 -61.069728)
		(width 0.127)
		(layer "B.Cu")
		(net "XM_ADDR_17")
	)
	(segment
		(start 200.126854 -62.319154)
		(end 199.999854 -62.446154)
		(width 0.127)
		(layer "B.Cu")
		(net "XM_ADDR_17")
	)
	(segment
		(start 195.554854 -62.319154)
		(end 195.554854 -62.069726)
		(width 0.127)
		(layer "B.Cu")
		(net "XM_ADDR_17")
	)
	(segment
		(start 196.443854 -60.942728)
		(end 196.189854 -60.942728)
		(width 0.127)
		(layer "B.Cu")
		(net "XM_ADDR_17")
	)
	(segment
		(start 194.030854 -62.680596)
		(end 193.903854 -62.807596)
		(width 0.127)
		(layer "B.Cu")
		(net "XM_ADDR_17")
	)
	(segment
		(start 200.126854 -60.873386)
		(end 200.126854 -62.319154)
		(width 0.127)
		(layer "B.Cu")
		(net "XM_ADDR_17")
	)
	(segment
		(start 198.602854 -62.319154)
		(end 198.602854 -61.81979)
		(width 0.127)
		(layer "B.Cu")
		(net "XM_ADDR_17")
	)
	(segment
		(start 199.618854 -62.319154)
		(end 199.618854 -60.857638)
		(width 0.127)
		(layer "B.Cu")
		(net "XM_ADDR_17")
	)
	(segment
		(start 195.046854 -62.069726)
		(end 195.046854 -62.70371)
		(width 0.127)
		(layer "B.Cu")
		(net "XM_ADDR_17")
	)
	(segment
		(start 197.205854 -60.932314)
		(end 197.078854 -61.059314)
		(width 0.127)
		(layer "B.Cu")
		(net "XM_ADDR_17")
	)
	(segment
		(start 196.951854 -62.446154)
		(end 196.697854 -62.446154)
		(width 0.127)
		(layer "B.Cu")
		(net "XM_ADDR_17")
	)
	(segment
		(start 194.157854 -62.169294)
		(end 194.030854 -62.296294)
		(width 0.127)
		(layer "B.Cu")
		(net "XM_ADDR_17")
	)
	(segment
		(start 194.665854 -62.83071)
		(end 194.538854 -62.70371)
		(width 0.127)
		(layer "B.Cu")
		(net "XM_ADDR_17")
	)
	(segment
		(start 196.062854 -61.069728)
		(end 196.062854 -62.319154)
		(width 0.127)
		(layer "B.Cu")
		(net "XM_ADDR_17")
	)
	(segment
		(start 200.634854 -60.873386)
		(end 200.507854 -60.746386)
		(width 0.127)
		(layer "B.Cu")
		(net "XM_ADDR_17")
	)
	(segment
		(start 197.586854 -62.319154)
		(end 197.586854 -61.059314)
		(width 0.127)
		(layer "B.Cu")
		(net "XM_ADDR_17")
	)
	(segment
		(start 196.189854 -60.942728)
		(end 196.062854 -61.069728)
		(width 0.127)
		(layer "B.Cu")
		(net "XM_ADDR_17")
	)
	(segment
		(start 194.030854 -62.296294)
		(end 194.030854 -62.680596)
		(width 0.127)
		(layer "B.Cu")
		(net "XM_ADDR_17")
	)
	(segment
		(start 197.078854 -62.319154)
		(end 196.951854 -62.446154)
		(width 0.127)
		(layer "B.Cu")
		(net "XM_ADDR_17")
	)
	(segment
		(start 195.554854 -62.069726)
		(end 195.427854 -61.942726)
		(width 0.127)
		(layer "B.Cu")
		(net "XM_ADDR_17")
	)
	(segment
		(start 198.475854 -61.69279)
		(end 198.221854 -61.69279)
		(width 0.127)
		(layer "B.Cu")
		(net "XM_ADDR_17")
	)
	(segment
		(start 200.761854 -62.446154)
		(end 200.634854 -62.319154)
		(width 0.127)
		(layer "B.Cu")
		(net "XM_ADDR_17")
	)
	(segment
		(start 193.903854 -62.807596)
		(end 192.927732 -62.807596)
		(width 0.127)
		(layer "B.Cu")
		(net "XM_ADDR_17")
	)
	(segment
		(start 199.745854 -62.446154)
		(end 199.618854 -62.319154)
		(width 0.127)
		(layer "B.Cu")
		(net "XM_ADDR_17")
	)
	(segment
		(start 201.269854 -60.868814)
		(end 201.142854 -60.995814)
		(width 0.127)
		(layer "B.Cu")
		(net "XM_ADDR_17")
	)
	(segment
		(start 195.173854 -61.942726)
		(end 195.046854 -62.069726)
		(width 0.127)
		(layer "B.Cu")
		(net "XM_ADDR_17")
	)
	(segment
		(start 196.697854 -62.446154)
		(end 196.570854 -62.319154)
		(width 0.127)
		(layer "B.Cu")
		(net "XM_ADDR_17")
	)
	(segment
		(start 199.491854 -60.730638)
		(end 199.237854 -60.730638)
		(width 0.127)
		(layer "B.Cu")
		(net "XM_ADDR_17")
	)
	(segment
		(start 201.523854 -60.868814)
		(end 201.269854 -60.868814)
		(width 0.127)
		(layer "B.Cu")
		(net "XM_ADDR_17")
	)
	(segment
		(start 199.237854 -60.730638)
		(end 199.110854 -60.857638)
		(width 0.127)
		(layer "B.Cu")
		(net "XM_ADDR_17")
	)
	(segment
		(start 199.110854 -60.857638)
		(end 199.110854 -62.319154)
		(width 0.127)
		(layer "B.Cu")
		(net "XM_ADDR_17")
	)
	(segment
		(start 198.094854 -62.319154)
		(end 197.967854 -62.446154)
		(width 0.127)
		(layer "B.Cu")
		(net "XM_ADDR_17")
	)
	(segment
		(start 196.062854 -62.319154)
		(end 195.935854 -62.446154)
		(width 0.127)
		(layer "B.Cu")
		(net "XM_ADDR_17")
	)
	(segment
		(start 201.015854 -62.446154)
		(end 200.761854 -62.446154)
		(width 0.127)
		(layer "B.Cu")
		(net "XM_ADDR_17")
	)
	(segment
		(start 201.142854 -60.995814)
		(end 201.142854 -62.319154)
		(width 0.127)
		(layer "B.Cu")
		(net "XM_ADDR_17")
	)
	(segment
		(start 200.253854 -60.746386)
		(end 200.126854 -60.873386)
		(width 0.127)
		(layer "B.Cu")
		(net "XM_ADDR_17")
	)
	(segment
		(start 197.713854 -62.446154)
		(end 197.586854 -62.319154)
		(width 0.127)
		(layer "B.Cu")
		(net "XM_ADDR_17")
	)
	(segment
		(start 197.459854 -60.932314)
		(end 197.205854 -60.932314)
		(width 0.127)
		(layer "B.Cu")
		(net "XM_ADDR_17")
	)
	(segment
		(start 198.221854 -61.69279)
		(end 198.094854 -61.81979)
		(width 0.127)
		(layer "B.Cu")
		(net "XM_ADDR_17")
	)
	(segment
		(start 198.094854 -61.81979)
		(end 198.094854 -62.319154)
		(width 0.127)
		(layer "B.Cu")
		(net "XM_ADDR_17")
	)
	(segment
		(start 194.538854 -62.70371)
		(end 194.538854 -62.296294)
		(width 0.127)
		(layer "B.Cu")
		(net "XM_ADDR_17")
	)
	(segment
		(start 188.716412 -52.375308)
		(end 188.716412 -51.86172)
		(width 0.127)
		(layer "B.Cu")
		(net "XM_ADDR_17")
	)
	(segment
		(start 194.411854 -62.169294)
		(end 194.157854 -62.169294)
		(width 0.127)
		(layer "B.Cu")
		(net "XM_ADDR_17")
	)
	(segment
		(start 195.427854 -61.942726)
		(end 195.173854 -61.942726)
		(width 0.127)
		(layer "B.Cu")
		(net "XM_ADDR_17")
	)
	(segment
		(start 199.618854 -60.857638)
		(end 199.491854 -60.730638)
		(width 0.127)
		(layer "B.Cu")
		(net "XM_ADDR_17")
	)
	(segment
		(start 197.967854 -62.446154)
		(end 197.713854 -62.446154)
		(width 0.127)
		(layer "B.Cu")
		(net "XM_ADDR_17")
	)
	(segment
		(start 198.729854 -62.446154)
		(end 198.602854 -62.319154)
		(width 0.127)
		(layer "B.Cu")
		(net "XM_ADDR_17")
	)
	(segment
		(start 196.570854 -61.069728)
		(end 196.443854 -60.942728)
		(width 0.127)
		(layer "B.Cu")
		(net "XM_ADDR_17")
	)
	(segment
		(start 200.507854 -60.746386)
		(end 200.253854 -60.746386)
		(width 0.127)
		(layer "B.Cu")
		(net "XM_ADDR_17")
	)
	(segment
		(start 199.110854 -62.319154)
		(end 198.983854 -62.446154)
		(width 0.127)
		(layer "B.Cu")
		(net "XM_ADDR_17")
	)
	(segment
		(start 200.634854 -62.319154)
		(end 200.634854 -60.873386)
		(width 0.127)
		(layer "B.Cu")
		(net "XM_ADDR_17")
	)
	(segment
		(start 197.078854 -61.059314)
		(end 197.078854 -62.319154)
		(width 0.127)
		(layer "B.Cu")
		(net "XM_ADDR_17")
	)
	(segment
		(start 198.983854 -62.446154)
		(end 198.729854 -62.446154)
		(width 0.127)
		(layer "B.Cu")
		(net "XM_ADDR_17")
	)
	(segment
		(start 195.935854 -62.446154)
		(end 195.681854 -62.446154)
		(width 0.127)
		(layer "B.Cu")
		(net "XM_ADDR_17")
	)
	(segment
		(start 201.777854 -61.526674)
		(end 201.650854 -61.399674)
		(width 0.127)
		(layer "B.Cu")
		(net "XM_ADDR_17")
	)
	(segment
		(start 203.22032 -61.526674)
		(end 201.777854 -61.526674)
		(width 0.127)
		(layer "B.Cu")
		(net "XM_ADDR_17")
	)
	(segment
		(start 199.999854 -62.446154)
		(end 199.745854 -62.446154)
		(width 0.127)
		(layer "B.Cu")
		(net "XM_ADDR_17")
	)
	(segment
		(start 189.64783 -51.519582)
		(end 189.35319 -51.224942)
		(width 0.127)
		(layer "In5.Cu")
		(net "XM_ADDR_17")
	)
	(segment
		(start 192.927732 -62.807596)
		(end 192.419732 -62.299596)
		(width 0.127)
		(layer "In5.Cu")
		(net "XM_ADDR_17")
	)
	(segment
		(start 192.419732 -58.609992)
		(end 190.205106 -56.395366)
		(width 0.127)
		(layer "In5.Cu")
		(net "XM_ADDR_17")
	)
	(segment
		(start 192.419732 -62.299596)
		(end 192.419732 -58.609992)
		(width 0.127)
		(layer "In5.Cu")
		(net "XM_ADDR_17")
	)
	(segment
		(start 190.205106 -53.772562)
		(end 189.64783 -53.215286)
		(width 0.127)
		(layer "In5.Cu")
		(net "XM_ADDR_17")
	)
	(segment
		(start 190.205106 -56.395366)
		(end 190.205106 -53.772562)
		(width 0.127)
		(layer "In5.Cu")
		(net "XM_ADDR_17")
	)
	(segment
		(start 189.64783 -53.215286)
		(end 189.64783 -51.519582)
		(width 0.127)
		(layer "In5.Cu")
		(net "XM_ADDR_17")
	)
	(segment
		(start 190.155576 -49.406556)
		(end 190.155576 -48.526954)
		(width 0.127)
		(layer "F.Cu")
		(net "XM_ADDR_16")
	)
	(segment
		(start 190.155576 -48.176942)
		(end 190.155576 -48.526954)
		(width 0.127)
		(layer "F.Cu")
		(net "XM_ADDR_16")
	)
	(segment
		(start 189.35319 -50.208942)
		(end 190.155576 -49.406556)
		(width 0.127)
		(layer "F.Cu")
		(net "XM_ADDR_16")
	)
	(segment
		(start 188.188854 -47.228506)
		(end 188.30925 -47.10811)
		(width 0.127)
		(layer "F.Cu")
		(net "XM_ADDR_16")
	)
	(segment
		(start 186.171332 -47.228506)
		(end 188.188854 -47.228506)
		(width 0.127)
		(layer "F.Cu")
		(net "XM_ADDR_16")
	)
	(segment
		(start 188.30925 -47.10811)
		(end 189.086744 -47.10811)
		(width 0.127)
		(layer "F.Cu")
		(net "XM_ADDR_16")
	)
	(segment
		(start 185.799984 -47.599854)
		(end 186.171332 -47.228506)
		(width 0.127)
		(layer "F.Cu")
		(net "XM_ADDR_16")
	)
	(segment
		(start 189.086744 -47.10811)
		(end 190.155576 -48.176942)
		(width 0.127)
		(layer "F.Cu")
		(net "XM_ADDR_16")
	)
	(via
		(at 192.927732 -61.220858)
		(size 0.508)
		(drill 0.254)
		(layers "F.Cu" "B.Cu")
		(net "XM_ADDR_16")
	)
	(via
		(at 189.35319 -50.208942)
		(size 0.508)
		(drill 0.254)
		(layers "F.Cu" "B.Cu")
		(net "XM_ADDR_16")
	)
	(segment
		(start 183.99252 -61.526674)
		(end 185.269378 -61.526674)
		(width 0.127)
		(layer "B.Cu")
		(net "XM_ADDR_16")
	)
	(segment
		(start 193.289174 -60.712858)
		(end 186.819286 -60.712858)
		(width 0.127)
		(layer "B.Cu")
		(net "XM_ADDR_16")
	)
	(segment
		(start 186.591194 -60.204858)
		(end 193.289174 -60.204858)
		(width 0.127)
		(layer "B.Cu")
		(net "XM_ADDR_16")
	)
	(segment
		(start 193.416174 -60.585858)
		(end 193.289174 -60.712858)
		(width 0.127)
		(layer "B.Cu")
		(net "XM_ADDR_16")
	)
	(segment
		(start 186.819286 -60.712858)
		(end 186.692286 -60.839858)
		(width 0.127)
		(layer "B.Cu")
		(net "XM_ADDR_16")
	)
	(segment
		(start 186.692286 -61.093858)
		(end 186.819286 -61.220858)
		(width 0.127)
		(layer "B.Cu")
		(net "XM_ADDR_16")
	)
	(segment
		(start 186.692286 -60.839858)
		(end 186.692286 -61.093858)
		(width 0.127)
		(layer "B.Cu")
		(net "XM_ADDR_16")
	)
	(segment
		(start 193.289174 -60.204858)
		(end 193.416174 -60.331858)
		(width 0.127)
		(layer "B.Cu")
		(net "XM_ADDR_16")
	)
	(segment
		(start 186.819286 -61.220858)
		(end 192.927732 -61.220858)
		(width 0.127)
		(layer "B.Cu")
		(net "XM_ADDR_16")
	)
	(segment
		(start 185.269378 -61.526674)
		(end 186.591194 -60.204858)
		(width 0.127)
		(layer "B.Cu")
		(net "XM_ADDR_16")
	)
	(segment
		(start 193.416174 -60.331858)
		(end 193.416174 -60.585858)
		(width 0.127)
		(layer "B.Cu")
		(net "XM_ADDR_16")
	)
	(segment
		(start 189.35319 -50.208942)
		(end 190.15583 -51.011582)
		(width 0.127)
		(layer "In5.Cu")
		(net "XM_ADDR_16")
	)
	(segment
		(start 190.15583 -51.011582)
		(end 190.15583 -53.00472)
		(width 0.127)
		(layer "In5.Cu")
		(net "XM_ADDR_16")
	)
	(segment
		(start 190.713106 -56.1848)
		(end 192.927732 -58.399426)
		(width 0.127)
		(layer "In5.Cu")
		(net "XM_ADDR_16")
	)
	(segment
		(start 190.713106 -53.561996)
		(end 190.713106 -56.1848)
		(width 0.127)
		(layer "In5.Cu")
		(net "XM_ADDR_16")
	)
	(segment
		(start 192.927732 -58.399426)
		(end 192.927732 -61.220858)
		(width 0.127)
		(layer "In5.Cu")
		(net "XM_ADDR_16")
	)
	(segment
		(start 190.15583 -53.00472)
		(end 190.713106 -53.561996)
		(width 0.127)
		(layer "In5.Cu")
		(net "XM_ADDR_16")
	)
	(segment
		(start 184.999884 -46.800008)
		(end 185.39968 -46.400212)
		(width 0.127)
		(layer "F.Cu")
		(net "XM_ADDR_15")
	)
	(via
		(at 198.332598 -61.18479)
		(size 0.508)
		(drill 0.254)
		(layers "F.Cu" "B.Cu")
		(net "XM_ADDR_15")
	)
	(via
		(at 185.39968 -46.400212)
		(size 0.508)
		(drill 0.254)
		(layers "F.Cu" "B.Cu")
		(net "XM_ADDR_15")
	)
	(segment
		(start 198.332598 -61.18479)
		(end 198.332598 -60.381896)
		(width 0.127)
		(layer "B.Cu")
		(net "XM_ADDR_15")
	)
	(segment
		(start 193.84645 -61.76391)
		(end 185.784998 -61.76391)
		(width 0.127)
		(layer "B.Cu")
		(net "XM_ADDR_15")
	)
	(segment
		(start 198.332598 -60.381896)
		(end 198.205598 -60.254896)
		(width 0.127)
		(layer "B.Cu")
		(net "XM_ADDR_15")
	)
	(segment
		(start 194.48145 -60.4139)
		(end 194.35445 -60.2869)
		(width 0.127)
		(layer "B.Cu")
		(net "XM_ADDR_15")
	)
	(segment
		(start 194.98945 -61.340492)
		(end 194.86245 -61.467492)
		(width 0.127)
		(layer "B.Cu")
		(net "XM_ADDR_15")
	)
	(segment
		(start 185.784998 -61.76391)
		(end 185.521854 -62.027054)
		(width 0.127)
		(layer "B.Cu")
		(net "XM_ADDR_15")
	)
	(segment
		(start 193.97345 -60.4139)
		(end 193.97345 -61.63691)
		(width 0.127)
		(layer "B.Cu")
		(net "XM_ADDR_15")
	)
	(segment
		(start 195.11645 -60.254896)
		(end 194.98945 -60.381896)
		(width 0.127)
		(layer "B.Cu")
		(net "XM_ADDR_15")
	)
	(segment
		(start 198.205598 -60.254896)
		(end 195.11645 -60.254896)
		(width 0.127)
		(layer "B.Cu")
		(net "XM_ADDR_15")
	)
	(segment
		(start 194.48145 -61.340492)
		(end 194.48145 -60.4139)
		(width 0.127)
		(layer "B.Cu")
		(net "XM_ADDR_15")
	)
	(segment
		(start 185.521854 -62.027054)
		(end 183.99252 -62.027054)
		(width 0.127)
		(layer "B.Cu")
		(net "XM_ADDR_15")
	)
	(segment
		(start 194.60845 -61.467492)
		(end 194.48145 -61.340492)
		(width 0.127)
		(layer "B.Cu")
		(net "XM_ADDR_15")
	)
	(segment
		(start 194.86245 -61.467492)
		(end 194.60845 -61.467492)
		(width 0.127)
		(layer "B.Cu")
		(net "XM_ADDR_15")
	)
	(segment
		(start 194.10045 -60.2869)
		(end 193.97345 -60.4139)
		(width 0.127)
		(layer "B.Cu")
		(net "XM_ADDR_15")
	)
	(segment
		(start 194.35445 -60.2869)
		(end 194.10045 -60.2869)
		(width 0.127)
		(layer "B.Cu")
		(net "XM_ADDR_15")
	)
	(segment
		(start 193.97345 -61.63691)
		(end 193.84645 -61.76391)
		(width 0.127)
		(layer "B.Cu")
		(net "XM_ADDR_15")
	)
	(segment
		(start 194.98945 -60.381896)
		(end 194.98945 -61.340492)
		(width 0.127)
		(layer "B.Cu")
		(net "XM_ADDR_15")
	)
	(segment
		(start 188.18606 -46.226222)
		(end 188.421772 -45.99051)
		(width 0.127)
		(layer "In5.Cu")
		(net "XM_ADDR_15")
	)
	(segment
		(start 185.57367 -46.226222)
		(end 188.18606 -46.226222)
		(width 0.127)
		(layer "In5.Cu")
		(net "XM_ADDR_15")
	)
	(segment
		(start 196.545962 -55.149242)
		(end 198.332598 -56.935878)
		(width 0.127)
		(layer "In5.Cu")
		(net "XM_ADDR_15")
	)
	(segment
		(start 194.708526 -53.24602)
		(end 194.708526 -54.285134)
		(width 0.127)
		(layer "In5.Cu")
		(net "XM_ADDR_15")
	)
	(segment
		(start 194.708526 -54.285134)
		(end 195.572634 -55.149242)
		(width 0.127)
		(layer "In5.Cu")
		(net "XM_ADDR_15")
	)
	(segment
		(start 189.944248 -45.99051)
		(end 193.761106 -49.807368)
		(width 0.127)
		(layer "In5.Cu")
		(net "XM_ADDR_15")
	)
	(segment
		(start 195.572634 -55.149242)
		(end 196.545962 -55.149242)
		(width 0.127)
		(layer "In5.Cu")
		(net "XM_ADDR_15")
	)
	(segment
		(start 193.761106 -49.807368)
		(end 193.761106 -52.2986)
		(width 0.127)
		(layer "In5.Cu")
		(net "XM_ADDR_15")
	)
	(segment
		(start 188.421772 -45.99051)
		(end 189.944248 -45.99051)
		(width 0.127)
		(layer "In5.Cu")
		(net "XM_ADDR_15")
	)
	(segment
		(start 185.39968 -46.400212)
		(end 185.57367 -46.226222)
		(width 0.127)
		(layer "In5.Cu")
		(net "XM_ADDR_15")
	)
	(segment
		(start 198.332598 -56.935878)
		(end 198.332598 -61.18479)
		(width 0.127)
		(layer "In5.Cu")
		(net "XM_ADDR_15")
	)
	(segment
		(start 193.761106 -52.2986)
		(end 194.708526 -53.24602)
		(width 0.127)
		(layer "In5.Cu")
		(net "XM_ADDR_15")
	)
	(segment
		(start 186.59983 -48.399954)
		(end 187.557664 -48.399954)
		(width 0.127)
		(layer "F.Cu")
		(net "XM_ADDR_14")
	)
	(via
		(at 187.557664 -48.399954)
		(size 0.508)
		(drill 0.254)
		(layers "F.Cu" "B.Cu")
		(net "XM_ADDR_14")
	)
	(via
		(at 193.416936 -63.901574)
		(size 0.508)
		(drill 0.254)
		(layers "F.Cu" "B.Cu")
		(net "XM_ADDR_14")
	)
	(segment
		(start 190.419228 -62.407038)
		(end 190.419228 -62.896242)
		(width 0.127)
		(layer "B.Cu")
		(net "XM_ADDR_14")
	)
	(segment
		(start 190.927228 -62.430406)
		(end 191.054228 -62.303406)
		(width 0.127)
		(layer "B.Cu")
		(net "XM_ADDR_14")
	)
	(segment
		(start 192.451228 -62.456822)
		(end 192.451228 -63.263018)
		(width 0.127)
		(layer "B.Cu")
		(net "XM_ADDR_14")
	)
	(segment
		(start 191.943228 -62.885828)
		(end 191.943228 -62.456822)
		(width 0.127)
		(layer "B.Cu")
		(net "XM_ADDR_14")
	)
	(segment
		(start 190.546228 -63.023242)
		(end 190.800228 -63.023242)
		(width 0.127)
		(layer "B.Cu")
		(net "XM_ADDR_14")
	)
	(segment
		(start 191.562228 -63.012828)
		(end 191.816228 -63.012828)
		(width 0.127)
		(layer "B.Cu")
		(net "XM_ADDR_14")
	)
	(segment
		(start 190.800228 -63.023242)
		(end 190.927228 -62.896242)
		(width 0.127)
		(layer "B.Cu")
		(net "XM_ADDR_14")
	)
	(segment
		(start 191.435228 -62.885828)
		(end 191.562228 -63.012828)
		(width 0.127)
		(layer "B.Cu")
		(net "XM_ADDR_14")
	)
	(segment
		(start 190.419228 -62.896242)
		(end 190.546228 -63.023242)
		(width 0.127)
		(layer "B.Cu")
		(net "XM_ADDR_14")
	)
	(segment
		(start 192.451228 -63.263018)
		(end 192.578228 -63.390018)
		(width 0.127)
		(layer "B.Cu")
		(net "XM_ADDR_14")
	)
	(segment
		(start 192.90538 -63.390018)
		(end 193.416936 -63.901574)
		(width 0.127)
		(layer "B.Cu")
		(net "XM_ADDR_14")
	)
	(segment
		(start 185.982102 -62.280038)
		(end 190.292228 -62.280038)
		(width 0.127)
		(layer "B.Cu")
		(net "XM_ADDR_14")
	)
	(segment
		(start 191.308228 -62.303406)
		(end 191.435228 -62.430406)
		(width 0.127)
		(layer "B.Cu")
		(net "XM_ADDR_14")
	)
	(segment
		(start 191.943228 -62.456822)
		(end 192.070228 -62.329822)
		(width 0.127)
		(layer "B.Cu")
		(net "XM_ADDR_14")
	)
	(segment
		(start 192.070228 -62.329822)
		(end 192.324228 -62.329822)
		(width 0.127)
		(layer "B.Cu")
		(net "XM_ADDR_14")
	)
	(segment
		(start 192.578228 -63.390018)
		(end 192.90538 -63.390018)
		(width 0.127)
		(layer "B.Cu")
		(net "XM_ADDR_14")
	)
	(segment
		(start 183.99252 -62.527434)
		(end 185.734706 -62.527434)
		(width 0.127)
		(layer "B.Cu")
		(net "XM_ADDR_14")
	)
	(segment
		(start 191.054228 -62.303406)
		(end 191.308228 -62.303406)
		(width 0.127)
		(layer "B.Cu")
		(net "XM_ADDR_14")
	)
	(segment
		(start 191.435228 -62.430406)
		(end 191.435228 -62.885828)
		(width 0.127)
		(layer "B.Cu")
		(net "XM_ADDR_14")
	)
	(segment
		(start 192.324228 -62.329822)
		(end 192.451228 -62.456822)
		(width 0.127)
		(layer "B.Cu")
		(net "XM_ADDR_14")
	)
	(segment
		(start 190.292228 -62.280038)
		(end 190.419228 -62.407038)
		(width 0.127)
		(layer "B.Cu")
		(net "XM_ADDR_14")
	)
	(segment
		(start 190.927228 -62.896242)
		(end 190.927228 -62.430406)
		(width 0.127)
		(layer "B.Cu")
		(net "XM_ADDR_14")
	)
	(segment
		(start 191.816228 -63.012828)
		(end 191.943228 -62.885828)
		(width 0.127)
		(layer "B.Cu")
		(net "XM_ADDR_14")
	)
	(segment
		(start 185.734706 -62.527434)
		(end 185.982102 -62.280038)
		(width 0.127)
		(layer "B.Cu")
		(net "XM_ADDR_14")
	)
	(segment
		(start 194.166744 -59.665362)
		(end 194.293744 -59.792362)
		(width 0.127)
		(layer "In5.Cu")
		(net "XM_ADDR_14")
	)
	(segment
		(start 188.760862 -48.399954)
		(end 187.557664 -48.399954)
		(width 0.127)
		(layer "In5.Cu")
		(net "XM_ADDR_14")
	)
	(segment
		(start 194.674744 -59.665362)
		(end 194.674744 -57.977278)
		(width 0.127)
		(layer "In5.Cu")
		(net "XM_ADDR_14")
	)
	(segment
		(start 193.890392 -57.911492)
		(end 193.890392 -58.090816)
		(width 0.127)
		(layer "In5.Cu")
		(net "XM_ADDR_14")
	)
	(segment
		(start 193.785744 -58.86069)
		(end 194.039744 -58.86069)
		(width 0.127)
		(layer "In5.Cu")
		(net "XM_ADDR_14")
	)
	(segment
		(start 191.798194 -55.63997)
		(end 191.798194 -55.819294)
		(width 0.127)
		(layer "In5.Cu")
		(net "XM_ADDR_14")
	)
	(segment
		(start 193.416936 -63.901574)
		(end 193.658744 -63.659766)
		(width 0.127)
		(layer "In5.Cu")
		(net "XM_ADDR_14")
	)
	(segment
		(start 194.674744 -57.977278)
		(end 192.15735 -55.459884)
		(width 0.127)
		(layer "In5.Cu")
		(net "XM_ADDR_14")
	)
	(segment
		(start 191.221106 -55.960772)
		(end 191.221106 -53.35143)
		(width 0.127)
		(layer "In5.Cu")
		(net "XM_ADDR_14")
	)
	(segment
		(start 193.890392 -58.090816)
		(end 193.71056 -58.270902)
		(width 0.127)
		(layer "In5.Cu")
		(net "XM_ADDR_14")
	)
	(segment
		(start 190.66383 -50.302922)
		(end 188.760862 -48.399954)
		(width 0.127)
		(layer "In5.Cu")
		(net "XM_ADDR_14")
	)
	(segment
		(start 194.293744 -59.792362)
		(end 194.547744 -59.792362)
		(width 0.127)
		(layer "In5.Cu")
		(net "XM_ADDR_14")
	)
	(segment
		(start 193.658744 -58.98769)
		(end 193.785744 -58.86069)
		(width 0.127)
		(layer "In5.Cu")
		(net "XM_ADDR_14")
	)
	(segment
		(start 191.798194 -55.819294)
		(end 193.890392 -57.911492)
		(width 0.127)
		(layer "In5.Cu")
		(net "XM_ADDR_14")
	)
	(segment
		(start 193.531236 -58.270902)
		(end 191.221106 -55.960772)
		(width 0.127)
		(layer "In5.Cu")
		(net "XM_ADDR_14")
	)
	(segment
		(start 193.658744 -63.659766)
		(end 193.658744 -58.98769)
		(width 0.127)
		(layer "In5.Cu")
		(net "XM_ADDR_14")
	)
	(segment
		(start 190.66383 -52.794154)
		(end 190.66383 -50.302922)
		(width 0.127)
		(layer "In5.Cu")
		(net "XM_ADDR_14")
	)
	(segment
		(start 191.221106 -53.35143)
		(end 190.66383 -52.794154)
		(width 0.127)
		(layer "In5.Cu")
		(net "XM_ADDR_14")
	)
	(segment
		(start 193.71056 -58.270902)
		(end 193.531236 -58.270902)
		(width 0.127)
		(layer "In5.Cu")
		(net "XM_ADDR_14")
	)
	(segment
		(start 191.978026 -55.459884)
		(end 191.798194 -55.63997)
		(width 0.127)
		(layer "In5.Cu")
		(net "XM_ADDR_14")
	)
	(segment
		(start 192.15735 -55.459884)
		(end 191.978026 -55.459884)
		(width 0.127)
		(layer "In5.Cu")
		(net "XM_ADDR_14")
	)
	(segment
		(start 194.166744 -58.98769)
		(end 194.166744 -59.665362)
		(width 0.127)
		(layer "In5.Cu")
		(net "XM_ADDR_14")
	)
	(segment
		(start 194.039744 -58.86069)
		(end 194.166744 -58.98769)
		(width 0.127)
		(layer "In5.Cu")
		(net "XM_ADDR_14")
	)
	(segment
		(start 194.547744 -59.792362)
		(end 194.674744 -59.665362)
		(width 0.127)
		(layer "In5.Cu")
		(net "XM_ADDR_14")
	)
	(segment
		(start 187.53201 -50.70221)
		(end 186.8297 -49.9999)
		(width 0.127)
		(layer "F.Cu")
		(net "XM_ADDR_13")
	)
	(segment
		(start 186.8297 -49.9999)
		(end 186.59983 -49.9999)
		(width 0.127)
		(layer "F.Cu")
		(net "XM_ADDR_13")
	)
	(segment
		(start 187.897008 -50.70221)
		(end 187.53201 -50.70221)
		(width 0.127)
		(layer "F.Cu")
		(net "XM_ADDR_13")
	)
	(via
		(at 189.879732 -62.807596)
		(size 0.508)
		(drill 0.254)
		(layers "F.Cu" "B.Cu")
		(net "XM_ADDR_13")
	)
	(via
		(at 187.897008 -50.70221)
		(size 0.508)
		(drill 0.254)
		(layers "F.Cu" "B.Cu")
		(net "XM_ADDR_13")
	)
	(segment
		(start 186.103006 -62.807596)
		(end 185.882788 -63.027814)
		(width 0.127)
		(layer "B.Cu")
		(net "XM_ADDR_13")
	)
	(segment
		(start 189.879732 -62.807596)
		(end 186.103006 -62.807596)
		(width 0.127)
		(layer "B.Cu")
		(net "XM_ADDR_13")
	)
	(segment
		(start 185.882788 -63.027814)
		(end 183.99252 -63.027814)
		(width 0.127)
		(layer "B.Cu")
		(net "XM_ADDR_13")
	)
	(segment
		(start 189.371732 -71.168006)
		(end 189.371732 -62.371224)
		(width 0.127)
		(layer "In5.Cu")
		(net "XM_ADDR_13")
	)
	(segment
		(start 188.427106 -52.135024)
		(end 187.897008 -51.604926)
		(width 0.127)
		(layer "In5.Cu")
		(net "XM_ADDR_13")
	)
	(segment
		(start 189.709552 -58.073798)
		(end 189.455552 -58.073798)
		(width 0.127)
		(layer "In5.Cu")
		(net "XM_ADDR_13")
	)
	(segment
		(start 189.836552 -58.200798)
		(end 189.709552 -58.073798)
		(width 0.127)
		(layer "In5.Cu")
		(net "XM_ADDR_13")
	)
	(segment
		(start 189.201552 -60.268104)
		(end 188.947552 -60.268104)
		(width 0.127)
		(layer "In5.Cu")
		(net "XM_ADDR_13")
	)
	(segment
		(start 189.328552 -58.200798)
		(end 189.328552 -60.141104)
		(width 0.127)
		(layer "In5.Cu")
		(net "XM_ADDR_13")
	)
	(segment
		(start 189.498732 -71.295006)
		(end 189.371732 -71.168006)
		(width 0.127)
		(layer "In5.Cu")
		(net "XM_ADDR_13")
	)
	(segment
		(start 189.836552 -61.906404)
		(end 189.836552 -58.200798)
		(width 0.127)
		(layer "In5.Cu")
		(net "XM_ADDR_13")
	)
	(segment
		(start 189.328552 -60.141104)
		(end 189.201552 -60.268104)
		(width 0.127)
		(layer "In5.Cu")
		(net "XM_ADDR_13")
	)
	(segment
		(start 189.455552 -58.073798)
		(end 189.328552 -58.200798)
		(width 0.127)
		(layer "In5.Cu")
		(net "XM_ADDR_13")
	)
	(segment
		(start 188.222382 -59.11215)
		(end 188.222382 -57.772046)
		(width 0.127)
		(layer "In5.Cu")
		(net "XM_ADDR_13")
	)
	(segment
		(start 187.897008 -51.604926)
		(end 187.897008 -50.70221)
		(width 0.127)
		(layer "In5.Cu")
		(net "XM_ADDR_13")
	)
	(segment
		(start 189.752732 -71.295006)
		(end 189.498732 -71.295006)
		(width 0.127)
		(layer "In5.Cu")
		(net "XM_ADDR_13")
	)
	(segment
		(start 188.947552 -60.268104)
		(end 188.820552 -60.141104)
		(width 0.127)
		(layer "In5.Cu")
		(net "XM_ADDR_13")
	)
	(segment
		(start 188.820552 -59.71032)
		(end 188.222382 -59.11215)
		(width 0.127)
		(layer "In5.Cu")
		(net "XM_ADDR_13")
	)
	(segment
		(start 189.371732 -62.371224)
		(end 189.836552 -61.906404)
		(width 0.127)
		(layer "In5.Cu")
		(net "XM_ADDR_13")
	)
	(segment
		(start 188.222382 -57.772046)
		(end 188.681106 -57.313322)
		(width 0.127)
		(layer "In5.Cu")
		(net "XM_ADDR_13")
	)
	(segment
		(start 188.681106 -54.272434)
		(end 188.427106 -54.018434)
		(width 0.127)
		(layer "In5.Cu")
		(net "XM_ADDR_13")
	)
	(segment
		(start 189.879732 -71.168006)
		(end 189.752732 -71.295006)
		(width 0.127)
		(layer "In5.Cu")
		(net "XM_ADDR_13")
	)
	(segment
		(start 188.681106 -57.313322)
		(end 188.681106 -54.272434)
		(width 0.127)
		(layer "In5.Cu")
		(net "XM_ADDR_13")
	)
	(segment
		(start 188.427106 -54.018434)
		(end 188.427106 -52.135024)
		(width 0.127)
		(layer "In5.Cu")
		(net "XM_ADDR_13")
	)
	(segment
		(start 188.820552 -60.141104)
		(end 188.820552 -59.71032)
		(width 0.127)
		(layer "In5.Cu")
		(net "XM_ADDR_13")
	)
	(segment
		(start 189.879732 -62.807596)
		(end 189.879732 -71.168006)
		(width 0.127)
		(layer "In5.Cu")
		(net "XM_ADDR_13")
	)
	(segment
		(start 184.999884 -48.399954)
		(end 185.39968 -48.000158)
		(width 0.127)
		(layer "F.Cu")
		(net "XM_ADDR_12")
	)
	(via
		(at 185.39968 -48.000158)
		(size 0.508)
		(drill 0.254)
		(layers "F.Cu" "B.Cu")
		(net "XM_ADDR_12")
	)
	(via
		(at 193.416936 -64.917574)
		(size 0.508)
		(drill 0.254)
		(layers "F.Cu" "B.Cu")
		(net "XM_ADDR_12")
	)
	(segment
		(start 190.079122 -64.240918)
		(end 190.079122 -63.69558)
		(width 0.127)
		(layer "B.Cu")
		(net "XM_ADDR_12")
	)
	(segment
		(start 190.587122 -63.69558)
		(end 190.587122 -64.240918)
		(width 0.127)
		(layer "B.Cu")
		(net "XM_ADDR_12")
	)
	(segment
		(start 189.444122 -63.325248)
		(end 189.571122 -63.452248)
		(width 0.127)
		(layer "B.Cu")
		(net "XM_ADDR_12")
	)
	(segment
		(start 189.571122 -64.240918)
		(end 189.698122 -64.367918)
		(width 0.127)
		(layer "B.Cu")
		(net "XM_ADDR_12")
	)
	(segment
		(start 190.968122 -64.367918)
		(end 191.095122 -64.240918)
		(width 0.127)
		(layer "B.Cu")
		(net "XM_ADDR_12")
	)
	(segment
		(start 183.99252 -63.526924)
		(end 186.11469 -63.526924)
		(width 0.127)
		(layer "B.Cu")
		(net "XM_ADDR_12")
	)
	(segment
		(start 190.460122 -63.56858)
		(end 190.587122 -63.69558)
		(width 0.127)
		(layer "B.Cu")
		(net "XM_ADDR_12")
	)
	(segment
		(start 192.86728 -64.367918)
		(end 193.416936 -64.917574)
		(width 0.127)
		(layer "B.Cu")
		(net "XM_ADDR_12")
	)
	(segment
		(start 191.603122 -63.732664)
		(end 191.603122 -64.240918)
		(width 0.127)
		(layer "B.Cu")
		(net "XM_ADDR_12")
	)
	(segment
		(start 191.603122 -64.240918)
		(end 191.730122 -64.367918)
		(width 0.127)
		(layer "B.Cu")
		(net "XM_ADDR_12")
	)
	(segment
		(start 189.952122 -64.367918)
		(end 190.079122 -64.240918)
		(width 0.127)
		(layer "B.Cu")
		(net "XM_ADDR_12")
	)
	(segment
		(start 190.587122 -64.240918)
		(end 190.714122 -64.367918)
		(width 0.127)
		(layer "B.Cu")
		(net "XM_ADDR_12")
	)
	(segment
		(start 191.476122 -63.605664)
		(end 191.603122 -63.732664)
		(width 0.127)
		(layer "B.Cu")
		(net "XM_ADDR_12")
	)
	(segment
		(start 191.095122 -63.732664)
		(end 191.222122 -63.605664)
		(width 0.127)
		(layer "B.Cu")
		(net "XM_ADDR_12")
	)
	(segment
		(start 186.316366 -63.325248)
		(end 189.444122 -63.325248)
		(width 0.127)
		(layer "B.Cu")
		(net "XM_ADDR_12")
	)
	(segment
		(start 191.095122 -64.240918)
		(end 191.095122 -63.732664)
		(width 0.127)
		(layer "B.Cu")
		(net "XM_ADDR_12")
	)
	(segment
		(start 189.571122 -63.452248)
		(end 189.571122 -64.240918)
		(width 0.127)
		(layer "B.Cu")
		(net "XM_ADDR_12")
	)
	(segment
		(start 191.730122 -64.367918)
		(end 192.86728 -64.367918)
		(width 0.127)
		(layer "B.Cu")
		(net "XM_ADDR_12")
	)
	(segment
		(start 191.222122 -63.605664)
		(end 191.476122 -63.605664)
		(width 0.127)
		(layer "B.Cu")
		(net "XM_ADDR_12")
	)
	(segment
		(start 190.079122 -63.69558)
		(end 190.206122 -63.56858)
		(width 0.127)
		(layer "B.Cu")
		(net "XM_ADDR_12")
	)
	(segment
		(start 190.206122 -63.56858)
		(end 190.460122 -63.56858)
		(width 0.127)
		(layer "B.Cu")
		(net "XM_ADDR_12")
	)
	(segment
		(start 190.714122 -64.367918)
		(end 190.968122 -64.367918)
		(width 0.127)
		(layer "B.Cu")
		(net "XM_ADDR_12")
	)
	(segment
		(start 186.11469 -63.526924)
		(end 186.316366 -63.325248)
		(width 0.127)
		(layer "B.Cu")
		(net "XM_ADDR_12")
	)
	(segment
		(start 189.698122 -64.367918)
		(end 189.952122 -64.367918)
		(width 0.127)
		(layer "B.Cu")
		(net "XM_ADDR_12")
	)
	(segment
		(start 191.17183 -52.583588)
		(end 191.17183 -50.092356)
		(width 0.127)
		(layer "In5.Cu")
		(net "XM_ADDR_12")
	)
	(segment
		(start 195.055744 -63.388494)
		(end 195.182744 -63.261494)
		(width 0.127)
		(layer "In5.Cu")
		(net "XM_ADDR_12")
	)
	(segment
		(start 189.060328 -47.980854)
		(end 187.383928 -47.980854)
		(width 0.127)
		(layer "In5.Cu")
		(net "XM_ADDR_12")
	)
	(segment
		(start 194.166744 -60.508896)
		(end 194.293744 -60.381896)
		(width 0.127)
		(layer "In5.Cu")
		(net "XM_ADDR_12")
	)
	(segment
		(start 194.166744 -64.167766)
		(end 194.166744 -60.508896)
		(width 0.127)
		(layer "In5.Cu")
		(net "XM_ADDR_12")
	)
	(segment
		(start 187.364624 -48.000158)
		(end 185.39968 -48.000158)
		(width 0.127)
		(layer "In5.Cu")
		(net "XM_ADDR_12")
	)
	(segment
		(start 187.383928 -47.980854)
		(end 187.364624 -48.000158)
		(width 0.127)
		(layer "In5.Cu")
		(net "XM_ADDR_12")
	)
	(segment
		(start 191.729106 -54.313074)
		(end 191.729106 -53.140864)
		(width 0.127)
		(layer "In5.Cu")
		(net "XM_ADDR_12")
	)
	(segment
		(start 194.293744 -60.381896)
		(end 194.547744 -60.381896)
		(width 0.127)
		(layer "In5.Cu")
		(net "XM_ADDR_12")
	)
	(segment
		(start 191.729106 -53.140864)
		(end 191.17183 -52.583588)
		(width 0.127)
		(layer "In5.Cu")
		(net "XM_ADDR_12")
	)
	(segment
		(start 195.182744 -57.766712)
		(end 191.729106 -54.313074)
		(width 0.127)
		(layer "In5.Cu")
		(net "XM_ADDR_12")
	)
	(segment
		(start 194.674744 -63.261494)
		(end 194.801744 -63.388494)
		(width 0.127)
		(layer "In5.Cu")
		(net "XM_ADDR_12")
	)
	(segment
		(start 194.547744 -60.381896)
		(end 194.674744 -60.508896)
		(width 0.127)
		(layer "In5.Cu")
		(net "XM_ADDR_12")
	)
	(segment
		(start 191.17183 -50.092356)
		(end 189.060328 -47.980854)
		(width 0.127)
		(layer "In5.Cu")
		(net "XM_ADDR_12")
	)
	(segment
		(start 194.674744 -60.508896)
		(end 194.674744 -63.261494)
		(width 0.127)
		(layer "In5.Cu")
		(net "XM_ADDR_12")
	)
	(segment
		(start 193.416936 -64.917574)
		(end 194.166744 -64.167766)
		(width 0.127)
		(layer "In5.Cu")
		(net "XM_ADDR_12")
	)
	(segment
		(start 194.801744 -63.388494)
		(end 195.055744 -63.388494)
		(width 0.127)
		(layer "In5.Cu")
		(net "XM_ADDR_12")
	)
	(segment
		(start 195.182744 -63.261494)
		(end 195.182744 -57.766712)
		(width 0.127)
		(layer "In5.Cu")
		(net "XM_ADDR_12")
	)
	(segment
		(start 187.723272 -51.7906)
		(end 190.85052 -51.7906)
		(width 0.127)
		(layer "F.Cu")
		(net "XM_ADDR_11")
	)
	(segment
		(start 186.0423 -49.9999)
		(end 186.4614 -50.419)
		(width 0.127)
		(layer "F.Cu")
		(net "XM_ADDR_11")
	)
	(segment
		(start 185.799984 -49.9999)
		(end 186.0423 -49.9999)
		(width 0.127)
		(layer "F.Cu")
		(net "XM_ADDR_11")
	)
	(segment
		(start 187.409328 -51.088544)
		(end 187.409328 -51.476656)
		(width 0.127)
		(layer "F.Cu")
		(net "XM_ADDR_11")
	)
	(segment
		(start 186.739784 -50.419)
		(end 187.409328 -51.088544)
		(width 0.127)
		(layer "F.Cu")
		(net "XM_ADDR_11")
	)
	(segment
		(start 187.409328 -51.476656)
		(end 187.723272 -51.7906)
		(width 0.127)
		(layer "F.Cu")
		(net "XM_ADDR_11")
	)
	(segment
		(start 186.4614 -50.419)
		(end 186.739784 -50.419)
		(width 0.127)
		(layer "F.Cu")
		(net "XM_ADDR_11")
	)
	(segment
		(start 190.85052 -51.7906)
		(end 191.40932 -51.2318)
		(width 0.127)
		(layer "F.Cu")
		(net "XM_ADDR_11")
	)
	(segment
		(start 191.40932 -50.0888)
		(end 191.40932 -51.2318)
		(width 0.127)
		(layer "F.Cu")
		(net "XM_ADDR_11")
	)
	(via
		(at 187.409328 -51.476656)
		(size 0.508)
		(drill 0.254)
		(layers "F.Cu" "B.Cu")
		(net "XM_ADDR_11")
	)
	(via
		(at 188.850778 -63.92799)
		(size 0.508)
		(drill 0.254)
		(layers "F.Cu" "B.Cu")
		(net "XM_ADDR_11")
	)
	(segment
		(start 188.850778 -63.92799)
		(end 188.585856 -64.192912)
		(width 0.127)
		(layer "B.Cu")
		(net "XM_ADDR_11")
	)
	(segment
		(start 185.72353 -64.192912)
		(end 185.557922 -64.027304)
		(width 0.127)
		(layer "B.Cu")
		(net "XM_ADDR_11")
	)
	(segment
		(start 185.557922 -64.027304)
		(end 183.99252 -64.027304)
		(width 0.127)
		(layer "B.Cu")
		(net "XM_ADDR_11")
	)
	(segment
		(start 188.585856 -64.192912)
		(end 185.72353 -64.192912)
		(width 0.127)
		(layer "B.Cu")
		(net "XM_ADDR_11")
	)
	(segment
		(start 187.708794 -58.13044)
		(end 187.581794 -58.25744)
		(width 0.127)
		(layer "In5.Cu")
		(net "XM_ADDR_11")
	)
	(segment
		(start 187.277248 -58.76544)
		(end 187.555124 -58.76544)
		(width 0.127)
		(layer "In5.Cu")
		(net "XM_ADDR_11")
	)
	(segment
		(start 187.708794 -57.87644)
		(end 187.708794 -58.13044)
		(width 0.127)
		(layer "In5.Cu")
		(net "XM_ADDR_11")
	)
	(segment
		(start 187.586874 -61.68644)
		(end 187.713874 -61.81344)
		(width 0.127)
		(layer "In5.Cu")
		(net "XM_ADDR_11")
	)
	(segment
		(start 187.277248 -57.22239)
		(end 187.150248 -57.34939)
		(width 0.127)
		(layer "In5.Cu")
		(net "XM_ADDR_11")
	)
	(segment
		(start 187.277248 -59.78144)
		(end 188.11621 -59.78144)
		(width 0.127)
		(layer "In5.Cu")
		(net "XM_ADDR_11")
	)
	(segment
		(start 188.815472 -62.95644)
		(end 188.815472 -63.21044)
		(width 0.127)
		(layer "In5.Cu")
		(net "XM_ADDR_11")
	)
	(segment
		(start 187.555124 -58.76544)
		(end 187.682124 -58.89244)
		(width 0.127)
		(layer "In5.Cu")
		(net "XM_ADDR_11")
	)
	(segment
		(start 187.600336 -60.67044)
		(end 187.727336 -60.79744)
		(width 0.127)
		(layer "In5.Cu")
		(net "XM_ADDR_11")
	)
	(segment
		(start 188.24321 -60.16244)
		(end 188.11621 -60.28944)
		(width 0.127)
		(layer "In5.Cu")
		(net "XM_ADDR_11")
	)
	(segment
		(start 187.150248 -57.62244)
		(end 187.277248 -57.74944)
		(width 0.127)
		(layer "In5.Cu")
		(net "XM_ADDR_11")
	)
	(segment
		(start 188.312552 -63.97244)
		(end 188.312552 -69.193664)
		(width 0.127)
		(layer "In5.Cu")
		(net "XM_ADDR_11")
	)
	(segment
		(start 189.307216 -61.17844)
		(end 189.180216 -61.30544)
		(width 0.127)
		(layer "In5.Cu")
		(net "XM_ADDR_11")
	)
	(segment
		(start 187.150248 -58.63844)
		(end 187.277248 -58.76544)
		(width 0.127)
		(layer "In5.Cu")
		(net "XM_ADDR_11")
	)
	(segment
		(start 188.688472 -62.82944)
		(end 188.815472 -62.95644)
		(width 0.127)
		(layer "In5.Cu")
		(net "XM_ADDR_11")
	)
	(segment
		(start 188.046106 -57.22239)
		(end 187.277248 -57.22239)
		(width 0.127)
		(layer "In5.Cu")
		(net "XM_ADDR_11")
	)
	(segment
		(start 188.815472 -63.21044)
		(end 188.688472 -63.33744)
		(width 0.127)
		(layer "In5.Cu")
		(net "XM_ADDR_11")
	)
	(segment
		(start 188.173106 -52.240434)
		(end 188.173106 -57.09539)
		(width 0.127)
		(layer "In5.Cu")
		(net "XM_ADDR_11")
	)
	(segment
		(start 187.74029 -62.32144)
		(end 187.61329 -62.44844)
		(width 0.127)
		(layer "In5.Cu")
		(net "XM_ADDR_11")
	)
	(segment
		(start 187.687458 -63.71844)
		(end 187.814458 -63.84544)
		(width 0.127)
		(layer "In5.Cu")
		(net "XM_ADDR_11")
	)
	(segment
		(start 187.814458 -63.84544)
		(end 188.185552 -63.84544)
		(width 0.127)
		(layer "In5.Cu")
		(net "XM_ADDR_11")
	)
	(segment
		(start 187.600336 -60.41644)
		(end 187.600336 -60.67044)
		(width 0.127)
		(layer "In5.Cu")
		(net "XM_ADDR_11")
	)
	(segment
		(start 187.150248 -59.65444)
		(end 187.277248 -59.78144)
		(width 0.127)
		(layer "In5.Cu")
		(net "XM_ADDR_11")
	)
	(segment
		(start 187.682124 -59.14644)
		(end 187.555124 -59.27344)
		(width 0.127)
		(layer "In5.Cu")
		(net "XM_ADDR_11")
	)
	(segment
		(start 188.11621 -59.78144)
		(end 188.24321 -59.90844)
		(width 0.127)
		(layer "In5.Cu")
		(net "XM_ADDR_11")
	)
	(segment
		(start 188.185552 -63.84544)
		(end 188.312552 -63.97244)
		(width 0.127)
		(layer "In5.Cu")
		(net "XM_ADDR_11")
	)
	(segment
		(start 187.61329 -62.70244)
		(end 187.74029 -62.82944)
		(width 0.127)
		(layer "In5.Cu")
		(net "XM_ADDR_11")
	)
	(segment
		(start 188.73597 -61.94044)
		(end 188.73597 -62.19444)
		(width 0.127)
		(layer "In5.Cu")
		(net "XM_ADDR_11")
	)
	(segment
		(start 188.11621 -60.28944)
		(end 187.727336 -60.28944)
		(width 0.127)
		(layer "In5.Cu")
		(net "XM_ADDR_11")
	)
	(segment
		(start 187.277248 -58.25744)
		(end 187.150248 -58.38444)
		(width 0.127)
		(layer "In5.Cu")
		(net "XM_ADDR_11")
	)
	(segment
		(start 188.850778 -69.193664)
		(end 188.850778 -63.92799)
		(width 0.127)
		(layer "In5.Cu")
		(net "XM_ADDR_11")
	)
	(segment
		(start 187.687458 -63.46444)
		(end 187.687458 -63.71844)
		(width 0.127)
		(layer "In5.Cu")
		(net "XM_ADDR_11")
	)
	(segment
		(start 188.723778 -69.320664)
		(end 188.850778 -69.193664)
		(width 0.127)
		(layer "In5.Cu")
		(net "XM_ADDR_11")
	)
	(segment
		(start 187.150248 -59.40044)
		(end 187.150248 -59.65444)
		(width 0.127)
		(layer "In5.Cu")
		(net "XM_ADDR_11")
	)
	(segment
		(start 189.180216 -61.30544)
		(end 187.713874 -61.30544)
		(width 0.127)
		(layer "In5.Cu")
		(net "XM_ADDR_11")
	)
	(segment
		(start 187.555124 -59.27344)
		(end 187.277248 -59.27344)
		(width 0.127)
		(layer "In5.Cu")
		(net "XM_ADDR_11")
	)
	(segment
		(start 187.74029 -62.82944)
		(end 188.688472 -62.82944)
		(width 0.127)
		(layer "In5.Cu")
		(net "XM_ADDR_11")
	)
	(segment
		(start 187.682124 -58.89244)
		(end 187.682124 -59.14644)
		(width 0.127)
		(layer "In5.Cu")
		(net "XM_ADDR_11")
	)
	(segment
		(start 189.180216 -60.79744)
		(end 189.307216 -60.92444)
		(width 0.127)
		(layer "In5.Cu")
		(net "XM_ADDR_11")
	)
	(segment
		(start 187.150248 -58.38444)
		(end 187.150248 -58.63844)
		(width 0.127)
		(layer "In5.Cu")
		(net "XM_ADDR_11")
	)
	(segment
		(start 187.409328 -51.476656)
		(end 188.173106 -52.240434)
		(width 0.127)
		(layer "In5.Cu")
		(net "XM_ADDR_11")
	)
	(segment
		(start 188.60897 -61.81344)
		(end 188.73597 -61.94044)
		(width 0.127)
		(layer "In5.Cu")
		(net "XM_ADDR_11")
	)
	(segment
		(start 189.307216 -60.92444)
		(end 189.307216 -61.17844)
		(width 0.127)
		(layer "In5.Cu")
		(net "XM_ADDR_11")
	)
	(segment
		(start 187.727336 -60.28944)
		(end 187.600336 -60.41644)
		(width 0.127)
		(layer "In5.Cu")
		(net "XM_ADDR_11")
	)
	(segment
		(start 187.150248 -57.34939)
		(end 187.150248 -57.62244)
		(width 0.127)
		(layer "In5.Cu")
		(net "XM_ADDR_11")
	)
	(segment
		(start 188.24321 -59.90844)
		(end 188.24321 -60.16244)
		(width 0.127)
		(layer "In5.Cu")
		(net "XM_ADDR_11")
	)
	(segment
		(start 187.713874 -61.30544)
		(end 187.586874 -61.43244)
		(width 0.127)
		(layer "In5.Cu")
		(net "XM_ADDR_11")
	)
	(segment
		(start 187.727336 -60.79744)
		(end 189.180216 -60.79744)
		(width 0.127)
		(layer "In5.Cu")
		(net "XM_ADDR_11")
	)
	(segment
		(start 187.814458 -63.33744)
		(end 187.687458 -63.46444)
		(width 0.127)
		(layer "In5.Cu")
		(net "XM_ADDR_11")
	)
	(segment
		(start 188.173106 -57.09539)
		(end 188.046106 -57.22239)
		(width 0.127)
		(layer "In5.Cu")
		(net "XM_ADDR_11")
	)
	(segment
		(start 187.277248 -57.74944)
		(end 187.581794 -57.74944)
		(width 0.127)
		(layer "In5.Cu")
		(net "XM_ADDR_11")
	)
	(segment
		(start 188.73597 -62.19444)
		(end 188.60897 -62.32144)
		(width 0.127)
		(layer "In5.Cu")
		(net "XM_ADDR_11")
	)
	(segment
		(start 187.586874 -61.43244)
		(end 187.586874 -61.68644)
		(width 0.127)
		(layer "In5.Cu")
		(net "XM_ADDR_11")
	)
	(segment
		(start 187.277248 -59.27344)
		(end 187.150248 -59.40044)
		(width 0.127)
		(layer "In5.Cu")
		(net "XM_ADDR_11")
	)
	(segment
		(start 188.312552 -69.193664)
		(end 188.439552 -69.320664)
		(width 0.127)
		(layer "In5.Cu")
		(net "XM_ADDR_11")
	)
	(segment
		(start 188.688472 -63.33744)
		(end 187.814458 -63.33744)
		(width 0.127)
		(layer "In5.Cu")
		(net "XM_ADDR_11")
	)
	(segment
		(start 188.439552 -69.320664)
		(end 188.723778 -69.320664)
		(width 0.127)
		(layer "In5.Cu")
		(net "XM_ADDR_11")
	)
	(segment
		(start 188.60897 -62.32144)
		(end 187.74029 -62.32144)
		(width 0.127)
		(layer "In5.Cu")
		(net "XM_ADDR_11")
	)
	(segment
		(start 187.581794 -57.74944)
		(end 187.708794 -57.87644)
		(width 0.127)
		(layer "In5.Cu")
		(net "XM_ADDR_11")
	)
	(segment
		(start 187.61329 -62.44844)
		(end 187.61329 -62.70244)
		(width 0.127)
		(layer "In5.Cu")
		(net "XM_ADDR_11")
	)
	(segment
		(start 187.581794 -58.25744)
		(end 187.277248 -58.25744)
		(width 0.127)
		(layer "In5.Cu")
		(net "XM_ADDR_11")
	)
	(segment
		(start 187.713874 -61.81344)
		(end 188.60897 -61.81344)
		(width 0.127)
		(layer "In5.Cu")
		(net "XM_ADDR_11")
	)
	(segment
		(start 186.180984 -48.8188)
		(end 185.799984 -49.1998)
		(width 0.127)
		(layer "F.Cu")
		(net "XM_ADDR_10")
	)
	(segment
		(start 186.978798 -48.8188)
		(end 186.180984 -48.8188)
		(width 0.127)
		(layer "F.Cu")
		(net "XM_ADDR_10")
	)
	(segment
		(start 187.922408 -49.76241)
		(end 186.978798 -48.8188)
		(width 0.127)
		(layer "F.Cu")
		(net "XM_ADDR_10")
	)
	(via
		(at 187.922408 -49.76241)
		(size 0.508)
		(drill 0.254)
		(layers "F.Cu" "B.Cu")
		(net "XM_ADDR_10")
	)
	(via
		(at 190.930022 -64.90716)
		(size 0.508)
		(drill 0.254)
		(layers "F.Cu" "B.Cu")
		(net "XM_ADDR_10")
	)
	(segment
		(start 188.884052 -65.346834)
		(end 188.757052 -65.219834)
		(width 0.127)
		(layer "B.Cu")
		(net "XM_ADDR_10")
	)
	(segment
		(start 190.930022 -64.90716)
		(end 190.408052 -64.90716)
		(width 0.127)
		(layer "B.Cu")
		(net "XM_ADDR_10")
	)
	(segment
		(start 186.725052 -65.219834)
		(end 186.725052 -65.03416)
		(width 0.127)
		(layer "B.Cu")
		(net "XM_ADDR_10")
	)
	(segment
		(start 186.598052 -64.90716)
		(end 185.829194 -64.90716)
		(width 0.127)
		(layer "B.Cu")
		(net "XM_ADDR_10")
	)
	(segment
		(start 188.376052 -64.90716)
		(end 188.249052 -65.03416)
		(width 0.127)
		(layer "B.Cu")
		(net "XM_ADDR_10")
	)
	(segment
		(start 190.154052 -65.346834)
		(end 189.900052 -65.346834)
		(width 0.127)
		(layer "B.Cu")
		(net "XM_ADDR_10")
	)
	(segment
		(start 188.757052 -65.03416)
		(end 188.630052 -64.90716)
		(width 0.127)
		(layer "B.Cu")
		(net "XM_ADDR_10")
	)
	(segment
		(start 189.265052 -65.03416)
		(end 189.265052 -65.219834)
		(width 0.127)
		(layer "B.Cu")
		(net "XM_ADDR_10")
	)
	(segment
		(start 189.773052 -65.219834)
		(end 189.773052 -65.03416)
		(width 0.127)
		(layer "B.Cu")
		(net "XM_ADDR_10")
	)
	(segment
		(start 189.900052 -65.346834)
		(end 189.773052 -65.219834)
		(width 0.127)
		(layer "B.Cu")
		(net "XM_ADDR_10")
	)
	(segment
		(start 190.408052 -64.90716)
		(end 190.281052 -65.03416)
		(width 0.127)
		(layer "B.Cu")
		(net "XM_ADDR_10")
	)
	(segment
		(start 188.122052 -65.346834)
		(end 187.868052 -65.346834)
		(width 0.127)
		(layer "B.Cu")
		(net "XM_ADDR_10")
	)
	(segment
		(start 188.249052 -65.219834)
		(end 188.122052 -65.346834)
		(width 0.127)
		(layer "B.Cu")
		(net "XM_ADDR_10")
	)
	(segment
		(start 187.741052 -65.219834)
		(end 187.741052 -65.03416)
		(width 0.127)
		(layer "B.Cu")
		(net "XM_ADDR_10")
	)
	(segment
		(start 185.829194 -64.90716)
		(end 185.449718 -64.527684)
		(width 0.127)
		(layer "B.Cu")
		(net "XM_ADDR_10")
	)
	(segment
		(start 185.449718 -64.527684)
		(end 183.99252 -64.527684)
		(width 0.127)
		(layer "B.Cu")
		(net "XM_ADDR_10")
	)
	(segment
		(start 190.281052 -65.03416)
		(end 190.281052 -65.219834)
		(width 0.127)
		(layer "B.Cu")
		(net "XM_ADDR_10")
	)
	(segment
		(start 186.725052 -65.03416)
		(end 186.598052 -64.90716)
		(width 0.127)
		(layer "B.Cu")
		(net "XM_ADDR_10")
	)
	(segment
		(start 187.360052 -64.90716)
		(end 187.233052 -65.03416)
		(width 0.127)
		(layer "B.Cu")
		(net "XM_ADDR_10")
	)
	(segment
		(start 190.281052 -65.219834)
		(end 190.154052 -65.346834)
		(width 0.127)
		(layer "B.Cu")
		(net "XM_ADDR_10")
	)
	(segment
		(start 186.852052 -65.346834)
		(end 186.725052 -65.219834)
		(width 0.127)
		(layer "B.Cu")
		(net "XM_ADDR_10")
	)
	(segment
		(start 188.249052 -65.03416)
		(end 188.249052 -65.219834)
		(width 0.127)
		(layer "B.Cu")
		(net "XM_ADDR_10")
	)
	(segment
		(start 187.233052 -65.03416)
		(end 187.233052 -65.219834)
		(width 0.127)
		(layer "B.Cu")
		(net "XM_ADDR_10")
	)
	(segment
		(start 189.392052 -64.90716)
		(end 189.265052 -65.03416)
		(width 0.127)
		(layer "B.Cu")
		(net "XM_ADDR_10")
	)
	(segment
		(start 187.233052 -65.219834)
		(end 187.106052 -65.346834)
		(width 0.127)
		(layer "B.Cu")
		(net "XM_ADDR_10")
	)
	(segment
		(start 187.106052 -65.346834)
		(end 186.852052 -65.346834)
		(width 0.127)
		(layer "B.Cu")
		(net "XM_ADDR_10")
	)
	(segment
		(start 188.630052 -64.90716)
		(end 188.376052 -64.90716)
		(width 0.127)
		(layer "B.Cu")
		(net "XM_ADDR_10")
	)
	(segment
		(start 189.138052 -65.346834)
		(end 188.884052 -65.346834)
		(width 0.127)
		(layer "B.Cu")
		(net "XM_ADDR_10")
	)
	(segment
		(start 187.741052 -65.03416)
		(end 187.614052 -64.90716)
		(width 0.127)
		(layer "B.Cu")
		(net "XM_ADDR_10")
	)
	(segment
		(start 189.265052 -65.219834)
		(end 189.138052 -65.346834)
		(width 0.127)
		(layer "B.Cu")
		(net "XM_ADDR_10")
	)
	(segment
		(start 187.614052 -64.90716)
		(end 187.360052 -64.90716)
		(width 0.127)
		(layer "B.Cu")
		(net "XM_ADDR_10")
	)
	(segment
		(start 189.773052 -65.03416)
		(end 189.646052 -64.90716)
		(width 0.127)
		(layer "B.Cu")
		(net "XM_ADDR_10")
	)
	(segment
		(start 188.757052 -65.219834)
		(end 188.757052 -65.03416)
		(width 0.127)
		(layer "B.Cu")
		(net "XM_ADDR_10")
	)
	(segment
		(start 187.868052 -65.346834)
		(end 187.741052 -65.219834)
		(width 0.127)
		(layer "B.Cu")
		(net "XM_ADDR_10")
	)
	(segment
		(start 189.646052 -64.90716)
		(end 189.392052 -64.90716)
		(width 0.127)
		(layer "B.Cu")
		(net "XM_ADDR_10")
	)
	(segment
		(start 192.038986 -63.89116)
		(end 192.165986 -63.76416)
		(width 0.127)
		(layer "In5.Cu")
		(net "XM_ADDR_10")
	)
	(segment
		(start 188.88583 -52.234338)
		(end 188.420756 -51.769264)
		(width 0.127)
		(layer "In5.Cu")
		(net "XM_ADDR_10")
	)
	(segment
		(start 191.403732 -62.605158)
		(end 191.403732 -59.031124)
		(width 0.127)
		(layer "In5.Cu")
		(net "XM_ADDR_10")
	)
	(segment
		(start 189.189106 -56.816498)
		(end 189.189106 -54.149498)
		(width 0.127)
		(layer "In5.Cu")
		(net "XM_ADDR_10")
	)
	(segment
		(start 190.768732 -59.164474)
		(end 190.895732 -59.291474)
		(width 0.127)
		(layer "In5.Cu")
		(net "XM_ADDR_10")
	)
	(segment
		(start 192.382648 -64.78016)
		(end 192.382648 -64.52616)
		(width 0.127)
		(layer "In5.Cu")
		(net "XM_ADDR_10")
	)
	(segment
		(start 190.387732 -63.25616)
		(end 190.387732 -59.291474)
		(width 0.127)
		(layer "In5.Cu")
		(net "XM_ADDR_10")
	)
	(segment
		(start 188.420756 -51.769264)
		(end 188.420756 -50.260758)
		(width 0.127)
		(layer "In5.Cu")
		(net "XM_ADDR_10")
	)
	(segment
		(start 189.189106 -54.149498)
		(end 188.88583 -53.846222)
		(width 0.127)
		(layer "In5.Cu")
		(net "XM_ADDR_10")
	)
	(segment
		(start 192.165986 -63.76416)
		(end 192.165986 -63.51016)
		(width 0.127)
		(layer "In5.Cu")
		(net "XM_ADDR_10")
	)
	(segment
		(start 192.255648 -64.90716)
		(end 192.382648 -64.78016)
		(width 0.127)
		(layer "In5.Cu")
		(net "XM_ADDR_10")
	)
	(segment
		(start 192.165986 -63.51016)
		(end 192.038986 -63.38316)
		(width 0.127)
		(layer "In5.Cu")
		(net "XM_ADDR_10")
	)
	(segment
		(start 191.276732 -62.732158)
		(end 191.403732 -62.605158)
		(width 0.127)
		(layer "In5.Cu")
		(net "XM_ADDR_10")
	)
	(segment
		(start 192.038986 -63.38316)
		(end 190.514732 -63.38316)
		(width 0.127)
		(layer "In5.Cu")
		(net "XM_ADDR_10")
	)
	(segment
		(start 188.420756 -50.260758)
		(end 187.922408 -49.76241)
		(width 0.127)
		(layer "In5.Cu")
		(net "XM_ADDR_10")
	)
	(segment
		(start 191.403732 -59.031124)
		(end 189.189106 -56.816498)
		(width 0.127)
		(layer "In5.Cu")
		(net "XM_ADDR_10")
	)
	(segment
		(start 190.930022 -64.90716)
		(end 192.255648 -64.90716)
		(width 0.127)
		(layer "In5.Cu")
		(net "XM_ADDR_10")
	)
	(segment
		(start 190.514732 -63.38316)
		(end 190.387732 -63.25616)
		(width 0.127)
		(layer "In5.Cu")
		(net "XM_ADDR_10")
	)
	(segment
		(start 190.585598 -64.39916)
		(end 190.458598 -64.27216)
		(width 0.127)
		(layer "In5.Cu")
		(net "XM_ADDR_10")
	)
	(segment
		(start 190.387732 -59.291474)
		(end 190.514732 -59.164474)
		(width 0.127)
		(layer "In5.Cu")
		(net "XM_ADDR_10")
	)
	(segment
		(start 190.585598 -63.89116)
		(end 192.038986 -63.89116)
		(width 0.127)
		(layer "In5.Cu")
		(net "XM_ADDR_10")
	)
	(segment
		(start 190.458598 -64.01816)
		(end 190.585598 -63.89116)
		(width 0.127)
		(layer "In5.Cu")
		(net "XM_ADDR_10")
	)
	(segment
		(start 188.88583 -53.846222)
		(end 188.88583 -52.234338)
		(width 0.127)
		(layer "In5.Cu")
		(net "XM_ADDR_10")
	)
	(segment
		(start 190.514732 -59.164474)
		(end 190.768732 -59.164474)
		(width 0.127)
		(layer "In5.Cu")
		(net "XM_ADDR_10")
	)
	(segment
		(start 192.255648 -64.39916)
		(end 190.585598 -64.39916)
		(width 0.127)
		(layer "In5.Cu")
		(net "XM_ADDR_10")
	)
	(segment
		(start 190.895732 -59.291474)
		(end 190.895732 -62.605158)
		(width 0.127)
		(layer "In5.Cu")
		(net "XM_ADDR_10")
	)
	(segment
		(start 190.458598 -64.27216)
		(end 190.458598 -64.01816)
		(width 0.127)
		(layer "In5.Cu")
		(net "XM_ADDR_10")
	)
	(segment
		(start 191.022732 -62.732158)
		(end 191.276732 -62.732158)
		(width 0.127)
		(layer "In5.Cu")
		(net "XM_ADDR_10")
	)
	(segment
		(start 190.895732 -62.605158)
		(end 191.022732 -62.732158)
		(width 0.127)
		(layer "In5.Cu")
		(net "XM_ADDR_10")
	)
	(segment
		(start 192.382648 -64.52616)
		(end 192.255648 -64.39916)
		(width 0.127)
		(layer "In5.Cu")
		(net "XM_ADDR_10")
	)
	(segment
		(start 185.600848 -58.028078)
		(end 185.598562 -58.025792)
		(width 0.127)
		(layer "F.Cu")
		(net "XM_ADDR_1")
	)
	(segment
		(start 183.665368 -52.883562)
		(end 183.78678 -52.76215)
		(width 0.127)
		(layer "F.Cu")
		(net "XM_ADDR_1")
	)
	(segment
		(start 183.78678 -51.213004)
		(end 184.199784 -50.8)
		(width 0.127)
		(layer "F.Cu")
		(net "XM_ADDR_1")
	)
	(segment
		(start 185.06313 -55.087012)
		(end 185.06313 -57.49036)
		(width 0.127)
		(layer "F.Cu")
		(net "XM_ADDR_1")
	)
	(segment
		(start 184.152286 -54.176168)
		(end 183.665368 -53.68925)
		(width 0.127)
		(layer "F.Cu")
		(net "XM_ADDR_1")
	)
	(segment
		(start 184.152286 -54.176168)
		(end 185.06313 -55.087012)
		(width 0.127)
		(layer "F.Cu")
		(net "XM_ADDR_1")
	)
	(segment
		(start 185.06313 -57.49036)
		(end 185.598562 -58.025792)
		(width 0.127)
		(layer "F.Cu")
		(net "XM_ADDR_1")
	)
	(segment
		(start 183.665368 -53.68925)
		(end 183.665368 -52.883562)
		(width 0.127)
		(layer "F.Cu")
		(net "XM_ADDR_1")
	)
	(segment
		(start 185.598562 -58.025792)
		(end 184.570624 -58.025792)
		(width 0.127)
		(layer "F.Cu")
		(net "XM_ADDR_1")
	)
	(segment
		(start 183.78678 -52.76215)
		(end 183.78678 -51.213004)
		(width 0.127)
		(layer "F.Cu")
		(net "XM_ADDR_1")
	)
	(via
		(at 184.152286 -54.176168)
		(size 0.508)
		(drill 0.254)
		(layers "F.Cu" "B.Cu")
		(net "XM_ADDR_1")
	)
	(via
		(at 187.7822 -73.053194)
		(size 0.508)
		(drill 0.254)
		(layers "F.Cu" "B.Cu")
		(net "XM_ADDR_1")
	)
	(segment
		(start 188.256926 -73.52792)
		(end 187.7822 -73.053194)
		(width 0.127)
		(layer "B.Cu")
		(net "XM_ADDR_1")
	)
	(segment
		(start 201.841354 -73.52792)
		(end 188.256926 -73.52792)
		(width 0.127)
		(layer "B.Cu")
		(net "XM_ADDR_1")
	)
	(segment
		(start 202.34148 -73.027794)
		(end 201.841354 -73.52792)
		(width 0.127)
		(layer "B.Cu")
		(net "XM_ADDR_1")
	)
	(segment
		(start 203.22032 -73.027794)
		(end 202.34148 -73.027794)
		(width 0.127)
		(layer "B.Cu")
		(net "XM_ADDR_1")
	)
	(segment
		(start 184.774332 -72.535034)
		(end 182.986934 -70.747636)
		(width 0.127)
		(layer "In5.Cu")
		(net "XM_ADDR_1")
	)
	(segment
		(start 180.997098 -66.873882)
		(end 180.997098 -62.002416)
		(width 0.127)
		(layer "In5.Cu")
		(net "XM_ADDR_1")
	)
	(segment
		(start 182.986934 -70.747636)
		(end 182.986934 -68.863718)
		(width 0.127)
		(layer "In5.Cu")
		(net "XM_ADDR_1")
	)
	(segment
		(start 180.997098 -60.260738)
		(end 180.997098 -57.331356)
		(width 0.127)
		(layer "In5.Cu")
		(net "XM_ADDR_1")
	)
	(segment
		(start 187.7822 -73.053194)
		(end 187.26404 -72.535034)
		(width 0.127)
		(layer "In5.Cu")
		(net "XM_ADDR_1")
	)
	(segment
		(start 180.997098 -62.002416)
		(end 180.519832 -61.52515)
		(width 0.127)
		(layer "In5.Cu")
		(net "XM_ADDR_1")
	)
	(segment
		(start 182.986934 -68.863718)
		(end 180.997098 -66.873882)
		(width 0.127)
		(layer "In5.Cu")
		(net "XM_ADDR_1")
	)
	(segment
		(start 180.997098 -57.331356)
		(end 184.152286 -54.176168)
		(width 0.127)
		(layer "In5.Cu")
		(net "XM_ADDR_1")
	)
	(segment
		(start 180.519832 -61.52515)
		(end 180.519832 -60.738004)
		(width 0.127)
		(layer "In5.Cu")
		(net "XM_ADDR_1")
	)
	(segment
		(start 187.26404 -72.535034)
		(end 184.774332 -72.535034)
		(width 0.127)
		(layer "In5.Cu")
		(net "XM_ADDR_1")
	)
	(segment
		(start 180.519832 -60.738004)
		(end 180.997098 -60.260738)
		(width 0.127)
		(layer "In5.Cu")
		(net "XM_ADDR_1")
	)
	(segment
		(start 182.2196 -51.680872)
		(end 182.2196 -51.180238)
		(width 0.127)
		(layer "F.Cu")
		(net "XM_ADDR_0")
	)
	(segment
		(start 181.728618 -54.258718)
		(end 181.728618 -53.468778)
		(width 0.127)
		(layer "F.Cu")
		(net "XM_ADDR_0")
	)
	(segment
		(start 181.728618 -52.171854)
		(end 182.2196 -51.680872)
		(width 0.127)
		(layer "F.Cu")
		(net "XM_ADDR_0")
	)
	(segment
		(start 182.2196 -51.180238)
		(end 182.599838 -50.8)
		(width 0.127)
		(layer "F.Cu")
		(net "XM_ADDR_0")
	)
	(segment
		(start 182.7022 -55.2323)
		(end 181.728618 -54.258718)
		(width 0.127)
		(layer "F.Cu")
		(net "XM_ADDR_0")
	)
	(segment
		(start 184.3405 -55.250588)
		(end 184.322212 -55.2323)
		(width 0.127)
		(layer "F.Cu")
		(net "XM_ADDR_0")
	)
	(segment
		(start 184.322212 -55.2323)
		(end 182.7022 -55.2323)
		(width 0.127)
		(layer "F.Cu")
		(net "XM_ADDR_0")
	)
	(segment
		(start 181.728618 -53.468778)
		(end 181.728618 -52.171854)
		(width 0.127)
		(layer "F.Cu")
		(net "XM_ADDR_0")
	)
	(via
		(at 181.728618 -53.468778)
		(size 0.508)
		(drill 0.254)
		(layers "F.Cu" "B.Cu")
		(net "XM_ADDR_0")
	)
	(segment
		(start 181.6862 -53.511196)
		(end 181.6862 -54.4576)
		(width 0.127)
		(layer "B.Cu")
		(net "XM_ADDR_0")
	)
	(segment
		(start 181.728618 -53.468778)
		(end 181.6862 -53.511196)
		(width 0.127)
		(layer "B.Cu")
		(net "XM_ADDR_0")
	)
	(segment
		(start 69.1134 -73.1393)
		(end 68.9864 -73.1393)
		(width 0.127)
		(layer "F.Cu")
		(net "VREF6")
	)
	(segment
		(start 68.9864 -73.693274)
		(end 68.9864 -73.1393)
		(width 0.127)
		(layer "F.Cu")
		(net "VREF6")
	)
	(segment
		(start 69.0372 -74.3204)
		(end 69.0372 -73.744074)
		(width 0.127)
		(layer "F.Cu")
		(net "VREF6")
	)
	(segment
		(start 70.885304 -70.696582)
		(end 70.885304 -71.07555)
		(width 0.127)
		(layer "F.Cu")
		(net "VREF6")
	)
	(segment
		(start 69.0372 -73.744074)
		(end 68.9864 -73.693274)
		(width 0.127)
		(layer "F.Cu")
		(net "VREF6")
	)
	(segment
		(start 68.599558 -74.758042)
		(end 69.0372 -74.3204)
		(width 0.127)
		(layer "F.Cu")
		(net "VREF6")
	)
	(segment
		(start 70.0024 -72.2503)
		(end 69.1134 -73.1393)
		(width 0.127)
		(layer "F.Cu")
		(net "VREF6")
	)
	(segment
		(start 68.599558 -75.934824)
		(end 68.599558 -74.758042)
		(width 0.127)
		(layer "F.Cu")
		(net "VREF6")
	)
	(segment
		(start 70.885304 -71.07555)
		(end 70.0024 -71.958454)
		(width 0.127)
		(layer "F.Cu")
		(net "VREF6")
	)
	(segment
		(start 70.0024 -71.958454)
		(end 70.0024 -72.2503)
		(width 0.127)
		(layer "F.Cu")
		(net "VREF6")
	)
	(via
		(at 69.0372 -74.3204)
		(size 0.6604)
		(drill 0.3302)
		(layers "F.Cu" "B.Cu")
		(net "VREF6")
	)
	(segment
		(start 64.008 -74.1934)
		(end 63.9572 -74.2442)
		(width 0.127)
		(layer "F.Cu")
		(net "VREF5")
	)
	(segment
		(start 65.024 -71.272654)
		(end 65.024 -72.2503)
		(width 0.127)
		(layer "F.Cu")
		(net "VREF5")
	)
	(segment
		(start 63.66637 -75.861418)
		(end 63.66637 -74.53503)
		(width 0.127)
		(layer "F.Cu")
		(net "VREF5")
	)
	(segment
		(start 63.66637 -74.53503)
		(end 63.9572 -74.2442)
		(width 0.127)
		(layer "F.Cu")
		(net "VREF5")
	)
	(segment
		(start 64.803274 -71.051928)
		(end 65.024 -71.272654)
		(width 0.127)
		(layer "F.Cu")
		(net "VREF5")
	)
	(segment
		(start 64.15913 -71.051928)
		(end 64.803274 -71.051928)
		(width 0.127)
		(layer "F.Cu")
		(net "VREF5")
	)
	(segment
		(start 64.008 -73.1393)
		(end 64.008 -74.1934)
		(width 0.127)
		(layer "F.Cu")
		(net "VREF5")
	)
	(segment
		(start 64.897 -72.2503)
		(end 64.008 -73.1393)
		(width 0.127)
		(layer "F.Cu")
		(net "VREF5")
	)
	(segment
		(start 65.024 -72.2503)
		(end 64.897 -72.2503)
		(width 0.127)
		(layer "F.Cu")
		(net "VREF5")
	)
	(via
		(at 63.9572 -74.2442)
		(size 0.6604)
		(drill 0.3302)
		(layers "F.Cu" "B.Cu")
		(net "VREF5")
	)
	(segment
		(start 59.007248 -74.221848)
		(end 59.0042 -74.2188)
		(width 0.127)
		(layer "F.Cu")
		(net "VREF4")
	)
	(segment
		(start 59.007248 -75.87107)
		(end 59.007248 -74.221848)
		(width 0.127)
		(layer "F.Cu")
		(net "VREF4")
	)
	(segment
		(start 58.5978 -73.8124)
		(end 59.0042 -74.2188)
		(width 0.127)
		(layer "F.Cu")
		(net "VREF4")
	)
	(segment
		(start 59.5122 -72.2249)
		(end 58.5978 -73.1393)
		(width 0.127)
		(layer "F.Cu")
		(net "VREF4")
	)
	(segment
		(start 58.5978 -73.1393)
		(end 58.5978 -73.8124)
		(width 0.127)
		(layer "F.Cu")
		(net "VREF4")
	)
	(segment
		(start 59.6392 -72.2249)
		(end 59.5122 -72.2249)
		(width 0.127)
		(layer "F.Cu")
		(net "VREF4")
	)
	(segment
		(start 60.7187 -71.0438)
		(end 60.7187 -71.1454)
		(width 0.127)
		(layer "F.Cu")
		(net "VREF4")
	)
	(segment
		(start 60.7187 -71.1454)
		(end 59.6392 -72.2249)
		(width 0.127)
		(layer "F.Cu")
		(net "VREF4")
	)
	(via
		(at 59.0042 -74.2188)
		(size 0.6604)
		(drill 0.3302)
		(layers "F.Cu" "B.Cu")
		(net "VREF4")
	)
	(segment
		(start 7.545324 -92.469462)
		(end 6.656578 -93.358208)
		(width 0.127)
		(layer "F.Cu")
		(net "VREF2")
	)
	(segment
		(start 7.5946 -94.386908)
		(end 6.6294 -94.386908)
		(width 0.127)
		(layer "F.Cu")
		(net "VREF2")
	)
	(segment
		(start 6.6294 -94.386908)
		(end 6.6294 -93.358208)
		(width 0.127)
		(layer "F.Cu")
		(net "VREF2")
	)
	(segment
		(start 6.656578 -93.358208)
		(end 6.6294 -93.358208)
		(width 0.127)
		(layer "F.Cu")
		(net "VREF2")
	)
	(segment
		(start 7.88035 -92.134436)
		(end 7.545324 -92.469462)
		(width 0.127)
		(layer "F.Cu")
		(net "VREF2")
	)
	(segment
		(start 7.88035 -90.679778)
		(end 7.88035 -92.134436)
		(width 0.127)
		(layer "F.Cu")
		(net "VREF2")
	)
	(via
		(at 7.545324 -92.469462)
		(size 0.6604)
		(drill 0.3302)
		(layers "F.Cu" "B.Cu")
		(net "VREF2")
	)
	(segment
		(start 18.5674 -94.5007)
		(end 17.6022 -94.5007)
		(width 0.127)
		(layer "F.Cu")
		(net "VREF0")
	)
	(segment
		(start 18.401284 -92.515182)
		(end 17.507712 -93.408754)
		(width 0.127)
		(layer "F.Cu")
		(net "VREF0")
	)
	(segment
		(start 18.72615 -92.190316)
		(end 18.401284 -92.515182)
		(width 0.127)
		(layer "F.Cu")
		(net "VREF0")
	)
	(segment
		(start 17.6022 -94.5007)
		(end 17.4752 -94.3737)
		(width 0.127)
		(layer "F.Cu")
		(net "VREF0")
	)
	(segment
		(start 17.507712 -93.408754)
		(end 17.4752 -93.408754)
		(width 0.127)
		(layer "F.Cu")
		(net "VREF0")
	)
	(segment
		(start 17.4752 -94.3737)
		(end 17.4752 -93.408754)
		(width 0.127)
		(layer "F.Cu")
		(net "VREF0")
	)
	(segment
		(start 18.72615 -90.730578)
		(end 18.72615 -92.190316)
		(width 0.127)
		(layer "F.Cu")
		(net "VREF0")
	)
	(via
		(at 18.401284 -92.515182)
		(size 0.6604)
		(drill 0.3302)
		(layers "F.Cu" "B.Cu")
		(net "VREF0")
	)
	(segment
		(start 155.720796 -81.730596)
		(end 155.678378 -81.730596)
		(width 0.127)
		(layer "F.Cu")
		(net "VOL_SEN1_SDA")
	)
	(segment
		(start 154.004772 -81.903824)
		(end 154.178 -81.730596)
		(width 0.127)
		(layer "F.Cu")
		(net "VOL_SEN1_SDA")
	)
	(segment
		(start 153.425398 -81.903824)
		(end 154.004772 -81.903824)
		(width 0.127)
		(layer "F.Cu")
		(net "VOL_SEN1_SDA")
	)
	(segment
		(start 156.4132 -85.914738)
		(end 156.4132 -82.423)
		(width 0.127)
		(layer "F.Cu")
		(net "VOL_SEN1_SDA")
	)
	(segment
		(start 154.178 -81.730596)
		(end 155.678378 -81.730596)
		(width 0.127)
		(layer "F.Cu")
		(net "VOL_SEN1_SDA")
	)
	(segment
		(start 156.4132 -82.423)
		(end 155.720796 -81.730596)
		(width 0.127)
		(layer "F.Cu")
		(net "VOL_SEN1_SDA")
	)
	(segment
		(start 157.81528 -86.275672)
		(end 156.774134 -86.275672)
		(width 0.127)
		(layer "F.Cu")
		(net "VOL_SEN1_SDA")
	)
	(segment
		(start 156.774134 -86.275672)
		(end 156.4132 -85.914738)
		(width 0.127)
		(layer "F.Cu")
		(net "VOL_SEN1_SDA")
	)
	(via
		(at 155.678378 -81.730596)
		(size 0.6604)
		(drill 0.3302)
		(layers "F.Cu" "B.Cu")
		(net "VOL_SEN1_SDA")
	)
	(segment
		(start 155.89123 -83.65363)
		(end 155.89123 -86.16823)
		(width 0.127)
		(layer "F.Cu")
		(net "VOL_SEN1_SCL")
	)
	(segment
		(start 154.586178 -82.970624)
		(end 155.208224 -82.970624)
		(width 0.127)
		(layer "F.Cu")
		(net "VOL_SEN1_SCL")
	)
	(segment
		(start 156.497782 -86.774782)
		(end 157.81528 -86.774782)
		(width 0.127)
		(layer "F.Cu")
		(net "VOL_SEN1_SCL")
	)
	(segment
		(start 155.89123 -86.16823)
		(end 156.497782 -86.774782)
		(width 0.127)
		(layer "F.Cu")
		(net "VOL_SEN1_SCL")
	)
	(segment
		(start 155.208224 -82.970624)
		(end 155.89123 -83.65363)
		(width 0.127)
		(layer "F.Cu")
		(net "VOL_SEN1_SCL")
	)
	(segment
		(start 154.586178 -82.970624)
		(end 153.425398 -82.970624)
		(width 0.127)
		(layer "F.Cu")
		(net "VOL_SEN1_SCL")
	)
	(via
		(at 154.586178 -82.970624)
		(size 0.6604)
		(drill 0.3302)
		(layers "F.Cu" "B.Cu")
		(net "VOL_SEN1_SCL")
	)
	(segment
		(start 156.083 -87.8332)
		(end 156.6672 -88.4174)
		(width 0.127)
		(layer "F.Cu")
		(net "VOL_SEN1_ALERT")
	)
	(segment
		(start 155.153106 -86.275672)
		(end 156.083 -87.205566)
		(width 0.127)
		(layer "F.Cu")
		(net "VOL_SEN1_ALERT")
	)
	(segment
		(start 156.8704 -88.6206)
		(end 156.6672 -88.4174)
		(width 0.127)
		(layer "F.Cu")
		(net "VOL_SEN1_ALERT")
	)
	(segment
		(start 158.0642 -88.6206)
		(end 156.8704 -88.6206)
		(width 0.127)
		(layer "F.Cu")
		(net "VOL_SEN1_ALERT")
	)
	(segment
		(start 153.67508 -86.275672)
		(end 155.153106 -86.275672)
		(width 0.127)
		(layer "F.Cu")
		(net "VOL_SEN1_ALERT")
	)
	(segment
		(start 156.083 -87.205566)
		(end 156.083 -87.8332)
		(width 0.127)
		(layer "F.Cu")
		(net "VOL_SEN1_ALERT")
	)
	(via
		(at 156.6672 -88.4174)
		(size 0.6604)
		(drill 0.3302)
		(layers "F.Cu" "B.Cu")
		(net "VOL_SEN1_ALERT")
	)
	(segment
		(start 152.64892 -87.478362)
		(end 152.64892 -86.968584)
		(width 0.127)
		(layer "F.Cu")
		(net "VOL_SEN1_ADDR")
	)
	(segment
		(start 153.390346 -87.955882)
		(end 153.328116 -87.955882)
		(width 0.127)
		(layer "F.Cu")
		(net "VOL_SEN1_ADDR")
	)
	(segment
		(start 153.328116 -87.955882)
		(end 153.243534 -87.8713)
		(width 0.127)
		(layer "F.Cu")
		(net "VOL_SEN1_ADDR")
	)
	(segment
		(start 153.88717 -88.452706)
		(end 153.390346 -87.955882)
		(width 0.127)
		(layer "F.Cu")
		(net "VOL_SEN1_ADDR")
	)
	(segment
		(start 156.4132 -89.313766)
		(end 155.55214 -88.452706)
		(width 0.127)
		(layer "F.Cu")
		(net "VOL_SEN1_ADDR")
	)
	(segment
		(start 156.4132 -89.7636)
		(end 156.4132 -89.313766)
		(width 0.127)
		(layer "F.Cu")
		(net "VOL_SEN1_ADDR")
	)
	(segment
		(start 157.4292 -89.7636)
		(end 156.4132 -89.7636)
		(width 0.127)
		(layer "F.Cu")
		(net "VOL_SEN1_ADDR")
	)
	(segment
		(start 152.64892 -86.968584)
		(end 152.842722 -86.774782)
		(width 0.127)
		(layer "F.Cu")
		(net "VOL_SEN1_ADDR")
	)
	(segment
		(start 153.041858 -87.8713)
		(end 152.64892 -87.478362)
		(width 0.127)
		(layer "F.Cu")
		(net "VOL_SEN1_ADDR")
	)
	(segment
		(start 155.55214 -88.452706)
		(end 155.189428 -88.452706)
		(width 0.127)
		(layer "F.Cu")
		(net "VOL_SEN1_ADDR")
	)
	(segment
		(start 155.189428 -88.452706)
		(end 153.88717 -88.452706)
		(width 0.127)
		(layer "F.Cu")
		(net "VOL_SEN1_ADDR")
	)
	(segment
		(start 152.842722 -86.774782)
		(end 153.67508 -86.774782)
		(width 0.127)
		(layer "F.Cu")
		(net "VOL_SEN1_ADDR")
	)
	(segment
		(start 153.243534 -87.8713)
		(end 153.041858 -87.8713)
		(width 0.127)
		(layer "F.Cu")
		(net "VOL_SEN1_ADDR")
	)
	(via
		(at 155.189428 -88.452706)
		(size 0.6604)
		(drill 0.3302)
		(layers "F.Cu" "B.Cu")
		(net "VOL_SEN1_ADDR")
	)
	(segment
		(start 102.042722 -75.95743)
		(end 100.957126 -75.95743)
		(width 0.254)
		(layer "F.Cu")
		(net "VDDIO_DDR")
	)
	(segment
		(start 100.042726 -73.043034)
		(end 100.042726 -71.957438)
		(width 0.254)
		(layer "F.Cu")
		(net "VDDIO_DDR")
	)
	(segment
		(start 102.957122 -71.957438)
		(end 104.042718 -71.957438)
		(width 0.254)
		(layer "F.Cu")
		(net "VDDIO_DDR")
	)
	(segment
		(start 107.499912 -71.500238)
		(end 108.49991 -70.50024)
		(width 0.254)
		(layer "F.Cu")
		(net "VDDIO_DDR")
	)
	(segment
		(start 102.957122 -77.957426)
		(end 104.042718 -77.957426)
		(width 0.254)
		(layer "F.Cu")
		(net "VDDIO_DDR")
	)
	(segment
		(start 100.499926 -81.500218)
		(end 100.017326 -81.017618)
		(width 0.254)
		(layer "F.Cu")
		(net "VDDIO_DDR")
	)
	(segment
		(start 109.499908 -69.500242)
		(end 109.982762 -69.017388)
		(width 0.254)
		(layer "F.Cu")
		(net "VDDIO_DDR")
	)
	(segment
		(start 104.042718 -73.957434)
		(end 104.499918 -73.500234)
		(width 0.254)
		(layer "F.Cu")
		(net "VDDIO_DDR")
	)
	(segment
		(start 102.499922 -71.500238)
		(end 102.957122 -71.957438)
		(width 0.254)
		(layer "F.Cu")
		(net "VDDIO_DDR")
	)
	(segment
		(start 100.499926 -67.500246)
		(end 100.042726 -67.957446)
		(width 0.254)
		(layer "F.Cu")
		(net "VDDIO_DDR")
	)
	(segment
		(start 100.499926 -77.500226)
		(end 100.957126 -77.957426)
		(width 0.254)
		(layer "F.Cu")
		(net "VDDIO_DDR")
	)
	(segment
		(start 100.957126 -71.957438)
		(end 100.499926 -71.500238)
		(width 0.254)
		(layer "F.Cu")
		(net "VDDIO_DDR")
	)
	(segment
		(start 100.042726 -67.957446)
		(end 100.042726 -69.043042)
		(width 0.254)
		(layer "F.Cu")
		(net "VDDIO_DDR")
	)
	(segment
		(start 107.017058 -67.017392)
		(end 105.98277 -67.017392)
		(width 0.254)
		(layer "F.Cu")
		(net "VDDIO_DDR")
	)
	(segment
		(start 102.499922 -65.85331)
		(end 102.042722 -66.31051)
		(width 0.254)
		(layer "F.Cu")
		(net "VDDIO_DDR")
	)
	(segment
		(start 100.957126 -79.957422)
		(end 102.042722 -79.957422)
		(width 0.254)
		(layer "F.Cu")
		(net "VDDIO_DDR")
	)
	(segment
		(start 100.957126 -65.042796)
		(end 102.042722 -65.042796)
		(width 0.254)
		(layer "F.Cu")
		(net "VDDIO_DDR")
	)
	(segment
		(start 100.042726 -77.043026)
		(end 100.499926 -77.500226)
		(width 0.254)
		(layer "F.Cu")
		(net "VDDIO_DDR")
	)
	(segment
		(start 102.499922 -71.500238)
		(end 102.042722 -71.957438)
		(width 0.254)
		(layer "F.Cu")
		(net "VDDIO_DDR")
	)
	(segment
		(start 100.957126 -75.95743)
		(end 100.499926 -75.50023)
		(width 0.254)
		(layer "F.Cu")
		(net "VDDIO_DDR")
	)
	(segment
		(start 102.042722 -69.957442)
		(end 100.957126 -69.957442)
		(width 0.254)
		(layer "F.Cu")
		(net "VDDIO_DDR")
	)
	(segment
		(start 102.957122 -73.957434)
		(end 104.042718 -73.957434)
		(width 0.254)
		(layer "F.Cu")
		(net "VDDIO_DDR")
	)
	(segment
		(start 102.042722 -66.31051)
		(end 102.042722 -67.043046)
		(width 0.254)
		(layer "F.Cu")
		(net "VDDIO_DDR")
	)
	(segment
		(start 100.499926 -65.499996)
		(end 100.957126 -65.042796)
		(width 0.254)
		(layer "F.Cu")
		(net "VDDIO_DDR")
	)
	(segment
		(start 107.499912 -69.500242)
		(end 106.499914 -70.50024)
		(width 0.254)
		(layer "F.Cu")
		(net "VDDIO_DDR")
	)
	(segment
		(start 100.042726 -77.957426)
		(end 100.499926 -77.500226)
		(width 0.254)
		(layer "F.Cu")
		(net "VDDIO_DDR")
	)
	(segment
		(start 100.042726 -69.957442)
		(end 100.042726 -71.043038)
		(width 0.254)
		(layer "F.Cu")
		(net "VDDIO_DDR")
	)
	(segment
		(start 100.957126 -77.957426)
		(end 102.042722 -77.957426)
		(width 0.254)
		(layer "F.Cu")
		(net "VDDIO_DDR")
	)
	(segment
		(start 102.957122 -67.043046)
		(end 105.042716 -67.043046)
		(width 0.254)
		(layer "F.Cu")
		(net "VDDIO_DDR")
	)
	(segment
		(start 100.499926 -73.500234)
		(end 100.042726 -73.043034)
		(width 0.254)
		(layer "F.Cu")
		(net "VDDIO_DDR")
	)
	(segment
		(start 105.042716 -67.043046)
		(end 105.499916 -67.500246)
		(width 0.254)
		(layer "F.Cu")
		(net "VDDIO_DDR")
	)
	(segment
		(start 108.49991 -68.500244)
		(end 107.499912 -69.500242)
		(width 0.254)
		(layer "F.Cu")
		(net "VDDIO_DDR")
	)
	(segment
		(start 107.957366 -67.9577)
		(end 109.042454 -67.9577)
		(width 0.254)
		(layer "F.Cu")
		(net "VDDIO_DDR")
	)
	(segment
		(start 104.042718 -77.957426)
		(end 104.499918 -77.500226)
		(width 0.254)
		(layer "F.Cu")
		(net "VDDIO_DDR")
	)
	(segment
		(start 102.499922 -75.50023)
		(end 102.042722 -75.95743)
		(width 0.254)
		(layer "F.Cu")
		(net "VDDIO_DDR")
	)
	(segment
		(start 100.499926 -73.500234)
		(end 100.957126 -73.957434)
		(width 0.254)
		(layer "F.Cu")
		(net "VDDIO_DDR")
	)
	(segment
		(start 100.957126 -69.957442)
		(end 100.499926 -69.500242)
		(width 0.254)
		(layer "F.Cu")
		(net "VDDIO_DDR")
	)
	(segment
		(start 105.98277 -67.017392)
		(end 105.499916 -67.500246)
		(width 0.254)
		(layer "F.Cu")
		(net "VDDIO_DDR")
	)
	(segment
		(start 102.017322 -81.982818)
		(end 102.499922 -81.500218)
		(width 0.254)
		(layer "F.Cu")
		(net "VDDIO_DDR")
	)
	(segment
		(start 102.499922 -67.500246)
		(end 102.957122 -67.043046)
		(width 0.254)
		(layer "F.Cu")
		(net "VDDIO_DDR")
	)
	(segment
		(start 102.499922 -69.500242)
		(end 102.042722 -69.957442)
		(width 0.254)
		(layer "F.Cu")
		(net "VDDIO_DDR")
	)
	(segment
		(start 102.042722 -67.043046)
		(end 102.499922 -67.500246)
		(width 0.254)
		(layer "F.Cu")
		(net "VDDIO_DDR")
	)
	(segment
		(start 100.499926 -73.500234)
		(end 100.042726 -73.957434)
		(width 0.254)
		(layer "F.Cu")
		(net "VDDIO_DDR")
	)
	(segment
		(start 100.042726 -73.957434)
		(end 100.042726 -75.04303)
		(width 0.254)
		(layer "F.Cu")
		(net "VDDIO_DDR")
	)
	(segment
		(start 100.017326 -81.017618)
		(end 100.017326 -79.982822)
		(width 0.254)
		(layer "F.Cu")
		(net "VDDIO_DDR")
	)
	(segment
		(start 102.042722 -65.042796)
		(end 102.499922 -65.499996)
		(width 0.254)
		(layer "F.Cu")
		(net "VDDIO_DDR")
	)
	(segment
		(start 109.042454 -67.9577)
		(end 109.499908 -67.500246)
		(width 0.254)
		(layer "F.Cu")
		(net "VDDIO_DDR")
	)
	(segment
		(start 102.957122 -75.95743)
		(end 102.499922 -75.50023)
		(width 0.254)
		(layer "F.Cu")
		(net "VDDIO_DDR")
	)
	(segment
		(start 107.499912 -67.500246)
		(end 107.017058 -67.017392)
		(width 0.254)
		(layer "F.Cu")
		(net "VDDIO_DDR")
	)
	(segment
		(start 109.982762 -67.9831)
		(end 109.499908 -67.500246)
		(width 0.254)
		(layer "F.Cu")
		(net "VDDIO_DDR")
	)
	(segment
		(start 102.499922 -73.500234)
		(end 102.957122 -73.957434)
		(width 0.254)
		(layer "F.Cu")
		(net "VDDIO_DDR")
	)
	(segment
		(start 104.499918 -75.50023)
		(end 104.042718 -75.95743)
		(width 0.254)
		(layer "F.Cu")
		(net "VDDIO_DDR")
	)
	(segment
		(start 100.499926 -79.500222)
		(end 100.957126 -79.957422)
		(width 0.254)
		(layer "F.Cu")
		(net "VDDIO_DDR")
	)
	(segment
		(start 102.042722 -77.957426)
		(end 102.499922 -77.500226)
		(width 0.254)
		(layer "F.Cu")
		(net "VDDIO_DDR")
	)
	(segment
		(start 104.042718 -71.957438)
		(end 104.499918 -71.500238)
		(width 0.254)
		(layer "F.Cu")
		(net "VDDIO_DDR")
	)
	(segment
		(start 109.499908 -69.500242)
		(end 108.49991 -70.50024)
		(width 0.254)
		(layer "F.Cu")
		(net "VDDIO_DDR")
	)
	(segment
		(start 100.982526 -81.982818)
		(end 102.017322 -81.982818)
		(width 0.254)
		(layer "F.Cu")
		(net "VDDIO_DDR")
	)
	(segment
		(start 102.042722 -73.957434)
		(end 102.499922 -73.500234)
		(width 0.254)
		(layer "F.Cu")
		(net "VDDIO_DDR")
	)
	(segment
		(start 104.042718 -75.95743)
		(end 102.957122 -75.95743)
		(width 0.254)
		(layer "F.Cu")
		(net "VDDIO_DDR")
	)
	(segment
		(start 105.98277 -71.983092)
		(end 107.017058 -71.983092)
		(width 0.254)
		(layer "F.Cu")
		(net "VDDIO_DDR")
	)
	(segment
		(start 100.042726 -71.043038)
		(end 100.499926 -71.500238)
		(width 0.254)
		(layer "F.Cu")
		(net "VDDIO_DDR")
	)
	(segment
		(start 102.042722 -71.957438)
		(end 100.957126 -71.957438)
		(width 0.254)
		(layer "F.Cu")
		(net "VDDIO_DDR")
	)
	(segment
		(start 100.042726 -71.957438)
		(end 100.499926 -71.500238)
		(width 0.254)
		(layer "F.Cu")
		(net "VDDIO_DDR")
	)
	(segment
		(start 100.957126 -73.957434)
		(end 102.042722 -73.957434)
		(width 0.254)
		(layer "F.Cu")
		(net "VDDIO_DDR")
	)
	(segment
		(start 102.499922 -77.500226)
		(end 102.957122 -77.957426)
		(width 0.254)
		(layer "F.Cu")
		(net "VDDIO_DDR")
	)
	(segment
		(start 100.042726 -79.043022)
		(end 100.042726 -77.957426)
		(width 0.254)
		(layer "F.Cu")
		(net "VDDIO_DDR")
	)
	(segment
		(start 100.017326 -79.982822)
		(end 100.499926 -79.500222)
		(width 0.254)
		(layer "F.Cu")
		(net "VDDIO_DDR")
	)
	(segment
		(start 100.499926 -81.500218)
		(end 100.982526 -81.982818)
		(width 0.254)
		(layer "F.Cu")
		(net "VDDIO_DDR")
	)
	(segment
		(start 107.017058 -71.983092)
		(end 107.499912 -71.500238)
		(width 0.254)
		(layer "F.Cu")
		(net "VDDIO_DDR")
	)
	(segment
		(start 109.982762 -69.017388)
		(end 109.982762 -67.9831)
		(width 0.254)
		(layer "F.Cu")
		(net "VDDIO_DDR")
	)
	(segment
		(start 105.499916 -71.500238)
		(end 104.499918 -71.500238)
		(width 0.254)
		(layer "F.Cu")
		(net "VDDIO_DDR")
	)
	(segment
		(start 102.042722 -79.957422)
		(end 102.499922 -79.500222)
		(width 0.254)
		(layer "F.Cu")
		(net "VDDIO_DDR")
	)
	(segment
		(start 100.499926 -69.500242)
		(end 100.042726 -69.957442)
		(width 0.254)
		(layer "F.Cu")
		(net "VDDIO_DDR")
	)
	(segment
		(start 102.499922 -65.499996)
		(end 102.499922 -65.85331)
		(width 0.254)
		(layer "F.Cu")
		(net "VDDIO_DDR")
	)
	(segment
		(start 100.499926 -75.50023)
		(end 100.042726 -75.95743)
		(width 0.254)
		(layer "F.Cu")
		(net "VDDIO_DDR")
	)
	(segment
		(start 108.49991 -70.50024)
		(end 107.499912 -69.500242)
		(width 0.254)
		(layer "F.Cu")
		(net "VDDIO_DDR")
	)
	(segment
		(start 100.042726 -67.043046)
		(end 100.499926 -67.500246)
		(width 0.254)
		(layer "F.Cu")
		(net "VDDIO_DDR")
	)
	(segment
		(start 100.499926 -65.499996)
		(end 100.042726 -65.957196)
		(width 0.254)
		(layer "F.Cu")
		(net "VDDIO_DDR")
	)
	(segment
		(start 100.499926 -79.500222)
		(end 100.042726 -79.043022)
		(width 0.254)
		(layer "F.Cu")
		(net "VDDIO_DDR")
	)
	(segment
		(start 100.042726 -75.95743)
		(end 100.042726 -77.043026)
		(width 0.254)
		(layer "F.Cu")
		(net "VDDIO_DDR")
	)
	(segment
		(start 100.042726 -75.04303)
		(end 100.499926 -75.50023)
		(width 0.254)
		(layer "F.Cu")
		(net "VDDIO_DDR")
	)
	(segment
		(start 100.042726 -69.043042)
		(end 100.499926 -69.500242)
		(width 0.254)
		(layer "F.Cu")
		(net "VDDIO_DDR")
	)
	(segment
		(start 106.499914 -68.500244)
		(end 107.499912 -67.500246)
		(width 0.254)
		(layer "F.Cu")
		(net "VDDIO_DDR")
	)
	(segment
		(start 100.042726 -65.957196)
		(end 100.042726 -67.043046)
		(width 0.254)
		(layer "F.Cu")
		(net "VDDIO_DDR")
	)
	(segment
		(start 107.499912 -67.500246)
		(end 107.957366 -67.9577)
		(width 0.254)
		(layer "F.Cu")
		(net "VDDIO_DDR")
	)
	(segment
		(start 105.499916 -71.500238)
		(end 105.98277 -71.983092)
		(width 0.254)
		(layer "F.Cu")
		(net "VDDIO_DDR")
	)
	(segment
		(start 180.199792 -43.599862)
		(end 180.599842 -43.999912)
		(width 0.127)
		(layer "F.Cu")
		(net "VDDIO_15")
	)
	(via
		(at 180.599842 -43.999912)
		(size 0.508)
		(drill 0.254)
		(layers "F.Cu" "B.Cu")
		(net "VDDIO_15")
	)
	(segment
		(start 181.87416 -44.785788)
		(end 181.385718 -44.785788)
		(width 0.127)
		(layer "B.Cu")
		(net "VDDIO_15")
	)
	(segment
		(start 181.385718 -44.785788)
		(end 180.599842 -43.999912)
		(width 0.127)
		(layer "B.Cu")
		(net "VDDIO_15")
	)
	(segment
		(start 171.399962 -37.999924)
		(end 170.999912 -37.599874)
		(width 0.3048)
		(layer "F.Cu")
		(net "VDDA_SAS_REF_CLK")
	)
	(via
		(at 165.329616 -57.623456)
		(size 0.6096)
		(drill 0.3048)
		(layers "F.Cu" "B.Cu")
		(net "VDDA_SAS_REF_CLK")
	)
	(via
		(at 170.999912 -37.599874)
		(size 0.508)
		(drill 0.254)
		(layers "F.Cu" "B.Cu")
		(net "VDDA_SAS_REF_CLK")
	)
	(via
		(at 172.5676 -54.1782)
		(size 0.508)
		(drill 0.254)
		(layers "F.Cu" "B.Cu")
		(net "VDDA_SAS_REF_CLK")
	)
	(segment
		(start 167.699944 -55.253128)
		(end 165.329616 -57.623456)
		(width 0.508)
		(layer "B.Cu")
		(net "VDDA_SAS_REF_CLK")
	)
	(segment
		(start 163.6522 -59.300872)
		(end 163.6522 -59.6138)
		(width 0.508)
		(layer "B.Cu")
		(net "VDDA_SAS_REF_CLK")
	)
	(segment
		(start 172.5676 -54.1782)
		(end 171.492672 -55.253128)
		(width 0.508)
		(layer "B.Cu")
		(net "VDDA_SAS_REF_CLK")
	)
	(segment
		(start 171.492672 -55.253128)
		(end 167.699944 -55.253128)
		(width 0.508)
		(layer "B.Cu")
		(net "VDDA_SAS_REF_CLK")
	)
	(segment
		(start 165.329616 -57.623456)
		(end 163.6522 -59.300872)
		(width 0.508)
		(layer "B.Cu")
		(net "VDDA_SAS_REF_CLK")
	)
	(segment
		(start 173.340014 -50.397156)
		(end 174.10811 -49.62906)
		(width 0.508)
		(layer "In2.Cu")
		(net "VDDA_SAS_REF_CLK")
	)
	(segment
		(start 173.340014 -53.405786)
		(end 173.340014 -50.397156)
		(width 0.508)
		(layer "In2.Cu")
		(net "VDDA_SAS_REF_CLK")
	)
	(segment
		(start 175.83277 -49.62906)
		(end 176.409604 -49.052226)
		(width 0.508)
		(layer "In2.Cu")
		(net "VDDA_SAS_REF_CLK")
	)
	(segment
		(start 176.409604 -49.052226)
		(end 176.409604 -45.347128)
		(width 0.508)
		(layer "In2.Cu")
		(net "VDDA_SAS_REF_CLK")
	)
	(segment
		(start 172.5676 -54.1782)
		(end 173.340014 -53.405786)
		(width 0.508)
		(layer "In2.Cu")
		(net "VDDA_SAS_REF_CLK")
	)
	(segment
		(start 172.539914 -44.802552)
		(end 171.645834 -43.908472)
		(width 0.508)
		(layer "In2.Cu")
		(net "VDDA_SAS_REF_CLK")
	)
	(segment
		(start 175.865028 -44.802552)
		(end 172.539914 -44.802552)
		(width 0.508)
		(layer "In2.Cu")
		(net "VDDA_SAS_REF_CLK")
	)
	(segment
		(start 171.645834 -43.908472)
		(end 171.645834 -38.245796)
		(width 0.508)
		(layer "In2.Cu")
		(net "VDDA_SAS_REF_CLK")
	)
	(segment
		(start 171.645834 -38.245796)
		(end 170.999912 -37.599874)
		(width 0.508)
		(layer "In2.Cu")
		(net "VDDA_SAS_REF_CLK")
	)
	(segment
		(start 176.409604 -45.347128)
		(end 175.865028 -44.802552)
		(width 0.508)
		(layer "In2.Cu")
		(net "VDDA_SAS_REF_CLK")
	)
	(segment
		(start 174.10811 -49.62906)
		(end 175.83277 -49.62906)
		(width 0.508)
		(layer "In2.Cu")
		(net "VDDA_SAS_REF_CLK")
	)
	(segment
		(start 122.536458 -90.150696)
		(end 122.589036 -90.150696)
		(width 0.127)
		(layer "F.Cu")
		(net "USB_NXT")
	)
	(segment
		(start 124.064776 -88.674956)
		(end 124.064776 -85.955886)
		(width 0.127)
		(layer "F.Cu")
		(net "USB_NXT")
	)
	(segment
		(start 124.064776 -85.955886)
		(end 124.064776 -84.598002)
		(width 0.127)
		(layer "F.Cu")
		(net "USB_NXT")
	)
	(segment
		(start 122.589036 -90.150696)
		(end 124.064776 -88.674956)
		(width 0.127)
		(layer "F.Cu")
		(net "USB_NXT")
	)
	(segment
		(start 120.50014 -81.847436)
		(end 120.50014 -81.500218)
		(width 0.127)
		(layer "F.Cu")
		(net "USB_NXT")
	)
	(segment
		(start 121.731786 -83.47964)
		(end 121.106184 -82.854038)
		(width 0.127)
		(layer "F.Cu")
		(net "USB_NXT")
	)
	(segment
		(start 122.946414 -83.47964)
		(end 121.731786 -83.47964)
		(width 0.127)
		(layer "F.Cu")
		(net "USB_NXT")
	)
	(segment
		(start 121.106184 -82.854038)
		(end 121.106184 -82.45348)
		(width 0.127)
		(layer "F.Cu")
		(net "USB_NXT")
	)
	(segment
		(start 124.064776 -84.598002)
		(end 122.946414 -83.47964)
		(width 0.127)
		(layer "F.Cu")
		(net "USB_NXT")
	)
	(segment
		(start 121.106184 -82.45348)
		(end 120.50014 -81.847436)
		(width 0.127)
		(layer "F.Cu")
		(net "USB_NXT")
	)
	(via
		(at 124.064776 -85.955886)
		(size 0.6604)
		(drill 0.3302)
		(layers "F.Cu" "B.Cu")
		(net "USB_NXT")
	)
	(segment
		(start 120.50014 -78.500224)
		(end 121.000012 -79.000096)
		(width 0.127)
		(layer "F.Cu")
		(net "USB_DIR")
	)
	(via
		(at 121.000012 -79.000096)
		(size 0.4572)
		(drill 0.2032)
		(layers "F.Cu" "B.Cu")
		(net "USB_DIR")
	)
	(via
		(at 124.82703 -87.0458)
		(size 0.6096)
		(drill 0.3048)
		(layers "F.Cu" "B.Cu")
		(net "USB_DIR")
	)
	(segment
		(start 124.82703 -87.0458)
		(end 124.82703 -86.419436)
		(width 0.127)
		(layer "B.Cu")
		(net "USB_DIR")
	)
	(segment
		(start 124.82703 -88.114632)
		(end 124.82703 -87.0458)
		(width 0.127)
		(layer "B.Cu")
		(net "USB_DIR")
	)
	(segment
		(start 121.393712 -81.310988)
		(end 121.393712 -79.636112)
		(width 0.127)
		(layer "B.Cu")
		(net "USB_DIR")
	)
	(segment
		(start 121.2342 -81.4705)
		(end 121.393712 -81.310988)
		(width 0.127)
		(layer "B.Cu")
		(net "USB_DIR")
	)
	(segment
		(start 121.000012 -79.242412)
		(end 121.000012 -79.000096)
		(width 0.127)
		(layer "B.Cu")
		(net "USB_DIR")
	)
	(segment
		(start 124.82703 -86.419436)
		(end 121.2342 -82.826606)
		(width 0.127)
		(layer "B.Cu")
		(net "USB_DIR")
	)
	(segment
		(start 121.393712 -79.636112)
		(end 121.000012 -79.242412)
		(width 0.127)
		(layer "B.Cu")
		(net "USB_DIR")
	)
	(segment
		(start 121.2342 -82.826606)
		(end 121.2342 -81.4705)
		(width 0.127)
		(layer "B.Cu")
		(net "USB_DIR")
	)
	(segment
		(start 124.580904 -85.6996)
		(end 124.580904 -84.580984)
		(width 0.127)
		(layer "F.Cu")
		(net "USB_CLK")
	)
	(segment
		(start 123.603258 -90.150696)
		(end 123.603258 -89.85504)
		(width 0.127)
		(layer "F.Cu")
		(net "USB_CLK")
	)
	(segment
		(start 124.572776 -88.736424)
		(end 124.578872 -88.730328)
		(width 0.127)
		(layer "F.Cu")
		(net "USB_CLK")
	)
	(segment
		(start 124.834396 -87.976456)
		(end 124.834396 -86.921086)
		(width 0.127)
		(layer "F.Cu")
		(net "USB_CLK")
	)
	(segment
		(start 124.834396 -86.378796)
		(end 124.610876 -86.155276)
		(width 0.127)
		(layer "F.Cu")
		(net "USB_CLK")
	)
	(segment
		(start 124.578872 -88.23198)
		(end 124.834396 -87.976456)
		(width 0.127)
		(layer "F.Cu")
		(net "USB_CLK")
	)
	(segment
		(start 124.572776 -88.885522)
		(end 124.572776 -88.736424)
		(width 0.127)
		(layer "F.Cu")
		(net "USB_CLK")
	)
	(segment
		(start 124.580904 -84.580984)
		(end 122.500136 -82.500216)
		(width 0.127)
		(layer "F.Cu")
		(net "USB_CLK")
	)
	(segment
		(start 124.610876 -85.729572)
		(end 124.580904 -85.6996)
		(width 0.127)
		(layer "F.Cu")
		(net "USB_CLK")
	)
	(segment
		(start 124.610876 -86.155276)
		(end 124.610876 -85.729572)
		(width 0.127)
		(layer "F.Cu")
		(net "USB_CLK")
	)
	(segment
		(start 124.834396 -86.921086)
		(end 124.834396 -86.378796)
		(width 0.127)
		(layer "F.Cu")
		(net "USB_CLK")
	)
	(segment
		(start 124.578872 -88.730328)
		(end 124.578872 -88.23198)
		(width 0.127)
		(layer "F.Cu")
		(net "USB_CLK")
	)
	(segment
		(start 123.603258 -89.85504)
		(end 124.572776 -88.885522)
		(width 0.127)
		(layer "F.Cu")
		(net "USB_CLK")
	)
	(via
		(at 124.834396 -86.921086)
		(size 0.6604)
		(drill 0.3302)
		(layers "F.Cu" "B.Cu")
		(net "USB_CLK")
	)
	(segment
		(start 184.999884 -32.399986)
		(end 185.399934 -31.999936)
		(width 0.127)
		(layer "F.Cu")
		(net "UART_SERCLK")
	)
	(via
		(at 185.399934 -31.999936)
		(size 0.508)
		(drill 0.254)
		(layers "F.Cu" "B.Cu")
		(net "UART_SERCLK")
	)
	(segment
		(start 192.29451 -33.573974)
		(end 192.29451 -33.54451)
		(width 0.127)
		(layer "B.Cu")
		(net "UART_SERCLK")
	)
	(segment
		(start 192.29451 -33.54451)
		(end 191.135 -32.385)
		(width 0.127)
		(layer "B.Cu")
		(net "UART_SERCLK")
	)
	(segment
		(start 186.15787 -31.242)
		(end 185.399934 -31.999936)
		(width 0.127)
		(layer "B.Cu")
		(net "UART_SERCLK")
	)
	(segment
		(start 191.135 -32.385)
		(end 189.992 -31.242)
		(width 0.127)
		(layer "B.Cu")
		(net "UART_SERCLK")
	)
	(segment
		(start 189.992 -31.242)
		(end 186.15787 -31.242)
		(width 0.127)
		(layer "B.Cu")
		(net "UART_SERCLK")
	)
	(segment
		(start 125.50013 -79.500222)
		(end 126.000002 -80.000094)
		(width 0.127)
		(layer "F.Cu")
		(net "UART_RTS")
	)
	(via
		(at 126.000002 -80.000094)
		(size 0.4572)
		(drill 0.2032)
		(layers "F.Cu" "B.Cu")
		(net "UART_RTS")
	)
	(segment
		(start 126.000002 -80.000094)
		(end 126.492508 -80.4926)
		(width 0.127)
		(layer "B.Cu")
		(net "UART_RTS")
	)
	(segment
		(start 127.606298 -82.103976)
		(end 127.880872 -82.37855)
		(width 0.127)
		(layer "B.Cu")
		(net "UART_RTS")
	)
	(segment
		(start 127.06858 -80.4926)
		(end 127.606298 -81.030318)
		(width 0.127)
		(layer "B.Cu")
		(net "UART_RTS")
	)
	(segment
		(start 126.492508 -80.4926)
		(end 127.06858 -80.4926)
		(width 0.127)
		(layer "B.Cu")
		(net "UART_RTS")
	)
	(segment
		(start 127.606298 -81.030318)
		(end 127.606298 -82.103976)
		(width 0.127)
		(layer "B.Cu")
		(net "UART_RTS")
	)
	(segment
		(start 130.369818 -85.708744)
		(end 130.369818 -85.369908)
		(width 0.127)
		(layer "F.Cu")
		(net "UART_CTS")
	)
	(segment
		(start 131.57708 -87.282528)
		(end 131.57708 -87.841074)
		(width 0.127)
		(layer "F.Cu")
		(net "UART_CTS")
	)
	(segment
		(start 130.369818 -85.369908)
		(end 127.500126 -82.500216)
		(width 0.127)
		(layer "F.Cu")
		(net "UART_CTS")
	)
	(segment
		(start 131.57708 -87.282528)
		(end 130.874516 -86.579964)
		(width 0.127)
		(layer "F.Cu")
		(net "UART_CTS")
	)
	(segment
		(start 131.137152 -88.281002)
		(end 131.137152 -88.675718)
		(width 0.127)
		(layer "F.Cu")
		(net "UART_CTS")
	)
	(segment
		(start 130.874516 -86.213442)
		(end 130.369818 -85.708744)
		(width 0.127)
		(layer "F.Cu")
		(net "UART_CTS")
	)
	(segment
		(start 130.874516 -86.579964)
		(end 130.874516 -86.213442)
		(width 0.127)
		(layer "F.Cu")
		(net "UART_CTS")
	)
	(segment
		(start 131.137152 -88.675718)
		(end 131.572 -89.110566)
		(width 0.127)
		(layer "F.Cu")
		(net "UART_CTS")
	)
	(segment
		(start 131.57708 -87.841074)
		(end 131.137152 -88.281002)
		(width 0.127)
		(layer "F.Cu")
		(net "UART_CTS")
	)
	(segment
		(start 131.572 -89.110566)
		(end 131.572 -89.2556)
		(width 0.127)
		(layer "F.Cu")
		(net "UART_CTS")
	)
	(segment
		(start 109.499908 -80.50022)
		(end 109.000036 -81.000092)
		(width 0.127)
		(layer "F.Cu")
		(net "TMUX_EN")
	)
	(via
		(at 109.525562 -82.90052)
		(size 0.6096)
		(drill 0.3048)
		(layers "F.Cu" "B.Cu")
		(net "TMUX_EN")
	)
	(via
		(at 109.000036 -81.000092)
		(size 0.4572)
		(drill 0.2032)
		(layers "F.Cu" "B.Cu")
		(net "TMUX_EN")
	)
	(segment
		(start 109.982 -84.488274)
		(end 109.2835 -85.186774)
		(width 0.127)
		(layer "B.Cu")
		(net "TMUX_EN")
	)
	(segment
		(start 109.380782 -87.4649)
		(end 109.9566 -87.4649)
		(width 0.127)
		(layer "B.Cu")
		(net "TMUX_EN")
	)
	(segment
		(start 109.000036 -81.242662)
		(end 109.000036 -81.000092)
		(width 0.127)
		(layer "B.Cu")
		(net "TMUX_EN")
	)
	(segment
		(start 109.2835 -86.6902)
		(end 108.585 -87.3887)
		(width 0.127)
		(layer "B.Cu")
		(net "TMUX_EN")
	)
	(segment
		(start 108.585 -87.3887)
		(end 109.304582 -87.3887)
		(width 0.127)
		(layer "B.Cu")
		(net "TMUX_EN")
	)
	(segment
		(start 109.304582 -87.3887)
		(end 109.380782 -87.4649)
		(width 0.127)
		(layer "B.Cu")
		(net "TMUX_EN")
	)
	(segment
		(start 109.2835 -85.186774)
		(end 109.2835 -86.6902)
		(width 0.127)
		(layer "B.Cu")
		(net "TMUX_EN")
	)
	(segment
		(start 109.599984 -82.974942)
		(end 109.599984 -83.437984)
		(width 0.127)
		(layer "B.Cu")
		(net "TMUX_EN")
	)
	(segment
		(start 109.122972 -81.365598)
		(end 109.000036 -81.242662)
		(width 0.127)
		(layer "B.Cu")
		(net "TMUX_EN")
	)
	(segment
		(start 109.122972 -82.49793)
		(end 109.122972 -81.365598)
		(width 0.127)
		(layer "B.Cu")
		(net "TMUX_EN")
	)
	(segment
		(start 109.982 -83.82)
		(end 109.982 -84.488274)
		(width 0.127)
		(layer "B.Cu")
		(net "TMUX_EN")
	)
	(segment
		(start 109.525562 -82.90052)
		(end 109.122972 -82.49793)
		(width 0.127)
		(layer "B.Cu")
		(net "TMUX_EN")
	)
	(segment
		(start 109.599984 -83.437984)
		(end 109.982 -83.82)
		(width 0.127)
		(layer "B.Cu")
		(net "TMUX_EN")
	)
	(segment
		(start 109.525562 -82.90052)
		(end 109.599984 -82.974942)
		(width 0.127)
		(layer "B.Cu")
		(net "TMUX_EN")
	)
	(segment
		(start 106.499914 -78.500224)
		(end 106.000042 -79.000096)
		(width 0.127)
		(layer "F.Cu")
		(net "TESTIBIAS")
	)
	(via
		(at 106.000042 -79.000096)
		(size 0.4572)
		(drill 0.2032)
		(layers "F.Cu" "B.Cu")
		(net "TESTIBIAS")
	)
	(segment
		(start 106.000042 -79.000096)
		(end 106.000042 -78.999842)
		(width 0.127)
		(layer "B.Cu")
		(net "TESTIBIAS")
	)
	(segment
		(start 106.000042 -78.999842)
		(end 106.499914 -78.49997)
		(width 0.127)
		(layer "B.Cu")
		(net "TESTIBIAS")
	)
	(segment
		(start 105.499916 -65.499996)
		(end 105.000044 -65.000124)
		(width 0.4572)
		(layer "F.Cu")
		(net "SYSPLL_VDDA18")
	)
	(via
		(at 96.4438 -71.096124)
		(size 0.6096)
		(drill 0.3048)
		(layers "F.Cu" "B.Cu")
		(net "SYSPLL_VDDA18")
	)
	(via
		(at 105.000044 -65.000124)
		(size 0.4572)
		(drill 0.2032)
		(layers "F.Cu" "B.Cu")
		(net "SYSPLL_VDDA18")
	)
	(segment
		(start 104.754934 -64.495934)
		(end 104.490266 -64.495934)
		(width 0.254)
		(layer "B.Cu")
		(net "SYSPLL_VDDA18")
	)
	(segment
		(start 92.916502 -71.650098)
		(end 92.611702 -71.954898)
		(width 0.508)
		(layer "B.Cu")
		(net "SYSPLL_VDDA18")
	)
	(segment
		(start 95.889826 -71.650098)
		(end 96.4438 -71.096124)
		(width 0.508)
		(layer "B.Cu")
		(net "SYSPLL_VDDA18")
	)
	(segment
		(start 96.4438 -71.096124)
		(end 97.028 -70.511924)
		(width 0.508)
		(layer "B.Cu")
		(net "SYSPLL_VDDA18")
	)
	(segment
		(start 90.650568 -72.005698)
		(end 89.465912 -72.005698)
		(width 0.508)
		(layer "B.Cu")
		(net "SYSPLL_VDDA18")
	)
	(segment
		(start 105.000044 -65.000124)
		(end 105.000044 -64.741044)
		(width 0.254)
		(layer "B.Cu")
		(net "SYSPLL_VDDA18")
	)
	(segment
		(start 103.499666 -64.495934)
		(end 103.505 -64.4906)
		(width 0.254)
		(layer "B.Cu")
		(net "SYSPLL_VDDA18")
	)
	(segment
		(start 105.000044 -64.741044)
		(end 104.754934 -64.495934)
		(width 0.254)
		(layer "B.Cu")
		(net "SYSPLL_VDDA18")
	)
	(segment
		(start 93.311472 -71.650098)
		(end 92.916502 -71.650098)
		(width 0.508)
		(layer "B.Cu")
		(net "SYSPLL_VDDA18")
	)
	(segment
		(start 93.311472 -71.650098)
		(end 95.889826 -71.650098)
		(width 0.508)
		(layer "B.Cu")
		(net "SYSPLL_VDDA18")
	)
	(segment
		(start 97.028 -65.400428)
		(end 97.587562 -64.840866)
		(width 0.508)
		(layer "B.Cu")
		(net "SYSPLL_VDDA18")
	)
	(segment
		(start 104.490266 -64.495934)
		(end 103.510334 -64.495934)
		(width 0.254)
		(layer "B.Cu")
		(net "SYSPLL_VDDA18")
	)
	(segment
		(start 92.168472 -71.954898)
		(end 91.850972 -71.637398)
		(width 0.508)
		(layer "B.Cu")
		(net "SYSPLL_VDDA18")
	)
	(segment
		(start 97.932494 -64.495934)
		(end 103.499666 -64.495934)
		(width 0.254)
		(layer "B.Cu")
		(net "SYSPLL_VDDA18")
	)
	(segment
		(start 92.611702 -71.954898)
		(end 92.168472 -71.954898)
		(width 0.508)
		(layer "B.Cu")
		(net "SYSPLL_VDDA18")
	)
	(segment
		(start 97.028 -70.511924)
		(end 97.028 -65.400428)
		(width 0.508)
		(layer "B.Cu")
		(net "SYSPLL_VDDA18")
	)
	(segment
		(start 104.490266 -64.495934)
		(end 104.4956 -64.4906)
		(width 0.254)
		(layer "B.Cu")
		(net "SYSPLL_VDDA18")
	)
	(segment
		(start 91.850972 -71.637398)
		(end 91.018868 -71.637398)
		(width 0.508)
		(layer "B.Cu")
		(net "SYSPLL_VDDA18")
	)
	(segment
		(start 103.510334 -64.495934)
		(end 103.505 -64.4906)
		(width 0.254)
		(layer "B.Cu")
		(net "SYSPLL_VDDA18")
	)
	(segment
		(start 91.018868 -71.637398)
		(end 90.650568 -72.005698)
		(width 0.508)
		(layer "B.Cu")
		(net "SYSPLL_VDDA18")
	)
	(segment
		(start 97.587562 -64.840866)
		(end 97.932494 -64.495934)
		(width 0.254)
		(layer "B.Cu")
		(net "SYSPLL_VDDA18")
	)
	(segment
		(start 106.499914 -66.499994)
		(end 106.000042 -66.000122)
		(width 0.4572)
		(layer "F.Cu")
		(net "SYSPLL_VDDA09")
	)
	(via
		(at 99.527106 -66.963036)
		(size 0.6096)
		(drill 0.3048)
		(layers "F.Cu" "B.Cu")
		(net "SYSPLL_VDDA09")
	)
	(via
		(at 106.000042 -66.000122)
		(size 0.4572)
		(drill 0.2032)
		(layers "F.Cu" "B.Cu")
		(net "SYSPLL_VDDA09")
	)
	(segment
		(start 91.567 -79.009748)
		(end 91.3257 -78.768448)
		(width 0.508)
		(layer "B.Cu")
		(net "SYSPLL_VDDA09")
	)
	(segment
		(start 91.3257 -78.768448)
		(end 90.986356 -78.768448)
		(width 0.508)
		(layer "B.Cu")
		(net "SYSPLL_VDDA09")
	)
	(segment
		(start 93.262958 -78.781148)
		(end 92.9386 -78.781148)
		(width 0.508)
		(layer "B.Cu")
		(net "SYSPLL_VDDA09")
	)
	(segment
		(start 90.268552 -78.768448)
		(end 89.900252 -79.136748)
		(width 0.508)
		(layer "B.Cu")
		(net "SYSPLL_VDDA09")
	)
	(segment
		(start 96.640396 -78.012544)
		(end 94.651068 -78.012544)
		(width 0.508)
		(layer "B.Cu")
		(net "SYSPLL_VDDA09")
	)
	(segment
		(start 100.131372 -66.963036)
		(end 99.527106 -66.963036)
		(width 0.508)
		(layer "B.Cu")
		(net "SYSPLL_VDDA09")
	)
	(segment
		(start 92.71 -79.009748)
		(end 92.119958 -79.009748)
		(width 0.508)
		(layer "B.Cu")
		(net "SYSPLL_VDDA09")
	)
	(segment
		(start 92.9386 -78.781148)
		(end 92.71 -79.009748)
		(width 0.508)
		(layer "B.Cu")
		(net "SYSPLL_VDDA09")
	)
	(segment
		(start 104.648 -67.3354)
		(end 105.283 -67.3354)
		(width 0.254)
		(layer "B.Cu")
		(net "SYSPLL_VDDA09")
	)
	(segment
		(start 93.882464 -78.781148)
		(end 93.262958 -78.781148)
		(width 0.508)
		(layer "B.Cu")
		(net "SYSPLL_VDDA09")
	)
	(segment
		(start 105.664 -67.3354)
		(end 106.000042 -66.999358)
		(width 0.254)
		(layer "B.Cu")
		(net "SYSPLL_VDDA09")
	)
	(segment
		(start 100.331524 -67.163188)
		(end 100.131372 -66.963036)
		(width 0.508)
		(layer "B.Cu")
		(net "SYSPLL_VDDA09")
	)
	(segment
		(start 90.986356 -78.768448)
		(end 90.268552 -78.768448)
		(width 0.508)
		(layer "B.Cu")
		(net "SYSPLL_VDDA09")
	)
	(segment
		(start 105.283 -67.3354)
		(end 105.664 -67.3354)
		(width 0.254)
		(layer "B.Cu")
		(net "SYSPLL_VDDA09")
	)
	(segment
		(start 100.689918 -67.521582)
		(end 100.331524 -67.163188)
		(width 0.254)
		(layer "B.Cu")
		(net "SYSPLL_VDDA09")
	)
	(segment
		(start 89.900252 -79.136748)
		(end 89.462356 -79.136748)
		(width 0.508)
		(layer "B.Cu")
		(net "SYSPLL_VDDA09")
	)
	(segment
		(start 94.651068 -78.012544)
		(end 93.882464 -78.781148)
		(width 0.508)
		(layer "B.Cu")
		(net "SYSPLL_VDDA09")
	)
	(segment
		(start 104.072182 -67.3354)
		(end 103.886 -67.521582)
		(width 0.254)
		(layer "B.Cu")
		(net "SYSPLL_VDDA09")
	)
	(segment
		(start 103.886 -67.521582)
		(end 100.689918 -67.521582)
		(width 0.254)
		(layer "B.Cu")
		(net "SYSPLL_VDDA09")
	)
	(segment
		(start 106.000042 -66.999358)
		(end 106.000042 -66.000122)
		(width 0.254)
		(layer "B.Cu")
		(net "SYSPLL_VDDA09")
	)
	(segment
		(start 99.527106 -66.963036)
		(end 98.898964 -66.963036)
		(width 0.508)
		(layer "B.Cu")
		(net "SYSPLL_VDDA09")
	)
	(segment
		(start 92.119958 -79.009748)
		(end 91.567 -79.009748)
		(width 0.508)
		(layer "B.Cu")
		(net "SYSPLL_VDDA09")
	)
	(segment
		(start 104.648 -67.3354)
		(end 104.072182 -67.3354)
		(width 0.254)
		(layer "B.Cu")
		(net "SYSPLL_VDDA09")
	)
	(segment
		(start 98.413062 -76.239878)
		(end 96.640396 -78.012544)
		(width 0.508)
		(layer "B.Cu")
		(net "SYSPLL_VDDA09")
	)
	(segment
		(start 98.898964 -66.963036)
		(end 98.413062 -67.448938)
		(width 0.508)
		(layer "B.Cu")
		(net "SYSPLL_VDDA09")
	)
	(segment
		(start 98.413062 -67.448938)
		(end 98.413062 -76.239878)
		(width 0.508)
		(layer "B.Cu")
		(net "SYSPLL_VDDA09")
	)
	(segment
		(start 180.999892 -32.399986)
		(end 181.399688 -32.799782)
		(width 0.127)
		(layer "F.Cu")
		(net "SYS_RST_N_1")
	)
	(via
		(at 181.73446 -33.39846)
		(size 0.6096)
		(drill 0.3048)
		(layers "F.Cu" "B.Cu")
		(net "SYS_RST_N_1")
	)
	(via
		(at 181.399688 -32.799782)
		(size 0.508)
		(drill 0.254)
		(layers "F.Cu" "B.Cu")
		(net "SYS_RST_N_1")
	)
	(segment
		(start 181.73446 -33.39846)
		(end 182.245 -33.909)
		(width 0.127)
		(layer "B.Cu")
		(net "SYS_RST_N_1")
	)
	(segment
		(start 181.399688 -33.063688)
		(end 181.399688 -32.799782)
		(width 0.127)
		(layer "B.Cu")
		(net "SYS_RST_N_1")
	)
	(segment
		(start 181.73446 -33.39846)
		(end 181.399688 -33.063688)
		(width 0.127)
		(layer "B.Cu")
		(net "SYS_RST_N_1")
	)
	(segment
		(start 182.245 -33.909)
		(end 182.245 -34.3408)
		(width 0.127)
		(layer "B.Cu")
		(net "SYS_RST_N_1")
	)
	(via
		(at 194.740276 -21.850096)
		(size 0.6096)
		(drill 0.3048)
		(layers "F.Cu" "B.Cu")
		(net "SYS_RST")
	)
	(segment
		(start 196.965062 -21.7805)
		(end 196.189092 -22.55647)
		(width 0.127)
		(layer "B.Cu")
		(net "SYS_RST")
	)
	(segment
		(start 195.44665 -22.55647)
		(end 194.740276 -21.850096)
		(width 0.127)
		(layer "B.Cu")
		(net "SYS_RST")
	)
	(segment
		(start 194.740276 -21.850096)
		(end 193.70548 -20.8153)
		(width 0.127)
		(layer "B.Cu")
		(net "SYS_RST")
	)
	(segment
		(start 193.69786 -19.76374)
		(end 193.69786 -20.79498)
		(width 0.127)
		(layer "B.Cu")
		(net "SYS_RST")
	)
	(segment
		(start 196.189092 -22.55647)
		(end 195.44665 -22.55647)
		(width 0.127)
		(layer "B.Cu")
		(net "SYS_RST")
	)
	(segment
		(start 197.104 -21.7805)
		(end 196.965062 -21.7805)
		(width 0.127)
		(layer "B.Cu")
		(net "SYS_RST")
	)
	(segment
		(start 193.70548 -20.8153)
		(end 193.70548 -20.8026)
		(width 0.127)
		(layer "B.Cu")
		(net "SYS_RST")
	)
	(segment
		(start 193.69786 -20.79498)
		(end 193.70548 -20.8026)
		(width 0.127)
		(layer "B.Cu")
		(net "SYS_RST")
	)
	(segment
		(start 169.800016 -39.600124)
		(end 169.800016 -39.59987)
		(width 0.3048)
		(layer "F.Cu")
		(net "SYS_PLL_VDD")
	)
	(segment
		(start 170.199812 -39.99992)
		(end 169.800016 -39.600124)
		(width 0.3048)
		(layer "F.Cu")
		(net "SYS_PLL_VDD")
	)
	(via
		(at 170.199812 -39.99992)
		(size 0.508)
		(drill 0.254)
		(layers "F.Cu" "B.Cu")
		(net "SYS_PLL_VDD")
	)
	(via
		(at 169.710862 -53.36413)
		(size 0.6096)
		(drill 0.3048)
		(layers "F.Cu" "B.Cu")
		(net "SYS_PLL_VDD")
	)
	(via
		(at 171.239688 -53.36413)
		(size 0.508)
		(drill 0.254)
		(layers "F.Cu" "B.Cu")
		(net "SYS_PLL_VDD")
	)
	(segment
		(start 164.02177 -56.399938)
		(end 166.878508 -53.5432)
		(width 0.508)
		(layer "B.Cu")
		(net "SYS_PLL_VDD")
	)
	(segment
		(start 168.50487 -53.36413)
		(end 169.710862 -53.36413)
		(width 0.508)
		(layer "B.Cu")
		(net "SYS_PLL_VDD")
	)
	(segment
		(start 171.239688 -53.36413)
		(end 169.710862 -53.36413)
		(width 0.508)
		(layer "B.Cu")
		(net "SYS_PLL_VDD")
	)
	(segment
		(start 154.859736 -58.709306)
		(end 154.859736 -58.189114)
		(width 0.508)
		(layer "B.Cu")
		(net "SYS_PLL_VDD")
	)
	(segment
		(start 166.878508 -53.5432)
		(end 168.3258 -53.5432)
		(width 0.508)
		(layer "B.Cu")
		(net "SYS_PLL_VDD")
	)
	(segment
		(start 168.3258 -53.5432)
		(end 168.50487 -53.36413)
		(width 0.508)
		(layer "B.Cu")
		(net "SYS_PLL_VDD")
	)
	(segment
		(start 154.859736 -58.189114)
		(end 156.648912 -56.399938)
		(width 0.508)
		(layer "B.Cu")
		(net "SYS_PLL_VDD")
	)
	(segment
		(start 156.648912 -56.399938)
		(end 164.02177 -56.399938)
		(width 0.508)
		(layer "B.Cu")
		(net "SYS_PLL_VDD")
	)
	(segment
		(start 170.199812 -39.99992)
		(end 170.199812 -41.520872)
		(width 0.508)
		(layer "In2.Cu")
		(net "SYS_PLL_VDD")
	)
	(segment
		(start 171.239688 -52.94249)
		(end 171.239688 -53.36413)
		(width 0.508)
		(layer "In2.Cu")
		(net "SYS_PLL_VDD")
	)
	(segment
		(start 169.403014 -42.31767)
		(end 169.403014 -46.929802)
		(width 0.508)
		(layer "In2.Cu")
		(net "SYS_PLL_VDD")
	)
	(segment
		(start 170.961558 -48.488346)
		(end 170.961558 -52.66436)
		(width 0.508)
		(layer "In2.Cu")
		(net "SYS_PLL_VDD")
	)
	(segment
		(start 169.403014 -46.929802)
		(end 170.961558 -48.488346)
		(width 0.508)
		(layer "In2.Cu")
		(net "SYS_PLL_VDD")
	)
	(segment
		(start 170.961558 -52.66436)
		(end 171.239688 -52.94249)
		(width 0.508)
		(layer "In2.Cu")
		(net "SYS_PLL_VDD")
	)
	(segment
		(start 170.199812 -41.520872)
		(end 169.403014 -42.31767)
		(width 0.508)
		(layer "In2.Cu")
		(net "SYS_PLL_VDD")
	)
	(segment
		(start 197.9295 -24.1935)
		(end 197.231 -23.495)
		(width 0.127)
		(layer "B.Cu")
		(net "SYS_HB_LED_R")
	)
	(segment
		(start 198.374 -24.1935)
		(end 197.9295 -24.1935)
		(width 0.127)
		(layer "B.Cu")
		(net "SYS_HB_LED_R")
	)
	(via
		(at 195.928234 -25.019)
		(size 0.6096)
		(drill 0.3048)
		(layers "F.Cu" "B.Cu")
		(net "SYS_HB_LED_D")
	)
	(segment
		(start 195.05168 -25.019)
		(end 195.928234 -25.019)
		(width 0.127)
		(layer "B.Cu")
		(net "SYS_HB_LED_D")
	)
	(segment
		(start 197.231 -25.019)
		(end 195.928234 -25.019)
		(width 0.127)
		(layer "B.Cu")
		(net "SYS_HB_LED_D")
	)
	(segment
		(start 194.3481 -24.31542)
		(end 195.05168 -25.019)
		(width 0.127)
		(layer "B.Cu")
		(net "SYS_HB_LED_D")
	)
	(segment
		(start 186.455812 -39.25697)
		(end 188.269372 -39.25697)
		(width 0.127)
		(layer "F.Cu")
		(net "SYS_HB_LED")
	)
	(segment
		(start 188.461142 -39.0652)
		(end 189.193424 -39.0652)
		(width 0.127)
		(layer "F.Cu")
		(net "SYS_HB_LED")
	)
	(segment
		(start 189.815724 -38.4429)
		(end 193.0654 -38.4429)
		(width 0.127)
		(layer "F.Cu")
		(net "SYS_HB_LED")
	)
	(segment
		(start 189.193424 -39.0652)
		(end 189.815724 -38.4429)
		(width 0.127)
		(layer "F.Cu")
		(net "SYS_HB_LED")
	)
	(segment
		(start 195.3006 -36.2077)
		(end 195.3006 -34.2392)
		(width 0.127)
		(layer "F.Cu")
		(net "SYS_HB_LED")
	)
	(segment
		(start 193.0654 -38.4429)
		(end 195.3006 -36.2077)
		(width 0.127)
		(layer "F.Cu")
		(net "SYS_HB_LED")
	)
	(segment
		(start 185.799984 -39.59987)
		(end 186.112912 -39.59987)
		(width 0.127)
		(layer "F.Cu")
		(net "SYS_HB_LED")
	)
	(segment
		(start 188.269372 -39.25697)
		(end 188.461142 -39.0652)
		(width 0.127)
		(layer "F.Cu")
		(net "SYS_HB_LED")
	)
	(segment
		(start 186.112912 -39.59987)
		(end 186.455812 -39.25697)
		(width 0.127)
		(layer "F.Cu")
		(net "SYS_HB_LED")
	)
	(via
		(at 194.5386 -30.4038)
		(size 0.6096)
		(drill 0.3048)
		(layers "F.Cu" "B.Cu")
		(net "SYS_HB_LED")
	)
	(via
		(at 195.3006 -34.2392)
		(size 0.508)
		(drill 0.254)
		(layers "F.Cu" "B.Cu")
		(net "SYS_HB_LED")
	)
	(segment
		(start 194.0814 -29.2608)
		(end 194.5386 -29.718)
		(width 0.127)
		(layer "B.Cu")
		(net "SYS_HB_LED")
	)
	(segment
		(start 194.5386 -33.4772)
		(end 195.3006 -34.2392)
		(width 0.127)
		(layer "B.Cu")
		(net "SYS_HB_LED")
	)
	(segment
		(start 194.172332 -23.33117)
		(end 192.4431 -23.33117)
		(width 0.127)
		(layer "B.Cu")
		(net "SYS_HB_LED")
	)
	(segment
		(start 194.5386 -29.718)
		(end 194.5386 -30.4038)
		(width 0.127)
		(layer "B.Cu")
		(net "SYS_HB_LED")
	)
	(segment
		(start 194.44462 -22.60854)
		(end 194.44462 -23.058882)
		(width 0.127)
		(layer "B.Cu")
		(net "SYS_HB_LED")
	)
	(segment
		(start 194.44462 -23.058882)
		(end 194.172332 -23.33117)
		(width 0.127)
		(layer "B.Cu")
		(net "SYS_HB_LED")
	)
	(segment
		(start 194.5386 -30.4038)
		(end 194.5386 -33.4772)
		(width 0.127)
		(layer "B.Cu")
		(net "SYS_HB_LED")
	)
	(segment
		(start 192.4431 -23.33117)
		(end 192.4431 -24.01062)
		(width 0.127)
		(layer "B.Cu")
		(net "SYS_HB_LED")
	)
	(segment
		(start 192.4431 -24.01062)
		(end 194.0814 -25.64892)
		(width 0.127)
		(layer "B.Cu")
		(net "SYS_HB_LED")
	)
	(segment
		(start 194.0814 -25.64892)
		(end 194.0814 -29.2608)
		(width 0.127)
		(layer "B.Cu")
		(net "SYS_HB_LED")
	)
	(segment
		(start 193.70548 -21.8694)
		(end 194.44462 -22.60854)
		(width 0.127)
		(layer "B.Cu")
		(net "SYS_HB_LED")
	)
	(segment
		(start 184.898538 -26.15311)
		(end 183.34609 -27.705558)
		(width 0.127)
		(layer "F.Cu")
		(net "SYS_HALT1#")
	)
	(segment
		(start 183.34609 -27.705558)
		(end 183.34609 -28.346146)
		(width 0.127)
		(layer "F.Cu")
		(net "SYS_HALT1#")
	)
	(segment
		(start 190.871602 -26.0604)
		(end 189.220602 -26.0604)
		(width 0.127)
		(layer "F.Cu")
		(net "SYS_HALT1#")
	)
	(segment
		(start 189.127892 -26.15311)
		(end 184.898538 -26.15311)
		(width 0.127)
		(layer "F.Cu")
		(net "SYS_HALT1#")
	)
	(segment
		(start 192.791842 -24.012144)
		(end 192.545208 -23.76551)
		(width 0.127)
		(layer "F.Cu")
		(net "SYS_HALT1#")
	)
	(segment
		(start 192.791842 -24.74976)
		(end 192.791842 -25.15235)
		(width 0.127)
		(layer "F.Cu")
		(net "SYS_HALT1#")
	)
	(segment
		(start 192.791842 -25.15235)
		(end 191.845692 -26.0985)
		(width 0.127)
		(layer "F.Cu")
		(net "SYS_HALT1#")
	)
	(segment
		(start 192.545208 -23.76551)
		(end 191.902842 -23.76551)
		(width 0.127)
		(layer "F.Cu")
		(net "SYS_HALT1#")
	)
	(segment
		(start 191.845692 -26.0985)
		(end 190.909702 -26.0985)
		(width 0.127)
		(layer "F.Cu")
		(net "SYS_HALT1#")
	)
	(segment
		(start 192.791842 -24.74976)
		(end 192.791842 -24.012144)
		(width 0.127)
		(layer "F.Cu")
		(net "SYS_HALT1#")
	)
	(segment
		(start 189.220602 -26.0604)
		(end 189.127892 -26.15311)
		(width 0.127)
		(layer "F.Cu")
		(net "SYS_HALT1#")
	)
	(segment
		(start 183.34609 -28.346146)
		(end 183.399938 -28.399994)
		(width 0.127)
		(layer "F.Cu")
		(net "SYS_HALT1#")
	)
	(segment
		(start 190.909702 -26.0985)
		(end 190.871602 -26.0604)
		(width 0.127)
		(layer "F.Cu")
		(net "SYS_HALT1#")
	)
	(segment
		(start 181.0893 -28.310586)
		(end 180.999892 -28.399994)
		(width 0.127)
		(layer "F.Cu")
		(net "SYS_HALT0#")
	)
	(segment
		(start 181.0893 -27.476958)
		(end 181.0893 -28.310586)
		(width 0.127)
		(layer "F.Cu")
		(net "SYS_HALT0#")
	)
	(segment
		(start 182.99049 -25.826466)
		(end 182.630064 -26.186892)
		(width 0.127)
		(layer "F.Cu")
		(net "SYS_HALT0#")
	)
	(segment
		(start 184.698894 -24.521922)
		(end 183.39435 -25.826466)
		(width 0.127)
		(layer "F.Cu")
		(net "SYS_HALT0#")
	)
	(segment
		(start 186.508644 -24.521922)
		(end 184.698894 -24.521922)
		(width 0.127)
		(layer "F.Cu")
		(net "SYS_HALT0#")
	)
	(segment
		(start 186.748166 -24.2824)
		(end 186.508644 -24.521922)
		(width 0.127)
		(layer "F.Cu")
		(net "SYS_HALT0#")
	)
	(segment
		(start 188.1378 -24.003)
		(end 188.8363 -24.003)
		(width 0.127)
		(layer "F.Cu")
		(net "SYS_HALT0#")
	)
	(segment
		(start 187.2234 -24.2824)
		(end 186.748166 -24.2824)
		(width 0.127)
		(layer "F.Cu")
		(net "SYS_HALT0#")
	)
	(segment
		(start 187.2234 -24.2824)
		(end 187.8584 -24.2824)
		(width 0.127)
		(layer "F.Cu")
		(net "SYS_HALT0#")
	)
	(segment
		(start 183.39435 -25.826466)
		(end 182.99049 -25.826466)
		(width 0.127)
		(layer "F.Cu")
		(net "SYS_HALT0#")
	)
	(segment
		(start 182.379366 -26.186892)
		(end 181.0893 -27.476958)
		(width 0.127)
		(layer "F.Cu")
		(net "SYS_HALT0#")
	)
	(segment
		(start 187.8584 -24.2824)
		(end 188.1378 -24.003)
		(width 0.127)
		(layer "F.Cu")
		(net "SYS_HALT0#")
	)
	(segment
		(start 182.630064 -26.186892)
		(end 182.379366 -26.186892)
		(width 0.127)
		(layer "F.Cu")
		(net "SYS_HALT0#")
	)
	(segment
		(start 180.471318 -27.133042)
		(end 180.199792 -27.404568)
		(width 0.127)
		(layer "F.Cu")
		(net "SYS_ERROR1")
	)
	(segment
		(start 180.199792 -27.404568)
		(end 180.199792 -28.399994)
		(width 0.127)
		(layer "F.Cu")
		(net "SYS_ERROR1")
	)
	(via
		(at 180.471318 -27.133042)
		(size 0.508)
		(drill 0.254)
		(layers "F.Cu" "B.Cu")
		(net "SYS_ERROR1")
	)
	(segment
		(start 181.392068 -25.483566)
		(end 182.140098 -24.735536)
		(width 0.127)
		(layer "B.Cu")
		(net "SYS_ERROR1")
	)
	(segment
		(start 181.392068 -26.212292)
		(end 181.392068 -25.483566)
		(width 0.127)
		(layer "B.Cu")
		(net "SYS_ERROR1")
	)
	(segment
		(start 180.471318 -27.133042)
		(end 181.392068 -26.212292)
		(width 0.127)
		(layer "B.Cu")
		(net "SYS_ERROR1")
	)
	(segment
		(start 199.4789 -24.1935)
		(end 199.9615 -24.1935)
		(width 0.127)
		(layer "B.Cu")
		(net "SYS_ERROR_LED_R")
	)
	(segment
		(start 199.9615 -24.1935)
		(end 200.66 -23.495)
		(width 0.127)
		(layer "B.Cu")
		(net "SYS_ERROR_LED_R")
	)
	(segment
		(start 203.073 -25.5905)
		(end 201.2315 -25.5905)
		(width 0.127)
		(layer "B.Cu")
		(net "SYS_ERROR_LED_D")
	)
	(segment
		(start 201.2315 -25.5905)
		(end 200.66 -25.019)
		(width 0.127)
		(layer "B.Cu")
		(net "SYS_ERROR_LED_D")
	)
	(segment
		(start 193.3448 -20.6502)
		(end 194.5767 -21.8821)
		(width 0.127)
		(layer "F.Cu")
		(net "SYS_ERR_0")
	)
	(segment
		(start 194.5767 -21.8821)
		(end 198.5899 -21.8821)
		(width 0.127)
		(layer "F.Cu")
		(net "SYS_ERR_0")
	)
	(segment
		(start 178.256946 -27.064208)
		(end 178.749706 -26.571448)
		(width 0.127)
		(layer "F.Cu")
		(net "SYS_ERR_0")
	)
	(segment
		(start 183.71439 -20.6502)
		(end 193.3448 -20.6502)
		(width 0.127)
		(layer "F.Cu")
		(net "SYS_ERR_0")
	)
	(segment
		(start 179.571142 -26.571448)
		(end 180.052472 -26.090118)
		(width 0.127)
		(layer "F.Cu")
		(net "SYS_ERR_0")
	)
	(segment
		(start 181.410864 -25.202388)
		(end 181.410864 -22.953726)
		(width 0.127)
		(layer "F.Cu")
		(net "SYS_ERR_0")
	)
	(segment
		(start 181.410864 -22.953726)
		(end 183.71439 -20.6502)
		(width 0.127)
		(layer "F.Cu")
		(net "SYS_ERR_0")
	)
	(segment
		(start 178.256946 -28.85694)
		(end 178.256946 -27.064208)
		(width 0.127)
		(layer "F.Cu")
		(net "SYS_ERR_0")
	)
	(segment
		(start 180.523134 -26.090118)
		(end 181.410864 -25.202388)
		(width 0.127)
		(layer "F.Cu")
		(net "SYS_ERR_0")
	)
	(segment
		(start 178.599846 -29.19984)
		(end 178.256946 -28.85694)
		(width 0.127)
		(layer "F.Cu")
		(net "SYS_ERR_0")
	)
	(segment
		(start 198.5899 -21.8821)
		(end 199.006206 -21.465794)
		(width 0.127)
		(layer "F.Cu")
		(net "SYS_ERR_0")
	)
	(segment
		(start 199.006206 -21.465794)
		(end 199.330818 -21.465794)
		(width 0.127)
		(layer "F.Cu")
		(net "SYS_ERR_0")
	)
	(segment
		(start 180.052472 -26.090118)
		(end 180.523134 -26.090118)
		(width 0.127)
		(layer "F.Cu")
		(net "SYS_ERR_0")
	)
	(segment
		(start 178.749706 -26.571448)
		(end 179.571142 -26.571448)
		(width 0.127)
		(layer "F.Cu")
		(net "SYS_ERR_0")
	)
	(segment
		(start 200.224898 -21.866098)
		(end 199.824594 -21.465794)
		(width 0.127)
		(layer "F.Cu")
		(net "SYS_ERR_0")
	)
	(segment
		(start 199.824594 -21.465794)
		(end 199.330818 -21.465794)
		(width 0.127)
		(layer "F.Cu")
		(net "SYS_ERR_0")
	)
	(via
		(at 199.330818 -21.465794)
		(size 0.6604)
		(drill 0.3302)
		(layers "F.Cu" "B.Cu")
		(net "SYS_ERR_0")
	)
	(via
		(at 200.224898 -21.866098)
		(size 0.508)
		(drill 0.254)
		(layers "F.Cu" "B.Cu")
		(net "SYS_ERR_0")
	)
	(segment
		(start 201.0918 -22.7076)
		(end 201.3712 -22.987)
		(width 0.127)
		(layer "B.Cu")
		(net "SYS_ERR_0")
	)
	(segment
		(start 200.6854 -22.7076)
		(end 201.0918 -22.7076)
		(width 0.127)
		(layer "B.Cu")
		(net "SYS_ERR_0")
	)
	(segment
		(start 201.7268 -24.6888)
		(end 203.6572 -24.6888)
		(width 0.127)
		(layer "B.Cu")
		(net "SYS_ERR_0")
	)
	(segment
		(start 201.3712 -24.3332)
		(end 201.7268 -24.6888)
		(width 0.127)
		(layer "B.Cu")
		(net "SYS_ERR_0")
	)
	(segment
		(start 201.3712 -22.987)
		(end 201.3712 -24.3332)
		(width 0.127)
		(layer "B.Cu")
		(net "SYS_ERR_0")
	)
	(segment
		(start 200.224898 -21.866098)
		(end 200.224898 -22.247098)
		(width 0.127)
		(layer "B.Cu")
		(net "SYS_ERR_0")
	)
	(segment
		(start 203.6572 -24.6888)
		(end 204.05725 -24.28875)
		(width 0.127)
		(layer "B.Cu")
		(net "SYS_ERR_0")
	)
	(segment
		(start 200.224898 -22.247098)
		(end 200.6854 -22.7076)
		(width 0.127)
		(layer "B.Cu")
		(net "SYS_ERR_0")
	)
	(segment
		(start 204.05725 -24.28875)
		(end 204.05725 -23.6855)
		(width 0.127)
		(layer "B.Cu")
		(net "SYS_ERR_0")
	)
	(segment
		(start 183.983884 -23.315168)
		(end 185.837068 -23.315168)
		(width 0.127)
		(layer "F.Cu")
		(net "SYS_DBMODE4")
	)
	(segment
		(start 179.5018 -27.381454)
		(end 179.5018 -27.437588)
		(width 0.127)
		(layer "F.Cu")
		(net "SYS_DBMODE4")
	)
	(segment
		(start 179.5018 -27.437588)
		(end 179.301902 -27.637486)
		(width 0.127)
		(layer "F.Cu")
		(net "SYS_DBMODE4")
	)
	(segment
		(start 182.71871 -24.580342)
		(end 182.25135 -25.047702)
		(width 0.127)
		(layer "F.Cu")
		(net "SYS_DBMODE4")
	)
	(segment
		(start 185.837068 -23.315168)
		(end 185.9026 -23.3807)
		(width 0.127)
		(layer "F.Cu")
		(net "SYS_DBMODE4")
	)
	(segment
		(start 182.71871 -24.580342)
		(end 183.983884 -23.315168)
		(width 0.127)
		(layer "F.Cu")
		(net "SYS_DBMODE4")
	)
	(segment
		(start 179.301902 -28.30195)
		(end 179.399946 -28.399994)
		(width 0.127)
		(layer "F.Cu")
		(net "SYS_DBMODE4")
	)
	(segment
		(start 181.13629 -26.711148)
		(end 180.172106 -26.711148)
		(width 0.127)
		(layer "F.Cu")
		(net "SYS_DBMODE4")
	)
	(segment
		(start 182.25135 -25.047702)
		(end 182.25135 -25.596088)
		(width 0.127)
		(layer "F.Cu")
		(net "SYS_DBMODE4")
	)
	(segment
		(start 179.301902 -27.637486)
		(end 179.301902 -28.30195)
		(width 0.127)
		(layer "F.Cu")
		(net "SYS_DBMODE4")
	)
	(segment
		(start 182.25135 -25.596088)
		(end 181.13629 -26.711148)
		(width 0.127)
		(layer "F.Cu")
		(net "SYS_DBMODE4")
	)
	(segment
		(start 180.172106 -26.711148)
		(end 179.5018 -27.381454)
		(width 0.127)
		(layer "F.Cu")
		(net "SYS_DBMODE4")
	)
	(via
		(at 182.71871 -24.580342)
		(size 0.6604)
		(drill 0.3302)
		(layers "F.Cu" "B.Cu")
		(net "SYS_DBMODE4")
	)
	(segment
		(start 183.113426 -25.388824)
		(end 184.588658 -23.913592)
		(width 0.127)
		(layer "F.Cu")
		(net "SYS_DBMODE3")
	)
	(segment
		(start 180.999892 -29.19984)
		(end 180.656992 -28.85694)
		(width 0.127)
		(layer "F.Cu")
		(net "SYS_DBMODE3")
	)
	(segment
		(start 187.8203 -22.9362)
		(end 187.8203 -23.2918)
		(width 0.127)
		(layer "F.Cu")
		(net "SYS_DBMODE3")
	)
	(segment
		(start 186.6138 -23.6982)
		(end 186.298078 -24.013922)
		(width 0.127)
		(layer "F.Cu")
		(net "SYS_DBMODE3")
	)
	(segment
		(start 188.352938 -22.9616)
		(end 188.8363 -22.9616)
		(width 0.127)
		(layer "F.Cu")
		(net "SYS_DBMODE3")
	)
	(segment
		(start 187.8203 -23.2918)
		(end 187.4139 -23.6982)
		(width 0.127)
		(layer "F.Cu")
		(net "SYS_DBMODE3")
	)
	(segment
		(start 182.818024 -25.388824)
		(end 183.113426 -25.388824)
		(width 0.127)
		(layer "F.Cu")
		(net "SYS_DBMODE3")
	)
	(segment
		(start 188.327538 -22.9362)
		(end 188.352938 -22.9616)
		(width 0.127)
		(layer "F.Cu")
		(net "SYS_DBMODE3")
	)
	(segment
		(start 186.298078 -24.013922)
		(end 185.318146 -24.013922)
		(width 0.127)
		(layer "F.Cu")
		(net "SYS_DBMODE3")
	)
	(segment
		(start 180.656992 -27.549856)
		(end 182.818024 -25.388824)
		(width 0.127)
		(layer "F.Cu")
		(net "SYS_DBMODE3")
	)
	(segment
		(start 185.217816 -23.913592)
		(end 184.842658 -23.913592)
		(width 0.127)
		(layer "F.Cu")
		(net "SYS_DBMODE3")
	)
	(segment
		(start 185.318146 -24.013922)
		(end 185.217816 -23.913592)
		(width 0.127)
		(layer "F.Cu")
		(net "SYS_DBMODE3")
	)
	(segment
		(start 187.4139 -23.6982)
		(end 186.6138 -23.6982)
		(width 0.127)
		(layer "F.Cu")
		(net "SYS_DBMODE3")
	)
	(segment
		(start 184.588658 -23.913592)
		(end 184.842658 -23.913592)
		(width 0.127)
		(layer "F.Cu")
		(net "SYS_DBMODE3")
	)
	(segment
		(start 180.656992 -28.85694)
		(end 180.656992 -27.549856)
		(width 0.127)
		(layer "F.Cu")
		(net "SYS_DBMODE3")
	)
	(segment
		(start 187.8203 -22.9362)
		(end 188.327538 -22.9362)
		(width 0.127)
		(layer "F.Cu")
		(net "SYS_DBMODE3")
	)
	(via
		(at 184.842658 -23.913592)
		(size 0.6604)
		(drill 0.3302)
		(layers "F.Cu" "B.Cu")
		(net "SYS_DBMODE3")
	)
	(segment
		(start 190.7413 -24.8412)
		(end 190.35522 -24.8412)
		(width 0.127)
		(layer "F.Cu")
		(net "SYS_DBMODE2")
	)
	(segment
		(start 181.5973 -27.687778)
		(end 182.590186 -26.694892)
		(width 0.127)
		(layer "F.Cu")
		(net "SYS_DBMODE2")
	)
	(segment
		(start 181.5973 -28.197302)
		(end 181.5973 -27.687778)
		(width 0.127)
		(layer "F.Cu")
		(net "SYS_DBMODE2")
	)
	(segment
		(start 182.590186 -26.694892)
		(end 182.91302 -26.694892)
		(width 0.127)
		(layer "F.Cu")
		(net "SYS_DBMODE2")
	)
	(segment
		(start 183.266334 -26.341578)
		(end 184.1246 -26.341578)
		(width 0.127)
		(layer "F.Cu")
		(net "SYS_DBMODE2")
	)
	(segment
		(start 189.23 -25.492964)
		(end 189.115954 -25.60701)
		(width 0.127)
		(layer "F.Cu")
		(net "SYS_DBMODE2")
	)
	(segment
		(start 189.115954 -25.60701)
		(end 188.600842 -25.60701)
		(width 0.127)
		(layer "F.Cu")
		(net "SYS_DBMODE2")
	)
	(segment
		(start 190.35522 -24.8412)
		(end 189.703456 -25.492964)
		(width 0.127)
		(layer "F.Cu")
		(net "SYS_DBMODE2")
	)
	(segment
		(start 184.1246 -26.341578)
		(end 184.859168 -25.60701)
		(width 0.127)
		(layer "F.Cu")
		(net "SYS_DBMODE2")
	)
	(segment
		(start 190.759842 -23.76551)
		(end 190.759842 -24.822658)
		(width 0.127)
		(layer "F.Cu")
		(net "SYS_DBMODE2")
	)
	(segment
		(start 182.91302 -26.694892)
		(end 183.266334 -26.341578)
		(width 0.127)
		(layer "F.Cu")
		(net "SYS_DBMODE2")
	)
	(segment
		(start 189.703456 -25.492964)
		(end 189.23 -25.492964)
		(width 0.127)
		(layer "F.Cu")
		(net "SYS_DBMODE2")
	)
	(segment
		(start 190.759842 -24.822658)
		(end 190.7413 -24.8412)
		(width 0.127)
		(layer "F.Cu")
		(net "SYS_DBMODE2")
	)
	(segment
		(start 184.859168 -25.60701)
		(end 188.600842 -25.60701)
		(width 0.127)
		(layer "F.Cu")
		(net "SYS_DBMODE2")
	)
	(segment
		(start 181.799992 -28.399994)
		(end 181.5973 -28.197302)
		(width 0.127)
		(layer "F.Cu")
		(net "SYS_DBMODE2")
	)
	(via
		(at 188.600842 -25.60701)
		(size 0.6604)
		(drill 0.3302)
		(layers "F.Cu" "B.Cu")
		(net "SYS_DBMODE2")
	)
	(segment
		(start 184.413906 -21.57857)
		(end 184.808876 -21.1836)
		(width 0.127)
		(layer "F.Cu")
		(net "SYS_DBMODE1")
	)
	(segment
		(start 187.8203 -21.4757)
		(end 187.8203 -21.8948)
		(width 0.127)
		(layer "F.Cu")
		(net "SYS_DBMODE1")
	)
	(segment
		(start 178.599846 -27.080718)
		(end 178.855116 -26.825448)
		(width 0.127)
		(layer "F.Cu")
		(net "SYS_DBMODE1")
	)
	(segment
		(start 181.918864 -25.319736)
		(end 181.918864 -23.164292)
		(width 0.127)
		(layer "F.Cu")
		(net "SYS_DBMODE1")
	)
	(segment
		(start 178.599846 -28.399994)
		(end 178.599846 -27.080718)
		(width 0.127)
		(layer "F.Cu")
		(net "SYS_DBMODE1")
	)
	(segment
		(start 178.855116 -26.825448)
		(end 179.676552 -26.825448)
		(width 0.127)
		(layer "F.Cu")
		(net "SYS_DBMODE1")
	)
	(segment
		(start 180.83149 -26.40711)
		(end 181.918864 -25.319736)
		(width 0.127)
		(layer "F.Cu")
		(net "SYS_DBMODE1")
	)
	(segment
		(start 187.5282 -21.1836)
		(end 187.8203 -21.4757)
		(width 0.127)
		(layer "F.Cu")
		(net "SYS_DBMODE1")
	)
	(segment
		(start 180.09489 -26.40711)
		(end 180.83149 -26.40711)
		(width 0.127)
		(layer "F.Cu")
		(net "SYS_DBMODE1")
	)
	(segment
		(start 181.918864 -23.164292)
		(end 183.504586 -21.57857)
		(width 0.127)
		(layer "F.Cu")
		(net "SYS_DBMODE1")
	)
	(segment
		(start 188.8363 -21.9202)
		(end 187.8457 -21.9202)
		(width 0.127)
		(layer "F.Cu")
		(net "SYS_DBMODE1")
	)
	(segment
		(start 187.8457 -21.9202)
		(end 187.8203 -21.8948)
		(width 0.127)
		(layer "F.Cu")
		(net "SYS_DBMODE1")
	)
	(segment
		(start 183.504586 -21.57857)
		(end 184.413906 -21.57857)
		(width 0.127)
		(layer "F.Cu")
		(net "SYS_DBMODE1")
	)
	(segment
		(start 184.808876 -21.1836)
		(end 187.5282 -21.1836)
		(width 0.127)
		(layer "F.Cu")
		(net "SYS_DBMODE1")
	)
	(segment
		(start 179.676552 -26.825448)
		(end 180.09489 -26.40711)
		(width 0.127)
		(layer "F.Cu")
		(net "SYS_DBMODE1")
	)
	(segment
		(start 180.199792 -32.399986)
		(end 180.599588 -32.799782)
		(width 0.127)
		(layer "F.Cu")
		(net "SYS_DBMODE0")
	)
	(via
		(at 180.599588 -32.799782)
		(size 0.508)
		(drill 0.254)
		(layers "F.Cu" "B.Cu")
		(net "SYS_DBMODE0")
	)
	(segment
		(start 179.796694 -34.73958)
		(end 180.212238 -35.155124)
		(width 0.127)
		(layer "B.Cu")
		(net "SYS_DBMODE0")
	)
	(segment
		(start 179.796694 -34.01822)
		(end 179.796694 -34.73958)
		(width 0.127)
		(layer "B.Cu")
		(net "SYS_DBMODE0")
	)
	(segment
		(start 180.212238 -35.155124)
		(end 180.414676 -35.155124)
		(width 0.127)
		(layer "B.Cu")
		(net "SYS_DBMODE0")
	)
	(segment
		(start 179.796694 -33.602676)
		(end 180.599588 -32.799782)
		(width 0.127)
		(layer "B.Cu")
		(net "SYS_DBMODE0")
	)
	(segment
		(start 179.796694 -34.01822)
		(end 179.796694 -33.602676)
		(width 0.127)
		(layer "B.Cu")
		(net "SYS_DBMODE0")
	)
	(segment
		(start 180.414676 -35.155124)
		(end 181.229 -34.3408)
		(width 0.127)
		(layer "B.Cu")
		(net "SYS_DBMODE0")
	)
	(segment
		(start 186.59983 -40.39997)
		(end 187.100464 -40.39997)
		(width 0.127)
		(layer "F.Cu")
		(net "SYS_CORE_TRI#")
	)
	(segment
		(start 190.5889 -40.6527)
		(end 189.24651 -40.6527)
		(width 0.127)
		(layer "F.Cu")
		(net "SYS_CORE_TRI#")
	)
	(segment
		(start 189.24651 -40.6527)
		(end 189.0522 -40.84701)
		(width 0.127)
		(layer "F.Cu")
		(net "SYS_CORE_TRI#")
	)
	(segment
		(start 187.805822 -41.105328)
		(end 188.793882 -41.105328)
		(width 0.127)
		(layer "F.Cu")
		(net "SYS_CORE_TRI#")
	)
	(segment
		(start 188.793882 -41.105328)
		(end 189.0522 -40.84701)
		(width 0.127)
		(layer "F.Cu")
		(net "SYS_CORE_TRI#")
	)
	(segment
		(start 187.100464 -40.39997)
		(end 187.805822 -41.105328)
		(width 0.127)
		(layer "F.Cu")
		(net "SYS_CORE_TRI#")
	)
	(via
		(at 189.0522 -40.84701)
		(size 0.6604)
		(drill 0.3302)
		(layers "F.Cu" "B.Cu")
		(net "SYS_CORE_TRI#")
	)
	(segment
		(start 106.299 -83.947)
		(end 107.315 -83.947)
		(width 0.127)
		(layer "F.Cu")
		(net "SXP_ACTIVE_2")
	)
	(segment
		(start 107.499912 -81.845912)
		(end 107.499912 -81.500218)
		(width 0.127)
		(layer "F.Cu")
		(net "SXP_ACTIVE_2")
	)
	(segment
		(start 107.315 -83.947)
		(end 107.931458 -83.330542)
		(width 0.127)
		(layer "F.Cu")
		(net "SXP_ACTIVE_2")
	)
	(segment
		(start 107.931458 -83.330542)
		(end 107.931458 -82.277458)
		(width 0.127)
		(layer "F.Cu")
		(net "SXP_ACTIVE_2")
	)
	(segment
		(start 105.877614 -85.224112)
		(end 105.877614 -84.368386)
		(width 0.127)
		(layer "F.Cu")
		(net "SXP_ACTIVE_2")
	)
	(segment
		(start 107.931458 -82.277458)
		(end 107.499912 -81.845912)
		(width 0.127)
		(layer "F.Cu")
		(net "SXP_ACTIVE_2")
	)
	(segment
		(start 105.877614 -86.444836)
		(end 105.877614 -85.224112)
		(width 0.127)
		(layer "F.Cu")
		(net "SXP_ACTIVE_2")
	)
	(segment
		(start 105.877614 -84.368386)
		(end 106.299 -83.947)
		(width 0.127)
		(layer "F.Cu")
		(net "SXP_ACTIVE_2")
	)
	(via
		(at 105.877614 -85.224112)
		(size 0.6604)
		(drill 0.3302)
		(layers "F.Cu" "B.Cu")
		(net "SXP_ACTIVE_2")
	)
	(segment
		(start 109.499908 -73.500234)
		(end 109.000036 -73.000362)
		(width 0.127)
		(layer "F.Cu")
		(net "SXP_ACTIVE_1")
	)
	(via
		(at 109.000036 -73.000362)
		(size 0.4572)
		(drill 0.2032)
		(layers "F.Cu" "B.Cu")
		(net "SXP_ACTIVE_1")
	)
	(segment
		(start 106.512106 -80.931004)
		(end 106.512106 -83.200494)
		(width 0.127)
		(layer "B.Cu")
		(net "SXP_ACTIVE_1")
	)
	(segment
		(start 107.39374 -80.163416)
		(end 106.950764 -80.606392)
		(width 0.127)
		(layer "B.Cu")
		(net "SXP_ACTIVE_1")
	)
	(segment
		(start 108.500164 -73.500234)
		(end 109.000036 -73.000362)
		(width 0.127)
		(layer "B.Cu")
		(net "SXP_ACTIVE_1")
	)
	(segment
		(start 108.059728 -79.606394)
		(end 107.836716 -79.606394)
		(width 0.127)
		(layer "B.Cu")
		(net "SXP_ACTIVE_1")
	)
	(segment
		(start 106.512106 -83.200494)
		(end 106.0196 -83.693)
		(width 0.127)
		(layer "B.Cu")
		(net "SXP_ACTIVE_1")
	)
	(segment
		(start 106.0196 -83.693)
		(end 106.0196 -86.4997)
		(width 0.127)
		(layer "B.Cu")
		(net "SXP_ACTIVE_1")
	)
	(segment
		(start 108.500164 -75.50023)
		(end 108.500164 -73.500234)
		(width 0.127)
		(layer "B.Cu")
		(net "SXP_ACTIVE_1")
	)
	(segment
		(start 107.39374 -80.04937)
		(end 107.39374 -80.163416)
		(width 0.127)
		(layer "B.Cu")
		(net "SXP_ACTIVE_1")
	)
	(segment
		(start 108.500164 -79.165958)
		(end 108.059728 -79.606394)
		(width 0.127)
		(layer "B.Cu")
		(net "SXP_ACTIVE_1")
	)
	(segment
		(start 106.950764 -80.606392)
		(end 106.836718 -80.606392)
		(width 0.127)
		(layer "B.Cu")
		(net "SXP_ACTIVE_1")
	)
	(segment
		(start 108.500164 -75.50023)
		(end 108.500164 -79.165958)
		(width 0.127)
		(layer "B.Cu")
		(net "SXP_ACTIVE_1")
	)
	(segment
		(start 106.836718 -80.606392)
		(end 106.512106 -80.931004)
		(width 0.127)
		(layer "B.Cu")
		(net "SXP_ACTIVE_1")
	)
	(segment
		(start 107.836716 -79.606394)
		(end 107.39374 -80.04937)
		(width 0.127)
		(layer "B.Cu")
		(net "SXP_ACTIVE_1")
	)
	(segment
		(start 108.49991 -75.50023)
		(end 108.000038 -76.000102)
		(width 0.127)
		(layer "F.Cu")
		(net "SXP_ACTIVE_0")
	)
	(via
		(at 108.000038 -76.000102)
		(size 0.4572)
		(drill 0.2032)
		(layers "F.Cu" "B.Cu")
		(net "SXP_ACTIVE_0")
	)
	(segment
		(start 106.049318 -80.393794)
		(end 106.163364 -80.393794)
		(width 0.127)
		(layer "B.Cu")
		(net "SXP_ACTIVE_0")
	)
	(segment
		(start 107.059476 -79.497682)
		(end 107.499912 -79.057246)
		(width 0.127)
		(layer "B.Cu")
		(net "SXP_ACTIVE_0")
	)
	(segment
		(start 105.0036 -86.15172)
		(end 105.453942 -85.701378)
		(width 0.127)
		(layer "B.Cu")
		(net "SXP_ACTIVE_0")
	)
	(segment
		(start 106.163364 -80.393794)
		(end 106.450638 -80.10652)
		(width 0.127)
		(layer "B.Cu")
		(net "SXP_ACTIVE_0")
	)
	(segment
		(start 106.450638 -80.10652)
		(end 106.450638 -79.992474)
		(width 0.127)
		(layer "B.Cu")
		(net "SXP_ACTIVE_0")
	)
	(segment
		(start 108.000038 -76.000102)
		(end 107.499912 -76.500228)
		(width 0.127)
		(layer "B.Cu")
		(net "SXP_ACTIVE_0")
	)
	(segment
		(start 107.499912 -76.500228)
		(end 107.499912 -77.499972)
		(width 0.127)
		(layer "B.Cu")
		(net "SXP_ACTIVE_0")
	)
	(segment
		(start 106.94543 -79.497682)
		(end 107.059476 -79.497682)
		(width 0.127)
		(layer "B.Cu")
		(net "SXP_ACTIVE_0")
	)
	(segment
		(start 107.499912 -79.057246)
		(end 107.499912 -77.499972)
		(width 0.127)
		(layer "B.Cu")
		(net "SXP_ACTIVE_0")
	)
	(segment
		(start 105.453942 -85.701378)
		(end 105.453942 -80.98917)
		(width 0.127)
		(layer "B.Cu")
		(net "SXP_ACTIVE_0")
	)
	(segment
		(start 105.453942 -80.98917)
		(end 106.049318 -80.393794)
		(width 0.127)
		(layer "B.Cu")
		(net "SXP_ACTIVE_0")
	)
	(segment
		(start 105.0036 -86.4997)
		(end 105.0036 -86.15172)
		(width 0.127)
		(layer "B.Cu")
		(net "SXP_ACTIVE_0")
	)
	(segment
		(start 106.450638 -79.992474)
		(end 106.94543 -79.497682)
		(width 0.127)
		(layer "B.Cu")
		(net "SXP_ACTIVE_0")
	)
	(segment
		(start 177.8 -32.399986)
		(end 178.199796 -32.799782)
		(width 0.127)
		(layer "F.Cu")
		(net "SPARE5")
	)
	(via
		(at 178.199796 -32.799782)
		(size 0.508)
		(drill 0.254)
		(layers "F.Cu" "B.Cu")
		(net "SPARE5")
	)
	(segment
		(start 177.799746 -33.199832)
		(end 178.199796 -32.799782)
		(width 0.127)
		(layer "B.Cu")
		(net "SPARE5")
	)
	(segment
		(start 177.799746 -33.636458)
		(end 177.799746 -33.199832)
		(width 0.127)
		(layer "B.Cu")
		(net "SPARE5")
	)
	(segment
		(start 188.7982 -35.177476)
		(end 187.954666 -36.02101)
		(width 0.127)
		(layer "F.Cu")
		(net "SPARE4")
	)
	(segment
		(start 188.7982 -34.77641)
		(end 188.7982 -35.177476)
		(width 0.127)
		(layer "F.Cu")
		(net "SPARE4")
	)
	(segment
		(start 190.162434 -33.2867)
		(end 189.2427 -34.206434)
		(width 0.127)
		(layer "F.Cu")
		(net "SPARE4")
	)
	(segment
		(start 187.954666 -36.02101)
		(end 186.178952 -36.02101)
		(width 0.127)
		(layer "F.Cu")
		(net "SPARE4")
	)
	(segment
		(start 189.2427 -34.206434)
		(end 189.2427 -34.33191)
		(width 0.127)
		(layer "F.Cu")
		(net "SPARE4")
	)
	(segment
		(start 186.178952 -36.02101)
		(end 185.799984 -36.399978)
		(width 0.127)
		(layer "F.Cu")
		(net "SPARE4")
	)
	(segment
		(start 189.2427 -34.33191)
		(end 188.7982 -34.77641)
		(width 0.127)
		(layer "F.Cu")
		(net "SPARE4")
	)
	(segment
		(start 190.6016 -33.2867)
		(end 190.162434 -33.2867)
		(width 0.127)
		(layer "F.Cu")
		(net "SPARE4")
	)
	(segment
		(start 178.599846 -32.399986)
		(end 178.999642 -32.799782)
		(width 0.127)
		(layer "F.Cu")
		(net "SPARE3")
	)
	(via
		(at 178.999642 -32.799782)
		(size 0.508)
		(drill 0.254)
		(layers "F.Cu" "B.Cu")
		(net "SPARE3")
	)
	(segment
		(start 176.93513 -32.380682)
		(end 178.580542 -32.380682)
		(width 0.127)
		(layer "B.Cu")
		(net "SPARE3")
	)
	(segment
		(start 176.193196 -33.122616)
		(end 176.93513 -32.380682)
		(width 0.127)
		(layer "B.Cu")
		(net "SPARE3")
	)
	(segment
		(start 178.580542 -32.380682)
		(end 178.999642 -32.799782)
		(width 0.127)
		(layer "B.Cu")
		(net "SPARE3")
	)
	(segment
		(start 176.193196 -33.60293)
		(end 176.193196 -33.122616)
		(width 0.127)
		(layer "B.Cu")
		(net "SPARE3")
	)
	(segment
		(start 179.742846 -28.742894)
		(end 180.199792 -29.19984)
		(width 0.127)
		(layer "F.Cu")
		(net "SPARE2")
	)
	(segment
		(start 179.742846 -27.940508)
		(end 179.742846 -28.742894)
		(width 0.127)
		(layer "F.Cu")
		(net "SPARE2")
	)
	(via
		(at 179.742846 -27.940508)
		(size 0.508)
		(drill 0.254)
		(layers "F.Cu" "B.Cu")
		(net "SPARE2")
	)
	(segment
		(start 179.742846 -27.940508)
		(end 180.264308 -27.940508)
		(width 0.127)
		(layer "B.Cu")
		(net "SPARE2")
	)
	(segment
		(start 180.264308 -27.940508)
		(end 180.8988 -28.575)
		(width 0.127)
		(layer "B.Cu")
		(net "SPARE2")
	)
	(segment
		(start 180.8988 -28.575)
		(end 181.2798 -28.575)
		(width 0.127)
		(layer "B.Cu")
		(net "SPARE2")
	)
	(segment
		(start 182.599838 -28.399994)
		(end 182.62854 -28.371292)
		(width 0.127)
		(layer "F.Cu")
		(net "SPARE1")
	)
	(segment
		(start 182.62854 -28.371292)
		(end 182.62854 -27.249374)
		(width 0.127)
		(layer "F.Cu")
		(net "SPARE1")
	)
	(via
		(at 182.62854 -27.249374)
		(size 0.508)
		(drill 0.254)
		(layers "F.Cu" "B.Cu")
		(net "SPARE1")
	)
	(segment
		(start 182.62854 -27.07386)
		(end 183.4642 -26.2382)
		(width 0.127)
		(layer "B.Cu")
		(net "SPARE1")
	)
	(segment
		(start 182.62854 -27.249374)
		(end 182.62854 -27.07386)
		(width 0.127)
		(layer "B.Cu")
		(net "SPARE1")
	)
	(segment
		(start 183.4642 -25.2476)
		(end 184.0484 -24.6634)
		(width 0.127)
		(layer "B.Cu")
		(net "SPARE1")
	)
	(segment
		(start 183.4642 -26.2382)
		(end 183.4642 -25.2476)
		(width 0.127)
		(layer "B.Cu")
		(net "SPARE1")
	)
	(segment
		(start 184.199784 -29.999686)
		(end 184.199784 -29.99994)
		(width 0.127)
		(layer "F.Cu")
		(net "SPARE0")
	)
	(segment
		(start 183.799988 -29.59989)
		(end 184.199784 -29.999686)
		(width 0.127)
		(layer "F.Cu")
		(net "SPARE0")
	)
	(via
		(at 183.799988 -29.59989)
		(size 0.508)
		(drill 0.254)
		(layers "F.Cu" "B.Cu")
		(net "SPARE0")
	)
	(segment
		(start 183.799988 -29.59989)
		(end 184.46369 -29.59989)
		(width 0.127)
		(layer "B.Cu")
		(net "SPARE0")
	)
	(segment
		(start 184.46369 -29.59989)
		(end 184.8358 -29.972)
		(width 0.127)
		(layer "B.Cu")
		(net "SPARE0")
	)
	(segment
		(start 110.106206 -84.178394)
		(end 110.106206 -82.468974)
		(width 0.127)
		(layer "F.Cu")
		(net "SOFT_RESET_N")
	)
	(segment
		(start 110.106206 -82.468974)
		(end 109.499908 -81.862676)
		(width 0.127)
		(layer "F.Cu")
		(net "SOFT_RESET_N")
	)
	(segment
		(start 109.323886 -84.960714)
		(end 110.106206 -84.178394)
		(width 0.127)
		(layer "F.Cu")
		(net "SOFT_RESET_N")
	)
	(segment
		(start 109.499908 -81.862676)
		(end 109.499908 -81.500218)
		(width 0.127)
		(layer "F.Cu")
		(net "SOFT_RESET_N")
	)
	(segment
		(start 109.323886 -85.129116)
		(end 109.323886 -84.960714)
		(width 0.127)
		(layer "F.Cu")
		(net "SOFT_RESET_N")
	)
	(segment
		(start 108.6358 -86.4997)
		(end 109.323886 -85.811614)
		(width 0.127)
		(layer "F.Cu")
		(net "SOFT_RESET_N")
	)
	(segment
		(start 109.323886 -85.811614)
		(end 109.323886 -85.129116)
		(width 0.127)
		(layer "F.Cu")
		(net "SOFT_RESET_N")
	)
	(via
		(at 109.323886 -85.129116)
		(size 0.6604)
		(drill 0.3302)
		(layers "F.Cu" "B.Cu")
		(net "SOFT_RESET_N")
	)
	(segment
		(start 157.790642 -92.563696)
		(end 158.015686 -92.563696)
		(width 0.127)
		(layer "F.Cu")
		(net "SMART_UART_EN")
	)
	(segment
		(start 156.01188 -92.40139)
		(end 157.628336 -92.40139)
		(width 0.127)
		(layer "F.Cu")
		(net "SMART_UART_EN")
	)
	(segment
		(start 158.015686 -92.563696)
		(end 159.277812 -92.563696)
		(width 0.127)
		(layer "F.Cu")
		(net "SMART_UART_EN")
	)
	(segment
		(start 157.628336 -92.40139)
		(end 157.790642 -92.563696)
		(width 0.127)
		(layer "F.Cu")
		(net "SMART_UART_EN")
	)
	(via
		(at 158.015686 -92.563696)
		(size 0.6604)
		(drill 0.3302)
		(layers "F.Cu" "B.Cu")
		(net "SMART_UART_EN")
	)
	(segment
		(start 128.163574 -85.223096)
		(end 128.661922 -85.721444)
		(width 0.127)
		(layer "F.Cu")
		(net "SMART_TX")
	)
	(segment
		(start 128.661922 -85.721444)
		(end 128.661922 -86.618826)
		(width 0.127)
		(layer "F.Cu")
		(net "SMART_TX")
	)
	(segment
		(start 128.163574 -85.223096)
		(end 126.500128 -83.55965)
		(width 0.127)
		(layer "F.Cu")
		(net "SMART_TX")
	)
	(segment
		(start 126.500128 -83.55965)
		(end 126.500128 -82.500216)
		(width 0.127)
		(layer "F.Cu")
		(net "SMART_TX")
	)
	(segment
		(start 128.661922 -86.618826)
		(end 128.863598 -86.820502)
		(width 0.127)
		(layer "F.Cu")
		(net "SMART_TX")
	)
	(via
		(at 128.163574 -85.223096)
		(size 0.6604)
		(drill 0.3302)
		(layers "F.Cu" "B.Cu")
		(net "SMART_TX")
	)
	(segment
		(start 129.44983 -85.237828)
		(end 129.44983 -85.753448)
		(width 0.127)
		(layer "F.Cu")
		(net "SMART_RX")
	)
	(segment
		(start 126.500128 -81.796128)
		(end 126.500128 -81.500218)
		(width 0.127)
		(layer "F.Cu")
		(net "SMART_RX")
	)
	(segment
		(start 130.239516 -86.543134)
		(end 130.239516 -86.800436)
		(width 0.127)
		(layer "F.Cu")
		(net "SMART_RX")
	)
	(segment
		(start 129.44983 -85.237828)
		(end 127 -82.787998)
		(width 0.127)
		(layer "F.Cu")
		(net "SMART_RX")
	)
	(segment
		(start 129.44983 -85.753448)
		(end 130.239516 -86.543134)
		(width 0.127)
		(layer "F.Cu")
		(net "SMART_RX")
	)
	(segment
		(start 127 -82.296)
		(end 126.500128 -81.796128)
		(width 0.127)
		(layer "F.Cu")
		(net "SMART_RX")
	)
	(segment
		(start 127 -82.787998)
		(end 127 -82.296)
		(width 0.127)
		(layer "F.Cu")
		(net "SMART_RX")
	)
	(via
		(at 129.44983 -85.237828)
		(size 0.6604)
		(drill 0.3302)
		(layers "F.Cu" "B.Cu")
		(net "SMART_RX")
	)
	(segment
		(start 163.399724 -44.399962)
		(end 162.689286 -45.1104)
		(width 0.127)
		(layer "F.Cu")
		(net "SIO_LOAD_1")
	)
	(segment
		(start 163.399978 -44.399962)
		(end 163.399724 -44.399962)
		(width 0.127)
		(layer "F.Cu")
		(net "SIO_LOAD_1")
	)
	(via
		(at 162.689286 -45.1104)
		(size 0.508)
		(drill 0.254)
		(layers "F.Cu" "B.Cu")
		(net "SIO_LOAD_1")
	)
	(segment
		(start 163.1442 -51.0413)
		(end 162.56 -51.6255)
		(width 0.127)
		(layer "B.Cu")
		(net "SIO_LOAD_1")
	)
	(segment
		(start 163.1442 -48.66894)
		(end 162.358324 -47.883064)
		(width 0.127)
		(layer "B.Cu")
		(net "SIO_LOAD_1")
	)
	(segment
		(start 162.358324 -47.883064)
		(end 162.358324 -45.441362)
		(width 0.127)
		(layer "B.Cu")
		(net "SIO_LOAD_1")
	)
	(segment
		(start 162.358324 -45.441362)
		(end 162.689286 -45.1104)
		(width 0.127)
		(layer "B.Cu")
		(net "SIO_LOAD_1")
	)
	(segment
		(start 163.1442 -50.419)
		(end 163.1442 -48.66894)
		(width 0.127)
		(layer "B.Cu")
		(net "SIO_LOAD_1")
	)
	(segment
		(start 163.1442 -50.419)
		(end 163.1442 -51.0413)
		(width 0.127)
		(layer "B.Cu")
		(net "SIO_LOAD_1")
	)
	(segment
		(start 164.599874 -43.199812)
		(end 164.99967 -42.800016)
		(width 0.127)
		(layer "F.Cu")
		(net "SIO_LOAD_0")
	)
	(segment
		(start 164.99967 -42.800016)
		(end 164.999924 -42.800016)
		(width 0.127)
		(layer "F.Cu")
		(net "SIO_LOAD_0")
	)
	(via
		(at 164.599874 -43.199812)
		(size 0.508)
		(drill 0.254)
		(layers "F.Cu" "B.Cu")
		(net "SIO_LOAD_0")
	)
	(segment
		(start 165.283388 -47.097188)
		(end 165.283388 -46.593506)
		(width 0.127)
		(layer "B.Cu")
		(net "SIO_LOAD_0")
	)
	(segment
		(start 165.283388 -45.027088)
		(end 164.599874 -44.343574)
		(width 0.127)
		(layer "B.Cu")
		(net "SIO_LOAD_0")
	)
	(segment
		(start 165.9382 -49.0728)
		(end 165.9382 -47.752)
		(width 0.127)
		(layer "B.Cu")
		(net "SIO_LOAD_0")
	)
	(segment
		(start 165.9382 -47.752)
		(end 165.283388 -47.097188)
		(width 0.127)
		(layer "B.Cu")
		(net "SIO_LOAD_0")
	)
	(segment
		(start 164.7698 -50.7873)
		(end 164.7698 -50.2412)
		(width 0.127)
		(layer "B.Cu")
		(net "SIO_LOAD_0")
	)
	(segment
		(start 164.7698 -50.2412)
		(end 165.9382 -49.0728)
		(width 0.127)
		(layer "B.Cu")
		(net "SIO_LOAD_0")
	)
	(segment
		(start 165.608 -51.6255)
		(end 164.7698 -50.7873)
		(width 0.127)
		(layer "B.Cu")
		(net "SIO_LOAD_0")
	)
	(segment
		(start 164.599874 -44.343574)
		(end 164.599874 -43.199812)
		(width 0.127)
		(layer "B.Cu")
		(net "SIO_LOAD_0")
	)
	(segment
		(start 165.283388 -46.593506)
		(end 165.283388 -45.027088)
		(width 0.127)
		(layer "B.Cu")
		(net "SIO_LOAD_0")
	)
	(segment
		(start 164.199824 -42.800016)
		(end 163.800028 -43.199812)
		(width 0.127)
		(layer "F.Cu")
		(net "SIO_DOUT_1")
	)
	(via
		(at 163.800028 -43.199812)
		(size 0.508)
		(drill 0.254)
		(layers "F.Cu" "B.Cu")
		(net "SIO_DOUT_1")
	)
	(segment
		(start 161.544 -50.673)
		(end 161.798 -50.419)
		(width 0.127)
		(layer "B.Cu")
		(net "SIO_DOUT_1")
	)
	(segment
		(start 163.800028 -43.199812)
		(end 162.02914 -44.9707)
		(width 0.127)
		(layer "B.Cu")
		(net "SIO_DOUT_1")
	)
	(segment
		(start 161.544 -51.6255)
		(end 161.544 -50.673)
		(width 0.127)
		(layer "B.Cu")
		(net "SIO_DOUT_1")
	)
	(segment
		(start 162.02914 -50.18786)
		(end 161.798 -50.419)
		(width 0.127)
		(layer "B.Cu")
		(net "SIO_DOUT_1")
	)
	(segment
		(start 162.02914 -44.9707)
		(end 162.02914 -50.18786)
		(width 0.127)
		(layer "B.Cu")
		(net "SIO_DOUT_1")
	)
	(segment
		(start 164.199824 -44.400216)
		(end 164.199824 -44.399962)
		(width 0.127)
		(layer "F.Cu")
		(net "SIO_DOUT_0")
	)
	(segment
		(start 163.800028 -44.800012)
		(end 164.199824 -44.400216)
		(width 0.127)
		(layer "F.Cu")
		(net "SIO_DOUT_0")
	)
	(via
		(at 163.800028 -44.800012)
		(size 0.508)
		(drill 0.254)
		(layers "F.Cu" "B.Cu")
		(net "SIO_DOUT_0")
	)
	(segment
		(start 164.084 -51.1175)
		(end 163.576 -51.6255)
		(width 0.127)
		(layer "B.Cu")
		(net "SIO_DOUT_0")
	)
	(segment
		(start 163.391088 -46.525688)
		(end 164.084 -47.2186)
		(width 0.127)
		(layer "B.Cu")
		(net "SIO_DOUT_0")
	)
	(segment
		(start 163.391088 -45.208952)
		(end 163.391088 -46.525688)
		(width 0.127)
		(layer "B.Cu")
		(net "SIO_DOUT_0")
	)
	(segment
		(start 164.084 -47.2186)
		(end 164.084 -51.1175)
		(width 0.127)
		(layer "B.Cu")
		(net "SIO_DOUT_0")
	)
	(segment
		(start 163.800028 -44.800012)
		(end 163.391088 -45.208952)
		(width 0.127)
		(layer "B.Cu")
		(net "SIO_DOUT_0")
	)
	(segment
		(start 163.800028 -43.999912)
		(end 164.199824 -43.600116)
		(width 0.127)
		(layer "F.Cu")
		(net "SIO_DIN_1")
	)
	(segment
		(start 164.199824 -43.600116)
		(end 164.199824 -43.599862)
		(width 0.127)
		(layer "F.Cu")
		(net "SIO_DIN_1")
	)
	(via
		(at 163.800028 -43.999912)
		(size 0.508)
		(drill 0.254)
		(layers "F.Cu" "B.Cu")
		(net "SIO_DIN_1")
	)
	(segment
		(start 164.6682 -46.863)
		(end 164.355018 -46.549818)
		(width 0.127)
		(layer "B.Cu")
		(net "SIO_DIN_1")
	)
	(segment
		(start 164.355018 -47.8282)
		(end 164.6682 -47.515018)
		(width 0.127)
		(layer "B.Cu")
		(net "SIO_DIN_1")
	)
	(segment
		(start 164.355018 -50.131218)
		(end 164.355018 -47.8282)
		(width 0.127)
		(layer "B.Cu")
		(net "SIO_DIN_1")
	)
	(segment
		(start 164.284152 -44.484036)
		(end 163.800028 -43.999912)
		(width 0.127)
		(layer "B.Cu")
		(net "SIO_DIN_1")
	)
	(segment
		(start 164.5158 -50.292)
		(end 164.355018 -50.131218)
		(width 0.127)
		(layer "B.Cu")
		(net "SIO_DIN_1")
	)
	(segment
		(start 164.5158 -50.89271)
		(end 164.5158 -50.292)
		(width 0.127)
		(layer "B.Cu")
		(net "SIO_DIN_1")
	)
	(segment
		(start 164.6682 -47.515018)
		(end 164.6682 -46.863)
		(width 0.127)
		(layer "B.Cu")
		(net "SIO_DIN_1")
	)
	(segment
		(start 164.355018 -45.931074)
		(end 164.085016 -45.661072)
		(width 0.127)
		(layer "B.Cu")
		(net "SIO_DIN_1")
	)
	(segment
		(start 164.085016 -45.661072)
		(end 164.085016 -45.120306)
		(width 0.127)
		(layer "B.Cu")
		(net "SIO_DIN_1")
	)
	(segment
		(start 164.355018 -46.549818)
		(end 164.355018 -45.931074)
		(width 0.127)
		(layer "B.Cu")
		(net "SIO_DIN_1")
	)
	(segment
		(start 164.592 -51.6255)
		(end 164.592 -50.96891)
		(width 0.127)
		(layer "B.Cu")
		(net "SIO_DIN_1")
	)
	(segment
		(start 164.592 -50.96891)
		(end 164.5158 -50.89271)
		(width 0.127)
		(layer "B.Cu")
		(net "SIO_DIN_1")
	)
	(segment
		(start 164.284152 -44.92117)
		(end 164.284152 -44.484036)
		(width 0.127)
		(layer "B.Cu")
		(net "SIO_DIN_1")
	)
	(segment
		(start 164.085016 -45.120306)
		(end 164.284152 -44.92117)
		(width 0.127)
		(layer "B.Cu")
		(net "SIO_DIN_1")
	)
	(segment
		(start 167.39997 -39.59987)
		(end 166.99992 -39.19982)
		(width 0.127)
		(layer "F.Cu")
		(net "SIO_DIN_0")
	)
	(via
		(at 166.99992 -39.19982)
		(size 0.508)
		(drill 0.254)
		(layers "F.Cu" "B.Cu")
		(net "SIO_DIN_0")
	)
	(segment
		(start 164.454586 -42.6974)
		(end 166.073328 -41.078658)
		(width 0.127)
		(layer "B.Cu")
		(net "SIO_DIN_0")
	)
	(segment
		(start 160.909 -43.902376)
		(end 161.758376 -43.053)
		(width 0.127)
		(layer "B.Cu")
		(net "SIO_DIN_0")
	)
	(segment
		(start 158.496 -51.6255)
		(end 158.496 -49.9618)
		(width 0.127)
		(layer "B.Cu")
		(net "SIO_DIN_0")
	)
	(segment
		(start 166.073328 -41.078658)
		(end 166.68242 -41.078658)
		(width 0.127)
		(layer "B.Cu")
		(net "SIO_DIN_0")
	)
	(segment
		(start 166.99992 -40.761158)
		(end 166.99992 -39.19982)
		(width 0.127)
		(layer "B.Cu")
		(net "SIO_DIN_0")
	)
	(segment
		(start 163.068 -42.6974)
		(end 164.454586 -42.6974)
		(width 0.127)
		(layer "B.Cu")
		(net "SIO_DIN_0")
	)
	(segment
		(start 166.68242 -41.078658)
		(end 166.847012 -40.914066)
		(width 0.127)
		(layer "B.Cu")
		(net "SIO_DIN_0")
	)
	(segment
		(start 162.7124 -43.053)
		(end 163.068 -42.6974)
		(width 0.127)
		(layer "B.Cu")
		(net "SIO_DIN_0")
	)
	(segment
		(start 161.758376 -43.053)
		(end 162.7124 -43.053)
		(width 0.127)
		(layer "B.Cu")
		(net "SIO_DIN_0")
	)
	(segment
		(start 166.847012 -40.914066)
		(end 166.99992 -40.761158)
		(width 0.127)
		(layer "B.Cu")
		(net "SIO_DIN_0")
	)
	(segment
		(start 158.496 -49.9618)
		(end 160.909 -47.5488)
		(width 0.127)
		(layer "B.Cu")
		(net "SIO_DIN_0")
	)
	(segment
		(start 160.909 -47.5488)
		(end 160.909 -43.902376)
		(width 0.127)
		(layer "B.Cu")
		(net "SIO_DIN_0")
	)
	(segment
		(start 162.59175 -44.40809)
		(end 163.399978 -43.599862)
		(width 0.127)
		(layer "F.Cu")
		(net "SIO_CLK_1")
	)
	(segment
		(start 161.885122 -44.40809)
		(end 162.59175 -44.40809)
		(width 0.127)
		(layer "F.Cu")
		(net "SIO_CLK_1")
	)
	(via
		(at 161.885122 -44.40809)
		(size 0.508)
		(drill 0.254)
		(layers "F.Cu" "B.Cu")
		(net "SIO_CLK_1")
	)
	(segment
		(start 161.63036 -44.662852)
		(end 161.63036 -49.24044)
		(width 0.127)
		(layer "B.Cu")
		(net "SIO_CLK_1")
	)
	(segment
		(start 161.885122 -44.40809)
		(end 161.63036 -44.662852)
		(width 0.127)
		(layer "B.Cu")
		(net "SIO_CLK_1")
	)
	(segment
		(start 161.63036 -49.24044)
		(end 160.4518 -50.419)
		(width 0.127)
		(layer "B.Cu")
		(net "SIO_CLK_1")
	)
	(segment
		(start 160.528 -51.6255)
		(end 160.528 -50.4952)
		(width 0.127)
		(layer "B.Cu")
		(net "SIO_CLK_1")
	)
	(segment
		(start 160.528 -50.4952)
		(end 160.4518 -50.419)
		(width 0.127)
		(layer "B.Cu")
		(net "SIO_CLK_1")
	)
	(segment
		(start 162.812984 -42.800016)
		(end 163.399978 -42.800016)
		(width 0.127)
		(layer "F.Cu")
		(net "SIO_CLK_0")
	)
	(segment
		(start 161.885122 -43.51909)
		(end 162.09391 -43.51909)
		(width 0.127)
		(layer "F.Cu")
		(net "SIO_CLK_0")
	)
	(segment
		(start 162.09391 -43.51909)
		(end 162.812984 -42.800016)
		(width 0.127)
		(layer "F.Cu")
		(net "SIO_CLK_0")
	)
	(via
		(at 161.885122 -43.51909)
		(size 0.508)
		(drill 0.254)
		(layers "F.Cu" "B.Cu")
		(net "SIO_CLK_0")
	)
	(segment
		(start 159.512 -51.6255)
		(end 159.512 -50.8254)
		(width 0.127)
		(layer "B.Cu")
		(net "SIO_CLK_0")
	)
	(segment
		(start 161.885122 -43.51909)
		(end 161.237676 -44.166536)
		(width 0.127)
		(layer "B.Cu")
		(net "SIO_CLK_0")
	)
	(segment
		(start 161.237676 -44.166536)
		(end 161.237676 -48.286924)
		(width 0.127)
		(layer "B.Cu")
		(net "SIO_CLK_0")
	)
	(segment
		(start 161.237676 -48.286924)
		(end 159.1056 -50.419)
		(width 0.127)
		(layer "B.Cu")
		(net "SIO_CLK_0")
	)
	(segment
		(start 159.512 -50.8254)
		(end 159.1056 -50.419)
		(width 0.127)
		(layer "B.Cu")
		(net "SIO_CLK_0")
	)
	(segment
		(start 170.599862 -38.800024)
		(end 170.199812 -38.399974)
		(width 0.3048)
		(layer "F.Cu")
		(net "SHELL_PLL_VDD")
	)
	(via
		(at 165.608 -56.007)
		(size 0.6096)
		(drill 0.3048)
		(layers "F.Cu" "B.Cu")
		(net "SHELL_PLL_VDD")
	)
	(via
		(at 170.199812 -38.399974)
		(size 0.508)
		(drill 0.254)
		(layers "F.Cu" "B.Cu")
		(net "SHELL_PLL_VDD")
	)
	(via
		(at 171.201842 -54.30901)
		(size 0.508)
		(drill 0.254)
		(layers "F.Cu" "B.Cu")
		(net "SHELL_PLL_VDD")
	)
	(segment
		(start 165.600888 -56.007)
		(end 165.608 -56.007)
		(width 0.508)
		(layer "B.Cu")
		(net "SHELL_PLL_VDD")
	)
	(segment
		(start 157.168342 -58.952638)
		(end 158.64078 -57.4802)
		(width 0.508)
		(layer "B.Cu")
		(net "SHELL_PLL_VDD")
	)
	(segment
		(start 158.64078 -57.4802)
		(end 164.127688 -57.4802)
		(width 0.508)
		(layer "B.Cu")
		(net "SHELL_PLL_VDD")
	)
	(segment
		(start 164.127688 -57.4802)
		(end 165.600888 -56.007)
		(width 0.508)
		(layer "B.Cu")
		(net "SHELL_PLL_VDD")
	)
	(segment
		(start 167.30599 -54.30901)
		(end 165.608 -56.007)
		(width 0.508)
		(layer "B.Cu")
		(net "SHELL_PLL_VDD")
	)
	(segment
		(start 171.201842 -54.30901)
		(end 167.30599 -54.30901)
		(width 0.508)
		(layer "B.Cu")
		(net "SHELL_PLL_VDD")
	)
	(segment
		(start 170.84675 -54.30901)
		(end 171.201842 -54.30901)
		(width 0.508)
		(layer "In2.Cu")
		(net "SHELL_PLL_VDD")
	)
	(segment
		(start 168.40327 -41.733724)
		(end 166.992808 -43.144186)
		(width 0.508)
		(layer "In2.Cu")
		(net "SHELL_PLL_VDD")
	)
	(segment
		(start 166.992808 -47.732442)
		(end 166.39032 -48.33493)
		(width 0.508)
		(layer "In2.Cu")
		(net "SHELL_PLL_VDD")
	)
	(segment
		(start 170.199812 -38.399974)
		(end 170.137328 -38.399974)
		(width 0.508)
		(layer "In2.Cu")
		(net "SHELL_PLL_VDD")
	)
	(segment
		(start 169.459148 -40.80256)
		(end 168.527984 -41.733724)
		(width 0.508)
		(layer "In2.Cu")
		(net "SHELL_PLL_VDD")
	)
	(segment
		(start 166.39032 -48.33493)
		(end 166.39032 -49.85258)
		(width 0.508)
		(layer "In2.Cu")
		(net "SHELL_PLL_VDD")
	)
	(segment
		(start 168.527984 -41.733724)
		(end 168.40327 -41.733724)
		(width 0.508)
		(layer "In2.Cu")
		(net "SHELL_PLL_VDD")
	)
	(segment
		(start 166.39032 -49.85258)
		(end 170.84675 -54.30901)
		(width 0.508)
		(layer "In2.Cu")
		(net "SHELL_PLL_VDD")
	)
	(segment
		(start 170.137328 -38.399974)
		(end 169.459148 -39.078154)
		(width 0.508)
		(layer "In2.Cu")
		(net "SHELL_PLL_VDD")
	)
	(segment
		(start 166.992808 -43.144186)
		(end 166.992808 -47.732442)
		(width 0.508)
		(layer "In2.Cu")
		(net "SHELL_PLL_VDD")
	)
	(segment
		(start 169.459148 -39.078154)
		(end 169.459148 -40.80256)
		(width 0.508)
		(layer "In2.Cu")
		(net "SHELL_PLL_VDD")
	)
	(segment
		(start 157.262322 -97.867216)
		(end 158.015686 -97.867216)
		(width 0.127)
		(layer "F.Cu")
		(net "SDB_UART_EN")
	)
	(segment
		(start 157.043628 -98.08591)
		(end 157.262322 -97.867216)
		(width 0.127)
		(layer "F.Cu")
		(net "SDB_UART_EN")
	)
	(segment
		(start 158.015686 -97.867216)
		(end 159.277812 -97.867216)
		(width 0.127)
		(layer "F.Cu")
		(net "SDB_UART_EN")
	)
	(segment
		(start 156.01188 -98.08591)
		(end 157.043628 -98.08591)
		(width 0.127)
		(layer "F.Cu")
		(net "SDB_UART_EN")
	)
	(via
		(at 158.015686 -97.867216)
		(size 0.6604)
		(drill 0.3302)
		(layers "F.Cu" "B.Cu")
		(net "SDB_UART_EN")
	)
	(segment
		(start 154.583638 -97.12071)
		(end 155.048458 -97.58553)
		(width 0.127)
		(layer "F.Cu")
		(net "SDB_TX_R")
	)
	(segment
		(start 153.8224 -94.869)
		(end 154.2034 -95.25)
		(width 0.127)
		(layer "F.Cu")
		(net "SDB_TX_R")
	)
	(segment
		(start 154.2034 -95.25)
		(end 154.2034 -95.72244)
		(width 0.127)
		(layer "F.Cu")
		(net "SDB_TX_R")
	)
	(segment
		(start 152.978612 -94.869)
		(end 153.8224 -94.869)
		(width 0.127)
		(layer "F.Cu")
		(net "SDB_TX_R")
	)
	(segment
		(start 155.048458 -97.58553)
		(end 156.01188 -97.58553)
		(width 0.127)
		(layer "F.Cu")
		(net "SDB_TX_R")
	)
	(segment
		(start 154.2034 -95.72244)
		(end 154.583638 -96.102678)
		(width 0.127)
		(layer "F.Cu")
		(net "SDB_TX_R")
	)
	(segment
		(start 152.609042 -95.23857)
		(end 152.978612 -94.869)
		(width 0.127)
		(layer "F.Cu")
		(net "SDB_TX_R")
	)
	(segment
		(start 154.583638 -96.102678)
		(end 154.583638 -97.12071)
		(width 0.127)
		(layer "F.Cu")
		(net "SDB_TX_R")
	)
	(via
		(at 153.8224 -94.869)
		(size 0.6604)
		(drill 0.3302)
		(layers "F.Cu" "B.Cu")
		(net "SDB_TX_R")
	)
	(segment
		(start 127.073152 -89.068148)
		(end 127.073152 -88.014048)
		(width 0.127)
		(layer "F.Cu")
		(net "SDB_TX")
	)
	(segment
		(start 126.802134 -89.483438)
		(end 126.9238 -89.4715)
		(width 0.127)
		(layer "F.Cu")
		(net "SDB_TX")
	)
	(segment
		(start 126.0983 -89.764108)
		(end 126.37897 -89.483438)
		(width 0.127)
		(layer "F.Cu")
		(net "SDB_TX")
	)
	(segment
		(start 126.7714 -92.305886)
		(end 126.697486 -92.305886)
		(width 0.127)
		(layer "F.Cu")
		(net "SDB_TX")
	)
	(segment
		(start 149.705314 -96.063308)
		(end 149.969728 -96.063308)
		(width 0.127)
		(layer "F.Cu")
		(net "SDB_TX")
	)
	(segment
		(start 126.37897 -89.483438)
		(end 126.802134 -89.483438)
		(width 0.127)
		(layer "F.Cu")
		(net "SDB_TX")
	)
	(segment
		(start 151.720042 -95.23857)
		(end 150.794466 -95.23857)
		(width 0.127)
		(layer "F.Cu")
		(net "SDB_TX")
	)
	(segment
		(start 150.794466 -95.23857)
		(end 150.498302 -95.534734)
		(width 0.127)
		(layer "F.Cu")
		(net "SDB_TX")
	)
	(segment
		(start 149.969728 -96.063308)
		(end 150.498302 -95.534734)
		(width 0.127)
		(layer "F.Cu")
		(net "SDB_TX")
	)
	(segment
		(start 127.073152 -88.014048)
		(end 127.3683 -87.7189)
		(width 0.127)
		(layer "F.Cu")
		(net "SDB_TX")
	)
	(segment
		(start 126.697486 -92.305886)
		(end 126.0983 -91.7067)
		(width 0.127)
		(layer "F.Cu")
		(net "SDB_TX")
	)
	(segment
		(start 127.3683 -87.7189)
		(end 127.6858 -87.7189)
		(width 0.127)
		(layer "F.Cu")
		(net "SDB_TX")
	)
	(segment
		(start 126.0983 -91.7067)
		(end 126.0983 -89.764108)
		(width 0.127)
		(layer "F.Cu")
		(net "SDB_TX")
	)
	(segment
		(start 126.9238 -89.4715)
		(end 127.073152 -89.068148)
		(width 0.127)
		(layer "F.Cu")
		(net "SDB_TX")
	)
	(via
		(at 149.705314 -96.063308)
		(size 0.508)
		(drill 0.254)
		(layers "F.Cu" "B.Cu")
		(net "SDB_TX")
	)
	(via
		(at 150.498302 -95.534734)
		(size 0.6604)
		(drill 0.3302)
		(layers "F.Cu" "B.Cu")
		(net "SDB_TX")
	)
	(via
		(at 126.7714 -92.305886)
		(size 0.508)
		(drill 0.254)
		(layers "F.Cu" "B.Cu")
		(net "SDB_TX")
	)
	(segment
		(start 128.34747 -98.755708)
		(end 128.362964 -98.771202)
		(width 0.127)
		(layer "In2.Cu")
		(net "SDB_TX")
	)
	(segment
		(start 126.7714 -92.305886)
		(end 126.9492 -92.483686)
		(width 0.127)
		(layer "In2.Cu")
		(net "SDB_TX")
	)
	(segment
		(start 127.2794 -97.687638)
		(end 127.2794 -97.6884)
		(width 0.127)
		(layer "In2.Cu")
		(net "SDB_TX")
	)
	(segment
		(start 128.346708 -98.755708)
		(end 128.34747 -98.755708)
		(width 0.127)
		(layer "In2.Cu")
		(net "SDB_TX")
	)
	(segment
		(start 127.2794 -97.6884)
		(end 128.346708 -98.755708)
		(width 0.127)
		(layer "In2.Cu")
		(net "SDB_TX")
	)
	(segment
		(start 142.651988 -98.771202)
		(end 142.667482 -98.755708)
		(width 0.127)
		(layer "In2.Cu")
		(net "SDB_TX")
	)
	(segment
		(start 126.9492 -92.483686)
		(end 126.9492 -97.357438)
		(width 0.127)
		(layer "In2.Cu")
		(net "SDB_TX")
	)
	(segment
		(start 128.362964 -98.771202)
		(end 142.651988 -98.771202)
		(width 0.127)
		(layer "In2.Cu")
		(net "SDB_TX")
	)
	(segment
		(start 142.667482 -98.755708)
		(end 147.71624 -98.755708)
		(width 0.127)
		(layer "In2.Cu")
		(net "SDB_TX")
	)
	(segment
		(start 149.521418 -96.247204)
		(end 149.705314 -96.063308)
		(width 0.127)
		(layer "In2.Cu")
		(net "SDB_TX")
	)
	(segment
		(start 147.71624 -98.755708)
		(end 149.521418 -96.95053)
		(width 0.127)
		(layer "In2.Cu")
		(net "SDB_TX")
	)
	(segment
		(start 126.9492 -97.357438)
		(end 127.2794 -97.687638)
		(width 0.127)
		(layer "In2.Cu")
		(net "SDB_TX")
	)
	(segment
		(start 149.521418 -96.95053)
		(end 149.521418 -96.247204)
		(width 0.127)
		(layer "In2.Cu")
		(net "SDB_TX")
	)
	(segment
		(start 153.67508 -97.58553)
		(end 153.67508 -97.13976)
		(width 0.127)
		(layer "F.Cu")
		(net "SDB_RX_R")
	)
	(segment
		(start 152.724612 -96.139)
		(end 153.5684 -96.139)
		(width 0.127)
		(layer "F.Cu")
		(net "SDB_RX_R")
	)
	(segment
		(start 153.5684 -96.139)
		(end 153.68778 -96.25838)
		(width 0.127)
		(layer "F.Cu")
		(net "SDB_RX_R")
	)
	(segment
		(start 153.8224 -96.393)
		(end 153.68778 -96.25838)
		(width 0.127)
		(layer "F.Cu")
		(net "SDB_RX_R")
	)
	(segment
		(start 153.67508 -97.13976)
		(end 153.8224 -96.99244)
		(width 0.127)
		(layer "F.Cu")
		(net "SDB_RX_R")
	)
	(segment
		(start 152.609042 -96.25457)
		(end 152.724612 -96.139)
		(width 0.127)
		(layer "F.Cu")
		(net "SDB_RX_R")
	)
	(segment
		(start 153.8224 -96.99244)
		(end 153.8224 -96.393)
		(width 0.127)
		(layer "F.Cu")
		(net "SDB_RX_R")
	)
	(via
		(at 153.68778 -96.25838)
		(size 0.6604)
		(drill 0.3302)
		(layers "F.Cu" "B.Cu")
		(net "SDB_RX_R")
	)
	(segment
		(start 125.208538 -91.9607)
		(end 124.4473 -91.199462)
		(width 0.127)
		(layer "F.Cu")
		(net "SDB_RX")
	)
	(segment
		(start 124.930408 -89.535)
		(end 125.2093 -89.535)
		(width 0.127)
		(layer "F.Cu")
		(net "SDB_RX")
	)
	(segment
		(start 149.940264 -97.681288)
		(end 150.48865 -97.132902)
		(width 0.127)
		(layer "F.Cu")
		(net "SDB_RX")
	)
	(segment
		(start 124.4473 -91.199462)
		(end 124.4473 -90.018108)
		(width 0.127)
		(layer "F.Cu")
		(net "SDB_RX")
	)
	(segment
		(start 151.366982 -96.25457)
		(end 150.48865 -97.132902)
		(width 0.127)
		(layer "F.Cu")
		(net "SDB_RX")
	)
	(segment
		(start 151.720042 -96.25457)
		(end 151.366982 -96.25457)
		(width 0.127)
		(layer "F.Cu")
		(net "SDB_RX")
	)
	(segment
		(start 149.706076 -97.681288)
		(end 149.940264 -97.681288)
		(width 0.127)
		(layer "F.Cu")
		(net "SDB_RX")
	)
	(segment
		(start 126.0348 -88.1507)
		(end 126.4666 -87.7189)
		(width 0.127)
		(layer "F.Cu")
		(net "SDB_RX")
	)
	(segment
		(start 125.2093 -89.535)
		(end 125.2728 -89.4715)
		(width 0.127)
		(layer "F.Cu")
		(net "SDB_RX")
	)
	(segment
		(start 124.4473 -90.018108)
		(end 124.930408 -89.535)
		(width 0.127)
		(layer "F.Cu")
		(net "SDB_RX")
	)
	(segment
		(start 125.5776 -92.4052)
		(end 125.5776 -92.329)
		(width 0.127)
		(layer "F.Cu")
		(net "SDB_RX")
	)
	(segment
		(start 125.2093 -91.9607)
		(end 125.208538 -91.9607)
		(width 0.127)
		(layer "F.Cu")
		(net "SDB_RX")
	)
	(segment
		(start 126.0348 -88.7095)
		(end 126.0348 -88.1507)
		(width 0.127)
		(layer "F.Cu")
		(net "SDB_RX")
	)
	(segment
		(start 125.2728 -89.4715)
		(end 126.0348 -88.7095)
		(width 0.127)
		(layer "F.Cu")
		(net "SDB_RX")
	)
	(segment
		(start 125.5776 -92.329)
		(end 125.2093 -91.9607)
		(width 0.127)
		(layer "F.Cu")
		(net "SDB_RX")
	)
	(via
		(at 149.706076 -97.681288)
		(size 0.508)
		(drill 0.254)
		(layers "F.Cu" "B.Cu")
		(net "SDB_RX")
	)
	(via
		(at 150.48865 -97.132902)
		(size 0.6604)
		(drill 0.3302)
		(layers "F.Cu" "B.Cu")
		(net "SDB_RX")
	)
	(via
		(at 125.5776 -92.4052)
		(size 0.508)
		(drill 0.254)
		(layers "F.Cu" "B.Cu")
		(net "SDB_RX")
	)
	(segment
		(start 147.996656 -99.390708)
		(end 149.706076 -97.681288)
		(width 0.127)
		(layer "In2.Cu")
		(net "SDB_RX")
	)
	(segment
		(start 125.5776 -92.4052)
		(end 125.5776 -97.2058)
		(width 0.127)
		(layer "In2.Cu")
		(net "SDB_RX")
	)
	(segment
		(start 142.915132 -99.406202)
		(end 142.930626 -99.390708)
		(width 0.127)
		(layer "In2.Cu")
		(net "SDB_RX")
	)
	(segment
		(start 125.5776 -97.2058)
		(end 127.778002 -99.406202)
		(width 0.127)
		(layer "In2.Cu")
		(net "SDB_RX")
	)
	(segment
		(start 142.930626 -99.390708)
		(end 147.996656 -99.390708)
		(width 0.127)
		(layer "In2.Cu")
		(net "SDB_RX")
	)
	(segment
		(start 127.778002 -99.406202)
		(end 142.915132 -99.406202)
		(width 0.127)
		(layer "In2.Cu")
		(net "SDB_RX")
	)
	(segment
		(start 127.6858 -86.026498)
		(end 127.6858 -86.8299)
		(width 0.127)
		(layer "F.Cu")
		(net "SDB_R_TX")
	)
	(segment
		(start 126.877318 -85.218016)
		(end 125.984 -84.324698)
		(width 0.127)
		(layer "F.Cu")
		(net "SDB_R_TX")
	)
	(segment
		(start 125.984 -82.288634)
		(end 125.50013 -81.804764)
		(width 0.127)
		(layer "F.Cu")
		(net "SDB_R_TX")
	)
	(segment
		(start 125.50013 -81.804764)
		(end 125.50013 -81.500218)
		(width 0.127)
		(layer "F.Cu")
		(net "SDB_R_TX")
	)
	(segment
		(start 125.984 -84.324698)
		(end 125.984 -82.288634)
		(width 0.127)
		(layer "F.Cu")
		(net "SDB_R_TX")
	)
	(segment
		(start 126.877318 -85.218016)
		(end 127.6858 -86.026498)
		(width 0.127)
		(layer "F.Cu")
		(net "SDB_R_TX")
	)
	(via
		(at 126.877318 -85.218016)
		(size 0.6604)
		(drill 0.3302)
		(layers "F.Cu" "B.Cu")
		(net "SDB_R_TX")
	)
	(segment
		(start 126.4666 -86.8299)
		(end 126.4666 -86.076028)
		(width 0.127)
		(layer "F.Cu")
		(net "SDB_R_RX")
	)
	(segment
		(start 125.50013 -82.500216)
		(end 125.50013 -85.109558)
		(width 0.127)
		(layer "F.Cu")
		(net "SDB_R_RX")
	)
	(segment
		(start 126.4666 -86.076028)
		(end 125.607318 -85.216746)
		(width 0.127)
		(layer "F.Cu")
		(net "SDB_R_RX")
	)
	(segment
		(start 125.50013 -85.109558)
		(end 125.607318 -85.216746)
		(width 0.127)
		(layer "F.Cu")
		(net "SDB_R_RX")
	)
	(via
		(at 125.607318 -85.216746)
		(size 0.6604)
		(drill 0.3302)
		(layers "F.Cu" "B.Cu")
		(net "SDB_R_RX")
	)
	(segment
		(start 188.139832 -43.539918)
		(end 186.59983 -41.999916)
		(width 0.127)
		(layer "F.Cu")
		(net "SBL_SDA")
	)
	(segment
		(start 191.406272 -45.479462)
		(end 190.945262 -45.479462)
		(width 0.127)
		(layer "F.Cu")
		(net "SBL_SDA")
	)
	(segment
		(start 189.95644 -44.49064)
		(end 189.61354 -44.49064)
		(width 0.127)
		(layer "F.Cu")
		(net "SBL_SDA")
	)
	(segment
		(start 191.8589 -44.831)
		(end 191.406272 -45.283628)
		(width 0.127)
		(layer "F.Cu")
		(net "SBL_SDA")
	)
	(segment
		(start 197.3707 -44.831)
		(end 195.669154 -44.831)
		(width 0.127)
		(layer "F.Cu")
		(net "SBL_SDA")
	)
	(segment
		(start 191.406272 -45.283628)
		(end 191.406272 -45.479462)
		(width 0.127)
		(layer "F.Cu")
		(net "SBL_SDA")
	)
	(segment
		(start 195.669154 -44.831)
		(end 191.8589 -44.831)
		(width 0.127)
		(layer "F.Cu")
		(net "SBL_SDA")
	)
	(segment
		(start 189.61354 -44.49064)
		(end 188.662818 -43.539918)
		(width 0.127)
		(layer "F.Cu")
		(net "SBL_SDA")
	)
	(segment
		(start 188.662818 -43.539918)
		(end 188.139832 -43.539918)
		(width 0.127)
		(layer "F.Cu")
		(net "SBL_SDA")
	)
	(segment
		(start 190.945262 -45.479462)
		(end 189.95644 -44.49064)
		(width 0.127)
		(layer "F.Cu")
		(net "SBL_SDA")
	)
	(segment
		(start 197.9168 -45.3771)
		(end 197.3707 -44.831)
		(width 0.127)
		(layer "F.Cu")
		(net "SBL_SDA")
	)
	(via
		(at 197.9168 -45.3771)
		(size 0.508)
		(drill 0.254)
		(layers "F.Cu" "B.Cu")
		(net "SBL_SDA")
	)
	(via
		(at 195.669154 -44.831)
		(size 0.6604)
		(drill 0.3302)
		(layers "F.Cu" "B.Cu")
		(net "SBL_SDA")
	)
	(segment
		(start 198.066914 -45.527214)
		(end 197.9168 -45.3771)
		(width 0.127)
		(layer "B.Cu")
		(net "SBL_SDA")
	)
	(segment
		(start 198.066914 -46.439074)
		(end 198.066914 -45.527214)
		(width 0.127)
		(layer "B.Cu")
		(net "SBL_SDA")
	)
	(segment
		(start 191.0334 -39.9288)
		(end 194.46621 -39.9288)
		(width 0.127)
		(layer "F.Cu")
		(net "SBL_SCL")
	)
	(segment
		(start 195.6054 -39.9288)
		(end 199.7329 -44.0563)
		(width 0.127)
		(layer "F.Cu")
		(net "SBL_SCL")
	)
	(segment
		(start 199.7329 -45.4533)
		(end 199.7456 -45.466)
		(width 0.127)
		(layer "F.Cu")
		(net "SBL_SCL")
	)
	(segment
		(start 194.46621 -39.9288)
		(end 195.6054 -39.9288)
		(width 0.127)
		(layer "F.Cu")
		(net "SBL_SCL")
	)
	(segment
		(start 190.590932 -39.486332)
		(end 191.0334 -39.9288)
		(width 0.127)
		(layer "F.Cu")
		(net "SBL_SCL")
	)
	(segment
		(start 190.590932 -39.1414)
		(end 190.590932 -39.486332)
		(width 0.127)
		(layer "F.Cu")
		(net "SBL_SCL")
	)
	(segment
		(start 189.383416 -39.59987)
		(end 186.59983 -39.59987)
		(width 0.127)
		(layer "F.Cu")
		(net "SBL_SCL")
	)
	(segment
		(start 199.7329 -44.0563)
		(end 199.7329 -45.4533)
		(width 0.127)
		(layer "F.Cu")
		(net "SBL_SCL")
	)
	(segment
		(start 190.590932 -39.1414)
		(end 189.841886 -39.1414)
		(width 0.127)
		(layer "F.Cu")
		(net "SBL_SCL")
	)
	(segment
		(start 189.841886 -39.1414)
		(end 189.383416 -39.59987)
		(width 0.127)
		(layer "F.Cu")
		(net "SBL_SCL")
	)
	(via
		(at 199.7456 -45.466)
		(size 0.508)
		(drill 0.254)
		(layers "F.Cu" "B.Cu")
		(net "SBL_SCL")
	)
	(via
		(at 194.46621 -39.9288)
		(size 0.6604)
		(drill 0.3302)
		(layers "F.Cu" "B.Cu")
		(net "SBL_SCL")
	)
	(segment
		(start 200.0758 -45.7962)
		(end 199.7456 -45.466)
		(width 0.127)
		(layer "B.Cu")
		(net "SBL_SCL")
	)
	(segment
		(start 200.0758 -46.4439)
		(end 200.0758 -45.7962)
		(width 0.127)
		(layer "B.Cu")
		(net "SBL_SCL")
	)
	(segment
		(start 162.039808 -36.19881)
		(end 162.240976 -36.399978)
		(width 0.3556)
		(layer "F.Cu")
		(net "SAS0_VDDH")
	)
	(segment
		(start 162.7124 -28.3464)
		(end 162.7124 -28.74391)
		(width 0.3048)
		(layer "F.Cu")
		(net "SAS0_VDDH")
	)
	(segment
		(start 162.240976 -36.399978)
		(end 163.399978 -36.399978)
		(width 0.3556)
		(layer "F.Cu")
		(net "SAS0_VDDH")
	)
	(segment
		(start 161.54273 -33.999932)
		(end 163.399978 -33.999932)
		(width 0.254)
		(layer "F.Cu")
		(net "SAS0_VDDH")
	)
	(segment
		(start 163.16833 -29.19984)
		(end 163.399978 -29.19984)
		(width 0.3048)
		(layer "F.Cu")
		(net "SAS0_VDDH")
	)
	(segment
		(start 167.39997 -33.999932)
		(end 167.000174 -33.600136)
		(width 0.3556)
		(layer "F.Cu")
		(net "SAS0_VDDH")
	)
	(segment
		(start 161.506408 -33.96361)
		(end 161.54273 -33.999932)
		(width 0.254)
		(layer "F.Cu")
		(net "SAS0_VDDH")
	)
	(segment
		(start 162.687 -31.75)
		(end 163.249864 -31.75)
		(width 0.3048)
		(layer "F.Cu")
		(net "SAS0_VDDH")
	)
	(segment
		(start 167.39997 -36.400486)
		(end 167.39997 -36.399978)
		(width 0.3048)
		(layer "F.Cu")
		(net "SAS0_VDDH")
	)
	(segment
		(start 163.800028 -39.200074)
		(end 163.399978 -38.800024)
		(width 0.3048)
		(layer "F.Cu")
		(net "SAS0_VDDH")
	)
	(segment
		(start 162.7124 -28.74391)
		(end 163.16833 -29.19984)
		(width 0.3048)
		(layer "F.Cu")
		(net "SAS0_VDDH")
	)
	(segment
		(start 167.799766 -36.800282)
		(end 167.39997 -36.400486)
		(width 0.3048)
		(layer "F.Cu")
		(net "SAS0_VDDH")
	)
	(segment
		(start 163.249864 -31.75)
		(end 163.399978 -31.599886)
		(width 0.3048)
		(layer "F.Cu")
		(net "SAS0_VDDH")
	)
	(via
		(at 159.893 -30.099)
		(size 0.6096)
		(drill 0.3048)
		(layers "F.Cu" "B.Cu")
		(net "SAS0_VDDH")
	)
	(via
		(at 161.506408 -33.96361)
		(size 0.508)
		(drill 0.254)
		(layers "F.Cu" "B.Cu")
		(net "SAS0_VDDH")
	)
	(via
		(at 162.7124 -28.3464)
		(size 0.508)
		(drill 0.254)
		(layers "F.Cu" "B.Cu")
		(net "SAS0_VDDH")
	)
	(via
		(at 162.039808 -36.19881)
		(size 0.508)
		(drill 0.254)
		(layers "F.Cu" "B.Cu")
		(net "SAS0_VDDH")
	)
	(via
		(at 162.687 -31.75)
		(size 0.508)
		(drill 0.254)
		(layers "F.Cu" "B.Cu")
		(net "SAS0_VDDH")
	)
	(via
		(at 163.800028 -39.200074)
		(size 0.508)
		(drill 0.254)
		(layers "F.Cu" "B.Cu")
		(net "SAS0_VDDH")
	)
	(via
		(at 167.799766 -36.800282)
		(size 0.508)
		(drill 0.254)
		(layers "F.Cu" "B.Cu")
		(net "SAS0_VDDH")
	)
	(via
		(at 167.000174 -33.600136)
		(size 0.508)
		(drill 0.254)
		(layers "F.Cu" "B.Cu")
		(net "SAS0_VDDH")
	)
	(segment
		(start 168.199816 -34.80054)
		(end 168.199816 -34.800032)
		(width 0.3048)
		(layer "F.Cu")
		(net "SAS0_AVDD")
	)
	(segment
		(start 165.419024 -29.61894)
		(end 164.999924 -29.19984)
		(width 0.2032)
		(layer "F.Cu")
		(net "SAS0_AVDD")
	)
	(segment
		(start 168.199816 -37.999924)
		(end 168.599866 -38.399974)
		(width 0.3048)
		(layer "F.Cu")
		(net "SAS0_AVDD")
	)
	(segment
		(start 168.599612 -36.800282)
		(end 168.199816 -36.400486)
		(width 0.3048)
		(layer "F.Cu")
		(net "SAS0_AVDD")
	)
	(segment
		(start 165.800024 -36.399978)
		(end 165.399974 -35.999928)
		(width 0.3048)
		(layer "F.Cu")
		(net "SAS0_AVDD")
	)
	(segment
		(start 165.419024 -30.4038)
		(end 165.419024 -29.61894)
		(width 0.2032)
		(layer "F.Cu")
		(net "SAS0_AVDD")
	)
	(segment
		(start 168.599612 -35.200336)
		(end 168.199816 -34.80054)
		(width 0.3048)
		(layer "F.Cu")
		(net "SAS0_AVDD")
	)
	(segment
		(start 168.199816 -33.199832)
		(end 168.599866 -33.599882)
		(width 0.3048)
		(layer "F.Cu")
		(net "SAS0_AVDD")
	)
	(segment
		(start 165.399974 -30.42285)
		(end 165.419024 -30.4038)
		(width 0.2032)
		(layer "F.Cu")
		(net "SAS0_AVDD")
	)
	(segment
		(start 168.199816 -36.400486)
		(end 168.199816 -36.399978)
		(width 0.3048)
		(layer "F.Cu")
		(net "SAS0_AVDD")
	)
	(segment
		(start 165.800024 -31.599886)
		(end 165.399974 -31.199836)
		(width 0.3048)
		(layer "F.Cu")
		(net "SAS0_AVDD")
	)
	(segment
		(start 165.800024 -33.999932)
		(end 165.399974 -33.599882)
		(width 0.3048)
		(layer "F.Cu")
		(net "SAS0_AVDD")
	)
	(segment
		(start 165.399974 -31.199836)
		(end 165.399974 -30.42285)
		(width 0.2032)
		(layer "F.Cu")
		(net "SAS0_AVDD")
	)
	(segment
		(start 169.800016 -37.999924)
		(end 169.399966 -37.599874)
		(width 0.3048)
		(layer "F.Cu")
		(net "SAS0_AVDD")
	)
	(via
		(at 167.02278 -37.14369)
		(size 0.6096)
		(drill 0.3048)
		(layers "F.Cu" "B.Cu")
		(net "SAS0_AVDD")
	)
	(via
		(at 168.599612 -36.800282)
		(size 0.508)
		(drill 0.254)
		(layers "F.Cu" "B.Cu")
		(net "SAS0_AVDD")
	)
	(via
		(at 179.917598 -99.299776)
		(size 0.6604)
		(drill 0.3302)
		(layers "F.Cu" "B.Cu")
		(net "SAS0_AVDD")
	)
	(via
		(at 168.6052 -37.6174)
		(size 0.6096)
		(drill 0.3048)
		(layers "F.Cu" "B.Cu")
		(net "SAS0_AVDD")
	)
	(via
		(at 168.599866 -33.599882)
		(size 0.508)
		(drill 0.254)
		(layers "F.Cu" "B.Cu")
		(net "SAS0_AVDD")
	)
	(via
		(at 180.5686 -98.2472)
		(size 0.7112)
		(drill 0.4064)
		(layers "F.Cu" "B.Cu")
		(net "SAS0_AVDD")
	)
	(via
		(at 179.324 -100.3554)
		(size 0.7112)
		(drill 0.4064)
		(layers "F.Cu" "B.Cu")
		(net "SAS0_AVDD")
	)
	(via
		(at 167.0558 -35.4838)
		(size 0.6096)
		(drill 0.3048)
		(layers "F.Cu" "B.Cu")
		(net "SAS0_AVDD")
	)
	(via
		(at 181.864 -99.822)
		(size 0.6604)
		(drill 0.3302)
		(layers "F.Cu" "B.Cu")
		(net "SAS0_AVDD")
	)
	(via
		(at 180.594 -100.3554)
		(size 0.7112)
		(drill 0.4064)
		(layers "F.Cu" "B.Cu")
		(net "SAS0_AVDD")
	)
	(via
		(at 183.1594 -98.425)
		(size 0.6604)
		(drill 0.3302)
		(layers "F.Cu" "B.Cu")
		(net "SAS0_AVDD")
	)
	(via
		(at 165.399974 -31.199836)
		(size 0.508)
		(drill 0.254)
		(layers "F.Cu" "B.Cu")
		(net "SAS0_AVDD")
	)
	(via
		(at 165.399974 -35.999928)
		(size 0.508)
		(drill 0.254)
		(layers "F.Cu" "B.Cu")
		(net "SAS0_AVDD")
	)
	(via
		(at 165.399974 -33.599882)
		(size 0.508)
		(drill 0.254)
		(layers "F.Cu" "B.Cu")
		(net "SAS0_AVDD")
	)
	(via
		(at 179.2986 -98.2726)
		(size 0.7112)
		(drill 0.4064)
		(layers "F.Cu" "B.Cu")
		(net "SAS0_AVDD")
	)
	(via
		(at 168.599612 -35.200336)
		(size 0.508)
		(drill 0.254)
		(layers "F.Cu" "B.Cu")
		(net "SAS0_AVDD")
	)
	(via
		(at 169.399966 -37.599874)
		(size 0.508)
		(drill 0.254)
		(layers "F.Cu" "B.Cu")
		(net "SAS0_AVDD")
	)
	(via
		(at 168.599866 -38.399974)
		(size 0.508)
		(drill 0.254)
		(layers "F.Cu" "B.Cu")
		(net "SAS0_AVDD")
	)
	(segment
		(start 165.405816 -35.202114)
		(end 165.405816 -35.994086)
		(width 0.508)
		(layer "B.Cu")
		(net "SAS0_AVDD")
	)
	(segment
		(start 165.405816 -35.994086)
		(end 165.399974 -35.999928)
		(width 0.508)
		(layer "B.Cu")
		(net "SAS0_AVDD")
	)
	(segment
		(start 128.863598 -87.709502)
		(end 129.07645 -87.922354)
		(width 0.127)
		(layer "F.Cu")
		(net "SAS_SMART_TX")
	)
	(segment
		(start 127.7493 -90.018108)
		(end 128.232408 -89.535)
		(width 0.127)
		(layer "F.Cu")
		(net "SAS_SMART_TX")
	)
	(segment
		(start 127.6223 -91.8083)
		(end 127.7493 -91.6813)
		(width 0.127)
		(layer "F.Cu")
		(net "SAS_SMART_TX")
	)
	(segment
		(start 129.07645 -87.922354)
		(end 129.07645 -88.96985)
		(width 0.127)
		(layer "F.Cu")
		(net "SAS_SMART_TX")
	)
	(segment
		(start 127.7493 -91.6813)
		(end 127.7493 -90.018108)
		(width 0.127)
		(layer "F.Cu")
		(net "SAS_SMART_TX")
	)
	(segment
		(start 128.5748 -92.255086)
		(end 127.840486 -92.255086)
		(width 0.127)
		(layer "F.Cu")
		(net "SAS_SMART_TX")
	)
	(segment
		(start 151.808942 -89.593166)
		(end 151.046434 -89.593166)
		(width 0.127)
		(layer "F.Cu")
		(net "SAS_SMART_TX")
	)
	(segment
		(start 128.232408 -89.535)
		(end 128.5113 -89.535)
		(width 0.127)
		(layer "F.Cu")
		(net "SAS_SMART_TX")
	)
	(segment
		(start 128.5113 -89.535)
		(end 128.5748 -89.4715)
		(width 0.127)
		(layer "F.Cu")
		(net "SAS_SMART_TX")
	)
	(segment
		(start 127.6223 -92.0369)
		(end 127.6223 -91.8083)
		(width 0.127)
		(layer "F.Cu")
		(net "SAS_SMART_TX")
	)
	(segment
		(start 127.840486 -92.255086)
		(end 127.6223 -92.0369)
		(width 0.127)
		(layer "F.Cu")
		(net "SAS_SMART_TX")
	)
	(segment
		(start 151.046434 -89.593166)
		(end 150.9776 -89.662)
		(width 0.127)
		(layer "F.Cu")
		(net "SAS_SMART_TX")
	)
	(segment
		(start 129.07645 -88.96985)
		(end 128.5748 -89.4715)
		(width 0.127)
		(layer "F.Cu")
		(net "SAS_SMART_TX")
	)
	(via
		(at 128.5748 -92.255086)
		(size 0.508)
		(drill 0.254)
		(layers "F.Cu" "B.Cu")
		(net "SAS_SMART_TX")
	)
	(via
		(at 150.9776 -89.662)
		(size 0.508)
		(drill 0.254)
		(layers "F.Cu" "B.Cu")
		(net "SAS_SMART_TX")
	)
	(via
		(at 127.6223 -91.8083)
		(size 0.6604)
		(drill 0.3302)
		(layers "F.Cu" "B.Cu")
		(net "SAS_SMART_TX")
	)
	(segment
		(start 134.65175 -89.103454)
		(end 134.258304 -89.4969)
		(width 0.127)
		(layer "In2.Cu")
		(net "SAS_SMART_TX")
	)
	(segment
		(start 150.9776 -89.662)
		(end 149.8219 -89.662)
		(width 0.127)
		(layer "In2.Cu")
		(net "SAS_SMART_TX")
	)
	(segment
		(start 134.258304 -89.4969)
		(end 131.332986 -89.4969)
		(width 0.127)
		(layer "In2.Cu")
		(net "SAS_SMART_TX")
	)
	(segment
		(start 149.8219 -89.662)
		(end 149.263354 -89.103454)
		(width 0.127)
		(layer "In2.Cu")
		(net "SAS_SMART_TX")
	)
	(segment
		(start 149.263354 -89.103454)
		(end 134.65175 -89.103454)
		(width 0.127)
		(layer "In2.Cu")
		(net "SAS_SMART_TX")
	)
	(segment
		(start 131.332986 -89.4969)
		(end 128.5748 -92.255086)
		(width 0.127)
		(layer "In2.Cu")
		(net "SAS_SMART_TX")
	)
	(segment
		(start 130.239516 -87.689436)
		(end 130.239516 -88.086184)
		(width 0.127)
		(layer "F.Cu")
		(net "SAS_SMART_RX")
	)
	(segment
		(start 130.067304 -88.258396)
		(end 130.067304 -88.683592)
		(width 0.127)
		(layer "F.Cu")
		(net "SAS_SMART_RX")
	)
	(segment
		(start 130.239516 -88.086184)
		(end 130.067304 -88.258396)
		(width 0.127)
		(layer "F.Cu")
		(net "SAS_SMART_RX")
	)
	(segment
		(start 151.808942 -90.609166)
		(end 151.046434 -90.609166)
		(width 0.127)
		(layer "F.Cu")
		(net "SAS_SMART_RX")
	)
	(segment
		(start 130.213608 -89.3572)
		(end 129.7305 -89.840308)
		(width 0.127)
		(layer "F.Cu")
		(net "SAS_SMART_RX")
	)
	(segment
		(start 129.7305 -89.840308)
		(end 129.7305 -91.1479)
		(width 0.127)
		(layer "F.Cu")
		(net "SAS_SMART_RX")
	)
	(segment
		(start 130.556 -89.172288)
		(end 130.556 -89.2937)
		(width 0.127)
		(layer "F.Cu")
		(net "SAS_SMART_RX")
	)
	(segment
		(start 130.556 -89.2937)
		(end 130.4925 -89.3572)
		(width 0.127)
		(layer "F.Cu")
		(net "SAS_SMART_RX")
	)
	(segment
		(start 129.5908 -91.2876)
		(end 129.5908 -92.255086)
		(width 0.127)
		(layer "F.Cu")
		(net "SAS_SMART_RX")
	)
	(segment
		(start 130.4925 -89.3572)
		(end 130.213608 -89.3572)
		(width 0.127)
		(layer "F.Cu")
		(net "SAS_SMART_RX")
	)
	(segment
		(start 129.7305 -91.1479)
		(end 129.5908 -91.2876)
		(width 0.127)
		(layer "F.Cu")
		(net "SAS_SMART_RX")
	)
	(segment
		(start 151.046434 -90.609166)
		(end 150.9776 -90.678)
		(width 0.127)
		(layer "F.Cu")
		(net "SAS_SMART_RX")
	)
	(segment
		(start 130.067304 -88.683592)
		(end 130.556 -89.172288)
		(width 0.127)
		(layer "F.Cu")
		(net "SAS_SMART_RX")
	)
	(via
		(at 150.9776 -90.678)
		(size 0.508)
		(drill 0.254)
		(layers "F.Cu" "B.Cu")
		(net "SAS_SMART_RX")
	)
	(via
		(at 129.5908 -91.2876)
		(size 0.6604)
		(drill 0.3302)
		(layers "F.Cu" "B.Cu")
		(net "SAS_SMART_RX")
	)
	(via
		(at 129.5908 -92.255086)
		(size 0.508)
		(drill 0.254)
		(layers "F.Cu" "B.Cu")
		(net "SAS_SMART_RX")
	)
	(segment
		(start 134.914894 -89.738454)
		(end 148.806154 -89.738454)
		(width 0.127)
		(layer "In2.Cu")
		(net "SAS_SMART_RX")
	)
	(segment
		(start 130.1369 -91.708986)
		(end 130.750818 -91.708986)
		(width 0.127)
		(layer "In2.Cu")
		(net "SAS_SMART_RX")
	)
	(segment
		(start 148.806154 -89.738454)
		(end 149.7457 -90.678)
		(width 0.127)
		(layer "In2.Cu")
		(net "SAS_SMART_RX")
	)
	(segment
		(start 129.5908 -92.255086)
		(end 130.1369 -91.708986)
		(width 0.127)
		(layer "In2.Cu")
		(net "SAS_SMART_RX")
	)
	(segment
		(start 134.521448 -90.1319)
		(end 134.914894 -89.738454)
		(width 0.127)
		(layer "In2.Cu")
		(net "SAS_SMART_RX")
	)
	(segment
		(start 149.7457 -90.678)
		(end 150.9776 -90.678)
		(width 0.127)
		(layer "In2.Cu")
		(net "SAS_SMART_RX")
	)
	(segment
		(start 130.750818 -91.708986)
		(end 132.327904 -90.1319)
		(width 0.127)
		(layer "In2.Cu")
		(net "SAS_SMART_RX")
	)
	(segment
		(start 132.327904 -90.1319)
		(end 134.521448 -90.1319)
		(width 0.127)
		(layer "In2.Cu")
		(net "SAS_SMART_RX")
	)
	(segment
		(start 156.01188 -91.90101)
		(end 155.082494 -91.90101)
		(width 0.127)
		(layer "F.Cu")
		(net "SAS_SMART_R_TX")
	)
	(segment
		(start 153.32075 -89.593166)
		(end 153.810716 -89.1032)
		(width 0.127)
		(layer "F.Cu")
		(net "SAS_SMART_R_TX")
	)
	(segment
		(start 154.5717 -90.135202)
		(end 154.5717 -89.515442)
		(width 0.127)
		(layer "F.Cu")
		(net "SAS_SMART_R_TX")
	)
	(segment
		(start 154.61615 -91.434666)
		(end 154.61615 -90.179652)
		(width 0.127)
		(layer "F.Cu")
		(net "SAS_SMART_R_TX")
	)
	(segment
		(start 154.5717 -89.515442)
		(end 154.159458 -89.1032)
		(width 0.127)
		(layer "F.Cu")
		(net "SAS_SMART_R_TX")
	)
	(segment
		(start 152.697942 -89.593166)
		(end 153.32075 -89.593166)
		(width 0.127)
		(layer "F.Cu")
		(net "SAS_SMART_R_TX")
	)
	(segment
		(start 153.810716 -89.1032)
		(end 153.8986 -89.1032)
		(width 0.127)
		(layer "F.Cu")
		(net "SAS_SMART_R_TX")
	)
	(segment
		(start 155.082494 -91.90101)
		(end 154.61615 -91.434666)
		(width 0.127)
		(layer "F.Cu")
		(net "SAS_SMART_R_TX")
	)
	(segment
		(start 154.61615 -90.179652)
		(end 154.5717 -90.135202)
		(width 0.127)
		(layer "F.Cu")
		(net "SAS_SMART_R_TX")
	)
	(segment
		(start 154.159458 -89.1032)
		(end 153.8986 -89.1032)
		(width 0.127)
		(layer "F.Cu")
		(net "SAS_SMART_R_TX")
	)
	(via
		(at 153.8986 -89.1032)
		(size 0.6604)
		(drill 0.3302)
		(layers "F.Cu" "B.Cu")
		(net "SAS_SMART_R_TX")
	)
	(segment
		(start 152.697942 -90.609166)
		(end 153.231596 -90.609166)
		(width 0.127)
		(layer "F.Cu")
		(net "SAS_SMART_R_RX")
	)
	(segment
		(start 153.231596 -90.609166)
		(end 153.397712 -90.44305)
		(width 0.127)
		(layer "F.Cu")
		(net "SAS_SMART_R_RX")
	)
	(segment
		(start 153.67508 -91.481402)
		(end 153.98115 -91.175332)
		(width 0.127)
		(layer "F.Cu")
		(net "SAS_SMART_R_RX")
	)
	(segment
		(start 153.98115 -91.175332)
		(end 153.98115 -90.44305)
		(width 0.127)
		(layer "F.Cu")
		(net "SAS_SMART_R_RX")
	)
	(segment
		(start 153.67508 -91.90101)
		(end 153.67508 -91.481402)
		(width 0.127)
		(layer "F.Cu")
		(net "SAS_SMART_R_RX")
	)
	(segment
		(start 153.397712 -90.44305)
		(end 153.98115 -90.44305)
		(width 0.127)
		(layer "F.Cu")
		(net "SAS_SMART_R_RX")
	)
	(via
		(at 153.98115 -90.44305)
		(size 0.6604)
		(drill 0.3302)
		(layers "F.Cu" "B.Cu")
		(net "SAS_SMART_R_RX")
	)
	(segment
		(start 156.45892 -100.38588)
		(end 156.6164 -100.2284)
		(width 0.127)
		(layer "F.Cu")
		(net "SAS_R_SDBTX")
	)
	(segment
		(start 156.6164 -100.2284)
		(end 156.6164 -99.949)
		(width 0.127)
		(layer "F.Cu")
		(net "SAS_R_SDBTX")
	)
	(segment
		(start 156.6164 -99.949)
		(end 156.01188 -99.34448)
		(width 0.127)
		(layer "F.Cu")
		(net "SAS_R_SDBTX")
	)
	(segment
		(start 155.5496 -100.38588)
		(end 156.45892 -100.38588)
		(width 0.127)
		(layer "F.Cu")
		(net "SAS_R_SDBTX")
	)
	(segment
		(start 156.01188 -99.34448)
		(end 156.01188 -99.08667)
		(width 0.127)
		(layer "F.Cu")
		(net "SAS_R_SDBTX")
	)
	(via
		(at 156.6164 -100.2284)
		(size 0.6604)
		(drill 0.3302)
		(layers "F.Cu" "B.Cu")
		(net "SAS_R_SDBTX")
	)
	(segment
		(start 152.85847 -99.659948)
		(end 153.471626 -99.659948)
		(width 0.127)
		(layer "F.Cu")
		(net "SAS_R_SDBRX")
	)
	(segment
		(start 152.67686 -99.841558)
		(end 152.85847 -99.659948)
		(width 0.127)
		(layer "F.Cu")
		(net "SAS_R_SDBRX")
	)
	(segment
		(start 153.471626 -99.659948)
		(end 153.67508 -99.456494)
		(width 0.127)
		(layer "F.Cu")
		(net "SAS_R_SDBRX")
	)
	(segment
		(start 153.67508 -99.456494)
		(end 153.67508 -99.08667)
		(width 0.127)
		(layer "F.Cu")
		(net "SAS_R_SDBRX")
	)
	(segment
		(start 152.67686 -100.38588)
		(end 152.67686 -99.841558)
		(width 0.127)
		(layer "F.Cu")
		(net "SAS_R_SDBRX")
	)
	(segment
		(start 127.500126 -51.500024)
		(end 127.999998 -51.000152)
		(width 0.127)
		(layer "F.Cu")
		(net "RTRIM_AN")
	)
	(via
		(at 127.999998 -51.000152)
		(size 0.4572)
		(drill 0.2032)
		(layers "F.Cu" "B.Cu")
		(net "RTRIM_AN")
	)
	(via
		(at 128.467104 -50.467006)
		(size 0.6096)
		(drill 0.3048)
		(layers "F.Cu" "B.Cu")
		(net "RTRIM_AN")
	)
	(segment
		(start 127.858266 -49.4792)
		(end 128.467104 -50.088038)
		(width 0.127)
		(layer "B.Cu")
		(net "RTRIM_AN")
	)
	(segment
		(start 128.467104 -50.533046)
		(end 128.467104 -50.467006)
		(width 0.127)
		(layer "B.Cu")
		(net "RTRIM_AN")
	)
	(segment
		(start 127.999998 -51.000152)
		(end 128.467104 -50.533046)
		(width 0.127)
		(layer "B.Cu")
		(net "RTRIM_AN")
	)
	(segment
		(start 128.467104 -50.088038)
		(end 128.467104 -50.467006)
		(width 0.127)
		(layer "B.Cu")
		(net "RTRIM_AN")
	)
	(segment
		(start 127.4953 -49.4792)
		(end 127.858266 -49.4792)
		(width 0.127)
		(layer "B.Cu")
		(net "RTRIM_AN")
	)
	(segment
		(start 126.500128 -51.500024)
		(end 127 -51.000152)
		(width 0.127)
		(layer "F.Cu")
		(net "RTRIM_A")
	)
	(via
		(at 127 -51.000152)
		(size 0.4572)
		(drill 0.2032)
		(layers "F.Cu" "B.Cu")
		(net "RTRIM_A")
	)
	(via
		(at 126.194312 -50.57394)
		(size 0.6096)
		(drill 0.3048)
		(layers "F.Cu" "B.Cu")
		(net "RTRIM_A")
	)
	(segment
		(start 126.194312 -49.891188)
		(end 126.194312 -50.57394)
		(width 0.127)
		(layer "B.Cu")
		(net "RTRIM_A")
	)
	(segment
		(start 126.620524 -51.000152)
		(end 126.194312 -50.57394)
		(width 0.127)
		(layer "B.Cu")
		(net "RTRIM_A")
	)
	(segment
		(start 126.6063 -49.4792)
		(end 126.194312 -49.891188)
		(width 0.127)
		(layer "B.Cu")
		(net "RTRIM_A")
	)
	(segment
		(start 127 -51.000152)
		(end 126.620524 -51.000152)
		(width 0.127)
		(layer "B.Cu")
		(net "RTRIM_A")
	)
	(segment
		(start 164.199824 -39.59987)
		(end 164.599874 -39.99992)
		(width 0.127)
		(layer "F.Cu")
		(net "RTRIM#")
	)
	(via
		(at 164.599874 -39.99992)
		(size 0.508)
		(drill 0.254)
		(layers "F.Cu" "B.Cu")
		(net "RTRIM#")
	)
	(via
		(at 164.015166 -41.047162)
		(size 0.6096)
		(drill 0.3048)
		(layers "F.Cu" "B.Cu")
		(net "RTRIM#")
	)
	(segment
		(start 164.599874 -40.854376)
		(end 164.599874 -39.99992)
		(width 0.127)
		(layer "B.Cu")
		(net "RTRIM#")
	)
	(segment
		(start 164.407088 -41.047162)
		(end 164.599874 -40.854376)
		(width 0.127)
		(layer "B.Cu")
		(net "RTRIM#")
	)
	(segment
		(start 161.3281 -40.1701)
		(end 162.205162 -41.047162)
		(width 0.127)
		(layer "B.Cu")
		(net "RTRIM#")
	)
	(segment
		(start 162.205162 -41.047162)
		(end 164.015166 -41.047162)
		(width 0.127)
		(layer "B.Cu")
		(net "RTRIM#")
	)
	(segment
		(start 160.6042 -40.1701)
		(end 161.3281 -40.1701)
		(width 0.127)
		(layer "B.Cu")
		(net "RTRIM#")
	)
	(segment
		(start 164.015166 -41.047162)
		(end 164.407088 -41.047162)
		(width 0.127)
		(layer "B.Cu")
		(net "RTRIM#")
	)
	(segment
		(start 163.320476 -39.679372)
		(end 163.399978 -39.59987)
		(width 0.127)
		(layer "F.Cu")
		(net "RTRIM")
	)
	(segment
		(start 162.75685 -39.679372)
		(end 163.320476 -39.679372)
		(width 0.127)
		(layer "F.Cu")
		(net "RTRIM")
	)
	(via
		(at 162.75685 -39.679372)
		(size 0.508)
		(drill 0.254)
		(layers "F.Cu" "B.Cu")
		(net "RTRIM")
	)
	(via
		(at 161.70402 -39.2811)
		(size 0.6096)
		(drill 0.3048)
		(layers "F.Cu" "B.Cu")
		(net "RTRIM")
	)
	(segment
		(start 162.59048 -39.679372)
		(end 162.75685 -39.679372)
		(width 0.127)
		(layer "B.Cu")
		(net "RTRIM")
	)
	(segment
		(start 160.6042 -39.2811)
		(end 161.70402 -39.2811)
		(width 0.127)
		(layer "B.Cu")
		(net "RTRIM")
	)
	(segment
		(start 162.192208 -39.2811)
		(end 162.59048 -39.679372)
		(width 0.127)
		(layer "B.Cu")
		(net "RTRIM")
	)
	(segment
		(start 161.70402 -39.2811)
		(end 162.192208 -39.2811)
		(width 0.127)
		(layer "B.Cu")
		(net "RTRIM")
	)
	(segment
		(start 88.354916 -84.201)
		(end 88.975692 -84.821776)
		(width 0.127)
		(layer "F.Cu")
		(net "RESET_SENSE")
	)
	(segment
		(start 89.508584 -85.354668)
		(end 88.975692 -84.821776)
		(width 0.127)
		(layer "F.Cu")
		(net "RESET_SENSE")
	)
	(segment
		(start 89.508584 -85.6488)
		(end 89.508584 -85.354668)
		(width 0.127)
		(layer "F.Cu")
		(net "RESET_SENSE")
	)
	(segment
		(start 87.660734 -84.201)
		(end 88.354916 -84.201)
		(width 0.127)
		(layer "F.Cu")
		(net "RESET_SENSE")
	)
	(via
		(at 89.508584 -85.6488)
		(size 0.508)
		(drill 0.254)
		(layers "F.Cu" "B.Cu")
		(net "RESET_SENSE")
	)
	(via
		(at 88.975692 -84.821776)
		(size 0.6604)
		(drill 0.3302)
		(layers "F.Cu" "B.Cu")
		(net "RESET_SENSE")
	)
	(segment
		(start 89.508584 -85.6488)
		(end 89.508584 -85.158326)
		(width 0.127)
		(layer "B.Cu")
		(net "RESET_SENSE")
	)
	(segment
		(start 89.508584 -85.158326)
		(end 90.1192 -84.54771)
		(width 0.127)
		(layer "B.Cu")
		(net "RESET_SENSE")
	)
	(segment
		(start 90.1192 -84.54771)
		(end 90.1192 -83.947)
		(width 0.127)
		(layer "B.Cu")
		(net "RESET_SENSE")
	)
	(segment
		(start 88.590882 -81.208118)
		(end 88.6206 -81.1784)
		(width 0.127)
		(layer "F.Cu")
		(net "RESET_MR#")
	)
	(segment
		(start 88.6206 -80.518)
		(end 88.3285 -80.2259)
		(width 0.127)
		(layer "F.Cu")
		(net "RESET_MR#")
	)
	(segment
		(start 88.6206 -81.1784)
		(end 88.6206 -80.518)
		(width 0.127)
		(layer "F.Cu")
		(net "RESET_MR#")
	)
	(segment
		(start 87.665814 -81.208118)
		(end 88.590882 -81.208118)
		(width 0.127)
		(layer "F.Cu")
		(net "RESET_MR#")
	)
	(via
		(at 88.3285 -80.2259)
		(size 0.508)
		(drill 0.254)
		(layers "F.Cu" "B.Cu")
		(net "RESET_MR#")
	)
	(via
		(at 88.6206 -81.1784)
		(size 0.6604)
		(drill 0.3302)
		(layers "F.Cu" "B.Cu")
		(net "RESET_MR#")
	)
	(segment
		(start 89.1667 -80.552544)
		(end 89.1667 -81.2546)
		(width 0.127)
		(layer "B.Cu")
		(net "RESET_MR#")
	)
	(segment
		(start 88.840056 -80.2259)
		(end 89.1667 -80.552544)
		(width 0.127)
		(layer "B.Cu")
		(net "RESET_MR#")
	)
	(segment
		(start 88.3285 -80.2259)
		(end 88.840056 -80.2259)
		(width 0.127)
		(layer "B.Cu")
		(net "RESET_MR#")
	)
	(segment
		(start 89.0905 -88.265)
		(end 89.0905 -87.122)
		(width 0.127)
		(layer "F.Cu")
		(net "RESET_CT")
	)
	(segment
		(start 89.0905 -86.208616)
		(end 88.543384 -85.6615)
		(width 0.127)
		(layer "F.Cu")
		(net "RESET_CT")
	)
	(segment
		(start 89.0905 -87.122)
		(end 89.0905 -86.208616)
		(width 0.127)
		(layer "F.Cu")
		(net "RESET_CT")
	)
	(via
		(at 88.543384 -85.6615)
		(size 0.508)
		(drill 0.254)
		(layers "F.Cu" "B.Cu")
		(net "RESET_CT")
	)
	(via
		(at 89.0905 -87.122)
		(size 0.6604)
		(drill 0.3302)
		(layers "F.Cu" "B.Cu")
		(net "RESET_CT")
	)
	(segment
		(start 88.543384 -85.6615)
		(end 88.543384 -85.27034)
		(width 0.127)
		(layer "B.Cu")
		(net "RESET_CT")
	)
	(segment
		(start 89.1667 -84.647024)
		(end 89.1667 -83.947)
		(width 0.127)
		(layer "B.Cu")
		(net "RESET_CT")
	)
	(segment
		(start 88.543384 -85.27034)
		(end 89.1667 -84.647024)
		(width 0.127)
		(layer "B.Cu")
		(net "RESET_CT")
	)
	(segment
		(start 156.591 -43.826684)
		(end 157.362652 -43.055032)
		(width 0.127)
		(layer "F.Cu")
		(net "REF_CLK")
	)
	(segment
		(start 158.385764 -45.592746)
		(end 157.51175 -45.592746)
		(width 0.127)
		(layer "F.Cu")
		(net "REF_CLK")
	)
	(segment
		(start 156.591 -44.671996)
		(end 156.591 -43.826684)
		(width 0.127)
		(layer "F.Cu")
		(net "REF_CLK")
	)
	(segment
		(start 157.9245 -42.808144)
		(end 157.9245 -42.291)
		(width 0.127)
		(layer "F.Cu")
		(net "REF_CLK")
	)
	(segment
		(start 157.51175 -45.592746)
		(end 156.591 -44.671996)
		(width 0.127)
		(layer "F.Cu")
		(net "REF_CLK")
	)
	(segment
		(start 158.0515 -42.164)
		(end 158.0515 -41.275)
		(width 0.127)
		(layer "F.Cu")
		(net "REF_CLK")
	)
	(segment
		(start 157.677612 -43.055032)
		(end 157.9245 -42.808144)
		(width 0.127)
		(layer "F.Cu")
		(net "REF_CLK")
	)
	(segment
		(start 157.362652 -43.055032)
		(end 157.677612 -43.055032)
		(width 0.127)
		(layer "F.Cu")
		(net "REF_CLK")
	)
	(segment
		(start 157.9245 -42.291)
		(end 158.0515 -42.164)
		(width 0.127)
		(layer "F.Cu")
		(net "REF_CLK")
	)
	(segment
		(start 167.39997 -40.39997)
		(end 167.80002 -40.80002)
		(width 0.127)
		(layer "F.Cu")
		(net "POWERLOSS#")
	)
	(via
		(at 168.057576 -41.782492)
		(size 0.6096)
		(drill 0.3048)
		(layers "F.Cu" "B.Cu")
		(net "POWERLOSS#")
	)
	(via
		(at 167.80002 -40.80002)
		(size 0.508)
		(drill 0.254)
		(layers "F.Cu" "B.Cu")
		(net "POWERLOSS#")
	)
	(segment
		(start 168.057576 -41.782492)
		(end 168.057576 -41.057576)
		(width 0.127)
		(layer "B.Cu")
		(net "POWERLOSS#")
	)
	(segment
		(start 168.057576 -41.782492)
		(end 168.057576 -42.003726)
		(width 0.127)
		(layer "B.Cu")
		(net "POWERLOSS#")
	)
	(segment
		(start 168.057576 -42.003726)
		(end 167.661336 -42.399966)
		(width 0.127)
		(layer "B.Cu")
		(net "POWERLOSS#")
	)
	(segment
		(start 167.661336 -42.399966)
		(end 167.071802 -42.399966)
		(width 0.127)
		(layer "B.Cu")
		(net "POWERLOSS#")
	)
	(segment
		(start 168.057576 -41.057576)
		(end 167.80002 -40.80002)
		(width 0.127)
		(layer "B.Cu")
		(net "POWERLOSS#")
	)
	(segment
		(start 107.499912 -65.499996)
		(end 107.00004 -65.000124)
		(width 0.4572)
		(layer "F.Cu")
		(net "PLLDDR_VDDA18")
	)
	(via
		(at 97.453958 -64.017398)
		(size 0.6096)
		(drill 0.3048)
		(layers "F.Cu" "B.Cu")
		(net "PLLDDR_VDDA18")
	)
	(via
		(at 107.00004 -65.000124)
		(size 0.4572)
		(drill 0.2032)
		(layers "F.Cu" "B.Cu")
		(net "PLLDDR_VDDA18")
	)
	(segment
		(start 90.974926 -67.390772)
		(end 90.355674 -67.390772)
		(width 0.508)
		(layer "B.Cu")
		(net "PLLDDR_VDDA18")
	)
	(segment
		(start 106.535982 -64.473582)
		(end 106.5784 -64.516)
		(width 0.254)
		(layer "B.Cu")
		(net "PLLDDR_VDDA18")
	)
	(segment
		(start 107.00004 -65.000124)
		(end 107.00004 -64.93764)
		(width 0.254)
		(layer "B.Cu")
		(net "PLLDDR_VDDA18")
	)
	(segment
		(start 92.510864 -66.863214)
		(end 92.168472 -66.863214)
		(width 0.508)
		(layer "B.Cu")
		(net "PLLDDR_VDDA18")
	)
	(segment
		(start 91.261438 -67.390772)
		(end 91.788996 -66.863214)
		(width 0.508)
		(layer "B.Cu")
		(net "PLLDDR_VDDA18")
	)
	(segment
		(start 98.443288 -63.46444)
		(end 101.216206 -63.46444)
		(width 0.254)
		(layer "B.Cu")
		(net "PLLDDR_VDDA18")
	)
	(segment
		(start 98.006916 -63.46444)
		(end 98.443288 -63.46444)
		(width 0.508)
		(layer "B.Cu")
		(net "PLLDDR_VDDA18")
	)
	(segment
		(start 107.00004 -64.93764)
		(end 106.5784 -64.516)
		(width 0.254)
		(layer "B.Cu")
		(net "PLLDDR_VDDA18")
	)
	(segment
		(start 92.815664 -67.168014)
		(end 92.510864 -66.863214)
		(width 0.508)
		(layer "B.Cu")
		(net "PLLDDR_VDDA18")
	)
	(segment
		(start 106.535982 -62.735714)
		(end 106.535982 -64.473582)
		(width 0.254)
		(layer "B.Cu")
		(net "PLLDDR_VDDA18")
	)
	(segment
		(start 97.453958 -64.017398)
		(end 98.006916 -63.46444)
		(width 0.508)
		(layer "B.Cu")
		(net "PLLDDR_VDDA18")
	)
	(segment
		(start 97.453958 -64.017398)
		(end 96.325182 -65.146174)
		(width 0.508)
		(layer "B.Cu")
		(net "PLLDDR_VDDA18")
	)
	(segment
		(start 104.504744 -62.5094)
		(end 106.309668 -62.5094)
		(width 0.254)
		(layer "B.Cu")
		(net "PLLDDR_VDDA18")
	)
	(segment
		(start 90.355674 -67.390772)
		(end 89.472516 -66.507614)
		(width 0.508)
		(layer "B.Cu")
		(net "PLLDDR_VDDA18")
	)
	(segment
		(start 101.216206 -63.46444)
		(end 101.536754 -63.143892)
		(width 0.254)
		(layer "B.Cu")
		(net "PLLDDR_VDDA18")
	)
	(segment
		(start 96.325182 -65.146174)
		(end 96.325182 -66.80835)
		(width 0.508)
		(layer "B.Cu")
		(net "PLLDDR_VDDA18")
	)
	(segment
		(start 96.325182 -66.80835)
		(end 95.965518 -67.168014)
		(width 0.508)
		(layer "B.Cu")
		(net "PLLDDR_VDDA18")
	)
	(segment
		(start 93.311472 -67.168014)
		(end 92.815664 -67.168014)
		(width 0.508)
		(layer "B.Cu")
		(net "PLLDDR_VDDA18")
	)
	(segment
		(start 101.536754 -63.143892)
		(end 101.536754 -62.793626)
		(width 0.254)
		(layer "B.Cu")
		(net "PLLDDR_VDDA18")
	)
	(segment
		(start 95.965518 -67.168014)
		(end 93.311472 -67.168014)
		(width 0.508)
		(layer "B.Cu")
		(net "PLLDDR_VDDA18")
	)
	(segment
		(start 101.82098 -62.5094)
		(end 104.504744 -62.5094)
		(width 0.254)
		(layer "B.Cu")
		(net "PLLDDR_VDDA18")
	)
	(segment
		(start 101.536754 -62.793626)
		(end 101.82098 -62.5094)
		(width 0.254)
		(layer "B.Cu")
		(net "PLLDDR_VDDA18")
	)
	(segment
		(start 106.309668 -62.5094)
		(end 106.535982 -62.735714)
		(width 0.254)
		(layer "B.Cu")
		(net "PLLDDR_VDDA18")
	)
	(segment
		(start 91.788996 -66.863214)
		(end 92.168472 -66.863214)
		(width 0.508)
		(layer "B.Cu")
		(net "PLLDDR_VDDA18")
	)
	(segment
		(start 90.974926 -67.390772)
		(end 91.261438 -67.390772)
		(width 0.508)
		(layer "B.Cu")
		(net "PLLDDR_VDDA18")
	)
	(segment
		(start 180.999892 -35.599878)
		(end 181.399942 -35.999928)
		(width 0.254)
		(layer "F.Cu")
		(net "PLL_VDD")
	)
	(via
		(at 181.399942 -35.999928)
		(size 0.508)
		(drill 0.254)
		(layers "F.Cu" "B.Cu")
		(net "PLL_VDD")
	)
	(via
		(at 195.2498 -32.9692)
		(size 0.508)
		(drill 0.254)
		(layers "F.Cu" "B.Cu")
		(net "PLL_VDD")
	)
	(via
		(at 196.3674 -33.528)
		(size 0.6096)
		(drill 0.3048)
		(layers "F.Cu" "B.Cu")
		(net "PLL_VDD")
	)
	(segment
		(start 184.05221 -35.390074)
		(end 181.947058 -35.390074)
		(width 0.508)
		(layer "In2.Cu")
		(net "PLL_VDD")
	)
	(segment
		(start 195.2498 -32.9692)
		(end 194.8561 -33.3629)
		(width 0.508)
		(layer "In2.Cu")
		(net "PLL_VDD")
	)
	(segment
		(start 181.947058 -35.390074)
		(end 181.399942 -35.93719)
		(width 0.508)
		(layer "In2.Cu")
		(net "PLL_VDD")
	)
	(segment
		(start 185.147204 -38.209474)
		(end 184.409334 -37.471604)
		(width 0.508)
		(layer "In2.Cu")
		(net "PLL_VDD")
	)
	(segment
		(start 184.409334 -35.747198)
		(end 184.05221 -35.390074)
		(width 0.508)
		(layer "In2.Cu")
		(net "PLL_VDD")
	)
	(segment
		(start 193.720974 -33.3629)
		(end 190.203074 -36.8808)
		(width 0.508)
		(layer "In2.Cu")
		(net "PLL_VDD")
	)
	(segment
		(start 190.203074 -36.8808)
		(end 188.595 -36.8808)
		(width 0.508)
		(layer "In2.Cu")
		(net "PLL_VDD")
	)
	(segment
		(start 188.595 -36.8808)
		(end 187.266326 -38.209474)
		(width 0.508)
		(layer "In2.Cu")
		(net "PLL_VDD")
	)
	(segment
		(start 187.266326 -38.209474)
		(end 185.147204 -38.209474)
		(width 0.508)
		(layer "In2.Cu")
		(net "PLL_VDD")
	)
	(segment
		(start 194.8561 -33.3629)
		(end 193.720974 -33.3629)
		(width 0.508)
		(layer "In2.Cu")
		(net "PLL_VDD")
	)
	(segment
		(start 184.409334 -37.471604)
		(end 184.409334 -35.747198)
		(width 0.508)
		(layer "In2.Cu")
		(net "PLL_VDD")
	)
	(segment
		(start 181.399942 -35.93719)
		(end 181.399942 -35.999928)
		(width 0.508)
		(layer "In2.Cu")
		(net "PLL_VDD")
	)
	(segment
		(start 125.061218 -84.6455)
		(end 125.061218 -85.44306)
		(width 0.127)
		(layer "F.Cu")
		(net "PHY_CLK")
	)
	(segment
		(start 123.106434 -82.339434)
		(end 123.106434 -82.690716)
		(width 0.127)
		(layer "F.Cu")
		(net "PHY_CLK")
	)
	(segment
		(start 125.118876 -85.825076)
		(end 125.495558 -86.201758)
		(width 0.127)
		(layer "F.Cu")
		(net "PHY_CLK")
	)
	(segment
		(start 125.495558 -87.791798)
		(end 125.3998 -87.887556)
		(width 0.127)
		(layer "F.Cu")
		(net "PHY_CLK")
	)
	(segment
		(start 125.495558 -86.201758)
		(end 125.495558 -87.791798)
		(width 0.127)
		(layer "F.Cu")
		(net "PHY_CLK")
	)
	(segment
		(start 125.118876 -85.500718)
		(end 125.118876 -85.825076)
		(width 0.127)
		(layer "F.Cu")
		(net "PHY_CLK")
	)
	(segment
		(start 123.106434 -82.690716)
		(end 125.061218 -84.6455)
		(width 0.127)
		(layer "F.Cu")
		(net "PHY_CLK")
	)
	(segment
		(start 125.061218 -85.44306)
		(end 125.118876 -85.500718)
		(width 0.127)
		(layer "F.Cu")
		(net "PHY_CLK")
	)
	(segment
		(start 125.3998 -88.1888)
		(end 125.2728 -88.3158)
		(width 0.127)
		(layer "F.Cu")
		(net "PHY_CLK")
	)
	(segment
		(start 122.500136 -81.500218)
		(end 122.500136 -81.733136)
		(width 0.127)
		(layer "F.Cu")
		(net "PHY_CLK")
	)
	(segment
		(start 125.3998 -87.887556)
		(end 125.3998 -88.1888)
		(width 0.127)
		(layer "F.Cu")
		(net "PHY_CLK")
	)
	(segment
		(start 122.500136 -81.733136)
		(end 123.106434 -82.339434)
		(width 0.127)
		(layer "F.Cu")
		(net "PHY_CLK")
	)
	(segment
		(start 169.799762 -33.199832)
		(end 169.800016 -33.199832)
		(width 0.3048)
		(layer "F.Cu")
		(net "PCE_AVDD")
	)
	(segment
		(start 169.800016 -27.786584)
		(end 169.800016 -28.399994)
		(width 0.3048)
		(layer "F.Cu")
		(net "PCE_AVDD")
	)
	(segment
		(start 174.599854 -28.22829)
		(end 174.599854 -28.399994)
		(width 0.3048)
		(layer "F.Cu")
		(net "PCE_AVDD")
	)
	(segment
		(start 172.260006 -27.631136)
		(end 172.260006 -27.739594)
		(width 0.3048)
		(layer "F.Cu")
		(net "PCE_AVDD")
	)
	(segment
		(start 177.689002 -27.63901)
		(end 176.9999 -28.328112)
		(width 0.3048)
		(layer "F.Cu")
		(net "PCE_AVDD")
	)
	(segment
		(start 167.399716 -28.399994)
		(end 167.39997 -28.399994)
		(width 0.3048)
		(layer "F.Cu")
		(net "PCE_AVDD")
	)
	(segment
		(start 166.99992 -28.79979)
		(end 167.399716 -28.399994)
		(width 0.3048)
		(layer "F.Cu")
		(net "PCE_AVDD")
	)
	(segment
		(start 171.399962 -33.998916)
		(end 171.799504 -33.599374)
		(width 0.3556)
		(layer "F.Cu")
		(net "PCE_AVDD")
	)
	(segment
		(start 172.999908 -33.199832)
		(end 173.39945 -33.599374)
		(width 0.3556)
		(layer "F.Cu")
		(net "PCE_AVDD")
	)
	(segment
		(start 169.399966 -32.800036)
		(end 169.799762 -33.199832)
		(width 0.3048)
		(layer "F.Cu")
		(net "PCE_AVDD")
	)
	(segment
		(start 172.260006 -27.739594)
		(end 172.199808 -27.799792)
		(width 0.3048)
		(layer "F.Cu")
		(net "PCE_AVDD")
	)
	(segment
		(start 172.199808 -27.799792)
		(end 172.199808 -28.399994)
		(width 0.3048)
		(layer "F.Cu")
		(net "PCE_AVDD")
	)
	(segment
		(start 171.399962 -33.199832)
		(end 171.799504 -33.599374)
		(width 0.3556)
		(layer "F.Cu")
		(net "PCE_AVDD")
	)
	(segment
		(start 174.599854 -33.199832)
		(end 174.999396 -33.599374)
		(width 0.3556)
		(layer "F.Cu")
		(net "PCE_AVDD")
	)
	(segment
		(start 175.018446 -27.809698)
		(end 174.599854 -28.22829)
		(width 0.3048)
		(layer "F.Cu")
		(net "PCE_AVDD")
	)
	(segment
		(start 176.9999 -28.328112)
		(end 176.9999 -28.399994)
		(width 0.3048)
		(layer "F.Cu")
		(net "PCE_AVDD")
	)
	(segment
		(start 171.399962 -33.999932)
		(end 171.399962 -33.998916)
		(width 0.3556)
		(layer "F.Cu")
		(net "PCE_AVDD")
	)
	(segment
		(start 170.053 -27.5336)
		(end 169.800016 -27.786584)
		(width 0.3048)
		(layer "F.Cu")
		(net "PCE_AVDD")
	)
	(via
		(at 171.799504 -33.599374)
		(size 0.508)
		(drill 0.254)
		(layers "F.Cu" "B.Cu")
		(net "PCE_AVDD")
	)
	(via
		(at 171.3738 -80.2386)
		(size 0.7112)
		(drill 0.4064)
		(layers "F.Cu" "B.Cu")
		(net "PCE_AVDD")
	)
	(via
		(at 173.39945 -33.599374)
		(size 0.4572)
		(drill 0.2032)
		(layers "F.Cu" "B.Cu")
		(net "PCE_AVDD")
	)
	(via
		(at 172.593 -80.2386)
		(size 0.7112)
		(drill 0.4064)
		(layers "F.Cu" "B.Cu")
		(net "PCE_AVDD")
	)
	(via
		(at 171.3738 -77.8002)
		(size 0.7112)
		(drill 0.4064)
		(layers "F.Cu" "B.Cu")
		(net "PCE_AVDD")
	)
	(via
		(at 172.593 -79.0194)
		(size 0.7112)
		(drill 0.4064)
		(layers "F.Cu" "B.Cu")
		(net "PCE_AVDD")
	)
	(via
		(at 171.3738 -79.0194)
		(size 0.7112)
		(drill 0.4064)
		(layers "F.Cu" "B.Cu")
		(net "PCE_AVDD")
	)
	(via
		(at 169.399966 -32.800036)
		(size 0.508)
		(drill 0.254)
		(layers "F.Cu" "B.Cu")
		(net "PCE_AVDD")
	)
	(via
		(at 172.260006 -27.631136)
		(size 0.508)
		(drill 0.254)
		(layers "F.Cu" "B.Cu")
		(net "PCE_AVDD")
	)
	(via
		(at 172.593 -77.8002)
		(size 0.7112)
		(drill 0.4064)
		(layers "F.Cu" "B.Cu")
		(net "PCE_AVDD")
	)
	(via
		(at 177.689002 -27.63901)
		(size 0.508)
		(drill 0.254)
		(layers "F.Cu" "B.Cu")
		(net "PCE_AVDD")
	)
	(via
		(at 170.053 -27.5336)
		(size 0.508)
		(drill 0.254)
		(layers "F.Cu" "B.Cu")
		(net "PCE_AVDD")
	)
	(via
		(at 174.999396 -33.599374)
		(size 0.4572)
		(drill 0.2032)
		(layers "F.Cu" "B.Cu")
		(net "PCE_AVDD")
	)
	(via
		(at 166.99992 -28.79979)
		(size 0.508)
		(drill 0.254)
		(layers "F.Cu" "B.Cu")
		(net "PCE_AVDD")
	)
	(via
		(at 173.58106 -76.91628)
		(size 0.6604)
		(drill 0.3302)
		(layers "F.Cu" "B.Cu")
		(net "PCE_AVDD")
	)
	(via
		(at 175.018446 -27.809698)
		(size 0.508)
		(drill 0.254)
		(layers "F.Cu" "B.Cu")
		(net "PCE_AVDD")
	)
	(segment
		(start 170.204638 -32.785304)
		(end 169.414698 -32.785304)
		(width 0.3048)
		(layer "B.Cu")
		(net "PCE_AVDD")
	)
	(segment
		(start 166.921688 -28.79979)
		(end 166.99992 -28.79979)
		(width 0.3048)
		(layer "B.Cu")
		(net "PCE_AVDD")
	)
	(segment
		(start 166.391082 -28.269184)
		(end 166.921688 -28.79979)
		(width 0.3048)
		(layer "B.Cu")
		(net "PCE_AVDD")
	)
	(segment
		(start 165.476682 -27.684984)
		(end 165.476682 -28.269184)
		(width 0.3048)
		(layer "B.Cu")
		(net "PCE_AVDD")
	)
	(segment
		(start 172.08627 -27.804872)
		(end 172.260006 -27.631136)
		(width 0.3048)
		(layer "B.Cu")
		(net "PCE_AVDD")
	)
	(segment
		(start 177.60823 -27.719782)
		(end 177.689002 -27.63901)
		(width 0.3048)
		(layer "B.Cu")
		(net "PCE_AVDD")
	)
	(segment
		(start 172.08627 -28.457398)
		(end 172.08627 -27.804872)
		(width 0.3048)
		(layer "B.Cu")
		(net "PCE_AVDD")
	)
	(segment
		(start 169.414698 -32.785304)
		(end 169.399966 -32.800036)
		(width 0.3048)
		(layer "B.Cu")
		(net "PCE_AVDD")
	)
	(segment
		(start 165.476682 -28.269184)
		(end 166.391082 -28.269184)
		(width 0.3048)
		(layer "B.Cu")
		(net "PCE_AVDD")
	)
	(segment
		(start 177.60823 -28.36545)
		(end 177.60823 -27.719782)
		(width 0.3048)
		(layer "B.Cu")
		(net "PCE_AVDD")
	)
	(via
		(at 199.4027 -20.23618)
		(size 0.6096)
		(drill 0.3048)
		(layers "F.Cu" "B.Cu")
		(net "P3V3_STBY_R")
	)
	(segment
		(start 199.4027 -20.07108)
		(end 199.4027 -20.23618)
		(width 0.127)
		(layer "B.Cu")
		(net "P3V3_STBY_R")
	)
	(segment
		(start 199.4027 -20.23618)
		(end 199.4027 -21.3233)
		(width 0.127)
		(layer "B.Cu")
		(net "P3V3_STBY_R")
	)
	(segment
		(start 200.533 -20.828)
		(end 199.9615 -21.3995)
		(width 0.127)
		(layer "B.Cu")
		(net "P3V3_STBY_R")
	)
	(segment
		(start 199.9615 -21.3995)
		(end 199.4789 -21.3995)
		(width 0.127)
		(layer "B.Cu")
		(net "P3V3_STBY_R")
	)
	(segment
		(start 200.533 -20.32)
		(end 200.533 -20.828)
		(width 0.127)
		(layer "B.Cu")
		(net "P3V3_STBY_R")
	)
	(segment
		(start 199.4027 -21.3233)
		(end 199.4789 -21.3995)
		(width 0.127)
		(layer "B.Cu")
		(net "P3V3_STBY_R")
	)
	(segment
		(start 201.1045 -19.939)
		(end 200.914 -19.939)
		(width 0.127)
		(layer "B.Cu")
		(net "P3V3_STBY_R")
	)
	(segment
		(start 198.08825 -19.8755)
		(end 199.20712 -19.8755)
		(width 0.127)
		(layer "B.Cu")
		(net "P3V3_STBY_R")
	)
	(segment
		(start 200.914 -19.939)
		(end 200.533 -20.32)
		(width 0.127)
		(layer "B.Cu")
		(net "P3V3_STBY_R")
	)
	(segment
		(start 199.20712 -19.8755)
		(end 199.4027 -20.07108)
		(width 0.127)
		(layer "B.Cu")
		(net "P3V3_STBY_R")
	)
	(segment
		(start 151.7015 -87.2363)
		(end 151.7015 -86.9696)
		(width 0.127)
		(layer "F.Cu")
		(net "P3V3_SENSE")
	)
	(segment
		(start 151.7015 -85.8266)
		(end 152.2984 -85.8266)
		(width 0.127)
		(layer "F.Cu")
		(net "P3V3_SENSE")
	)
	(segment
		(start 152.2984 -85.8266)
		(end 152.850088 -85.274912)
		(width 0.127)
		(layer "F.Cu")
		(net "P3V3_SENSE")
	)
	(segment
		(start 150.8125 -88.1253)
		(end 151.7015 -87.2363)
		(width 0.127)
		(layer "F.Cu")
		(net "P3V3_SENSE")
	)
	(segment
		(start 152.850088 -85.274912)
		(end 153.67508 -85.274912)
		(width 0.127)
		(layer "F.Cu")
		(net "P3V3_SENSE")
	)
	(segment
		(start 151.7015 -85.8266)
		(end 151.6888 -85.8393)
		(width 0.127)
		(layer "F.Cu")
		(net "P3V3_SENSE")
	)
	(segment
		(start 151.6888 -85.8393)
		(end 151.6888 -86.9569)
		(width 0.127)
		(layer "F.Cu")
		(net "P3V3_SENSE")
	)
	(segment
		(start 151.6888 -86.9569)
		(end 151.7015 -86.9696)
		(width 0.127)
		(layer "F.Cu")
		(net "P3V3_SENSE")
	)
	(via
		(at 151.7015 -86.9696)
		(size 0.6604)
		(drill 0.3302)
		(layers "F.Cu" "B.Cu")
		(net "P3V3_SENSE")
	)
	(segment
		(start 61.4045 -23.5585)
		(end 61.4045 -24.13)
		(width 0.381)
		(layer "F.Cu")
		(net "P3V3")
	)
	(segment
		(start 20.6502 -94.1197)
		(end 20.6502 -94.996)
		(width 0.508)
		(layer "F.Cu")
		(net "P3V3")
	)
	(segment
		(start 159.004 -85.775292)
		(end 157.81528 -85.775292)
		(width 0.3048)
		(layer "F.Cu")
		(net "P3V3")
	)
	(segment
		(start 159.054292 -85.725)
		(end 159.004 -85.775292)
		(width 0.3048)
		(layer "F.Cu")
		(net "P3V3")
	)
	(segment
		(start 26.00833 -94.067122)
		(end 26.00833 -94.943422)
		(width 0.508)
		(layer "F.Cu")
		(net "P3V3")
	)
	(segment
		(start 60.672218 -16.966946)
		(end 60.672218 -16.1671)
		(width 0.508)
		(layer "F.Cu")
		(net "P3V3")
	)
	(segment
		(start 191.060832 -81.707736)
		(end 189.73038 -80.377284)
		(width 0.508)
		(layer "F.Cu")
		(net "P3V3")
	)
	(segment
		(start 6.8453 -71.9328)
		(end 5.8674 -71.9328)
		(width 0.508)
		(layer "F.Cu")
		(net "P3V3")
	)
	(segment
		(start 76.970128 -78.290928)
		(end 81.9912 -83.312)
		(width 0.508)
		(layer "F.Cu")
		(net "P3V3")
	)
	(segment
		(start 24.96693 -94.067122)
		(end 24.96693 -94.943422)
		(width 0.508)
		(layer "F.Cu")
		(net "P3V3")
	)
	(segment
		(start 15.4559 -99.3267)
		(end 16.15186 -99.3267)
		(width 0.508)
		(layer "F.Cu")
		(net "P3V3")
	)
	(segment
		(start 80.677004 -70.821804)
		(end 80.6704 -70.8152)
		(width 0.2032)
		(layer "F.Cu")
		(net "P3V3")
	)
	(segment
		(start 159.8295 -88.6206)
		(end 158.9532 -88.6206)
		(width 0.508)
		(layer "F.Cu")
		(net "P3V3")
	)
	(segment
		(start 60.6806 -72.2503)
		(end 61.0743 -71.8566)
		(width 0.508)
		(layer "F.Cu")
		(net "P3V3")
	)
	(segment
		(start 55.7276 -72.1233)
		(end 55.7276 -70.9676)
		(width 0.508)
		(layer "F.Cu")
		(net "P3V3")
	)
	(segment
		(start 12.8778 -95.245682)
		(end 12.8778 -96.071182)
		(width 0.508)
		(layer "F.Cu")
		(net "P3V3")
	)
	(segment
		(start 193.633598 -71.161656)
		(end 191.479932 -71.161656)
		(width 0.3048)
		(layer "F.Cu")
		(net "P3V3")
	)
	(segment
		(start 157.46476 -99.04476)
		(end 157.00629 -98.58629)
		(width 0.3048)
		(layer "F.Cu")
		(net "P3V3")
	)
	(segment
		(start 180.3908 -111.24692)
		(end 180.3908 -112.0648)
		(width 0.508)
		(layer "F.Cu")
		(net "P3V3")
	)
	(segment
		(start 16.15186 -99.3267)
		(end 16.60525 -99.78009)
		(width 0.508)
		(layer "F.Cu")
		(net "P3V3")
	)
	(segment
		(start 159.8295 -76.921614)
		(end 159.8295 -75.969114)
		(width 0.508)
		(layer "F.Cu")
		(net "P3V3")
	)
	(segment
		(start 147.57908 -119.00662)
		(end 147.57908 -119.86006)
		(width 0.508)
		(layer "F.Cu")
		(net "P3V3")
	)
	(segment
		(start 62.844172 -71.864728)
		(end 62.4332 -72.2757)
		(width 0.508)
		(layer "F.Cu")
		(net "P3V3")
	)
	(segment
		(start 15.3416 -94.0181)
		(end 15.3416 -94.8944)
		(width 0.508)
		(layer "F.Cu")
		(net "P3V3")
	)
	(segment
		(start 12.6238 -102.108)
		(end 12.6238 -101.1301)
		(width 0.508)
		(layer "F.Cu")
		(net "P3V3")
	)
	(segment
		(start 81.9531 -70.821804)
		(end 80.677004 -70.821804)
		(width 0.2032)
		(layer "F.Cu")
		(net "P3V3")
	)
	(segment
		(start 152.233122 -88.656922)
		(end 153.070306 -88.656922)
		(width 0.508)
		(layer "F.Cu")
		(net "P3V3")
	)
	(segment
		(start 6.9088 -76.6445)
		(end 6.096 -76.6445)
		(width 0.508)
		(layer "F.Cu")
		(net "P3V3")
	)
	(segment
		(start 184.20588 -107.67822)
		(end 183.23052 -107.67822)
		(width 0.508)
		(layer "F.Cu")
		(net "P3V3")
	)
	(segment
		(start 190.4746 -74.4728)
		(end 185.876438 -74.4728)
		(width 1.016)
		(layer "F.Cu")
		(net "P3V3")
	)
	(segment
		(start 151.7015 -88.1253)
		(end 152.233122 -88.656922)
		(width 0.508)
		(layer "F.Cu")
		(net "P3V3")
	)
	(segment
		(start 18.8341 -74.0918)
		(end 18.7071 -74.2188)
		(width 0.508)
		(layer "F.Cu")
		(net "P3V3")
	)
	(segment
		(start 51.9176 -72.5424)
		(end 51.9176 -73.3298)
		(width 0.508)
		(layer "F.Cu")
		(net "P3V3")
	)
	(segment
		(start 194.504056 -83.018376)
		(end 192.492376 -83.018376)
		(width 0.508)
		(layer "F.Cu")
		(net "P3V3")
	)
	(segment
		(start 13.9192 -94.0181)
		(end 13.9192 -94.8944)
		(width 0.508)
		(layer "F.Cu")
		(net "P3V3")
	)
	(segment
		(start 66.04 -71.468234)
		(end 65.945766 -71.374)
		(width 0.508)
		(layer "F.Cu")
		(net "P3V3")
	)
	(segment
		(start 80.7847 -74.079608)
		(end 81.163922 -73.700386)
		(width 0.508)
		(layer "F.Cu")
		(net "P3V3")
	)
	(segment
		(start 90.5637 -84.836)
		(end 90.5637 -85.6488)
		(width 0.508)
		(layer "F.Cu")
		(net "P3V3")
	)
	(segment
		(start 159.8295 -77.848714)
		(end 159.8295 -76.947014)
		(width 0.508)
		(layer "F.Cu")
		(net "P3V3")
	)
	(segment
		(start 23.79853 -95.294704)
		(end 23.79853 -96.120204)
		(width 0.508)
		(layer "F.Cu")
		(net "P3V3")
	)
	(segment
		(start 63.622428 -71.864728)
		(end 63.2206 -71.864728)
		(width 0.508)
		(layer "F.Cu")
		(net "P3V3")
	)
	(segment
		(start 50.8635 -75.8952)
		(end 50.0634 -75.8952)
		(width 0.508)
		(layer "F.Cu")
		(net "P3V3")
	)
	(segment
		(start 191.479932 -73.859644)
		(end 191.479932 -71.161656)
		(width 0.508)
		(layer "F.Cu")
		(net "P3V3")
	)
	(segment
		(start 63.2206 -71.864728)
		(end 62.844172 -71.864728)
		(width 0.508)
		(layer "F.Cu")
		(net "P3V3")
	)
	(segment
		(start 5.9436 -78.613)
		(end 6.9215 -78.613)
		(width 0.508)
		(layer "F.Cu")
		(net "P3V3")
	)
	(segment
		(start 40.6527 -28.8036)
		(end 38.8112 -28.8036)
		(width 0.508)
		(layer "F.Cu")
		(net "P3V3")
	)
	(segment
		(start 76.970128 -73.6346)
		(end 76.970128 -78.290928)
		(width 0.508)
		(layer "F.Cu")
		(net "P3V3")
	)
	(segment
		(start 87.660734 -83.312)
		(end 89.0397 -83.312)
		(width 0.508)
		(layer "F.Cu")
		(net "P3V3")
	)
	(segment
		(start 159.054292 -75.969114)
		(end 159.004 -76.019406)
		(width 0.3048)
		(layer "F.Cu")
		(net "P3V3")
	)
	(segment
		(start 82.709766 -112.65154)
		(end 83.549744 -112.65154)
		(width 0.508)
		(layer "F.Cu")
		(net "P3V3")
	)
	(segment
		(start 172.014388 -68.728844)
		(end 171.484544 -68.199)
		(width 1.016)
		(layer "F.Cu")
		(net "P3V3")
	)
	(segment
		(start 11.0109 -101.23424)
		(end 12.51966 -101.23424)
		(width 0.4064)
		(layer "F.Cu")
		(net "P3V3")
	)
	(segment
		(start 165.497256 -13.370052)
		(end 165.090094 -12.96289)
		(width 0.2032)
		(layer "F.Cu")
		(net "P3V3")
	)
	(segment
		(start 64.008 -72.2503)
		(end 63.622428 -71.864728)
		(width 0.508)
		(layer "F.Cu")
		(net "P3V3")
	)
	(segment
		(start 204.5462 -67.8815)
		(end 204.5462 -67.01536)
		(width 0.508)
		(layer "F.Cu")
		(net "P3V3")
	)
	(segment
		(start 191.549782 -81.707736)
		(end 191.060832 -81.707736)
		(width 0.508)
		(layer "F.Cu")
		(net "P3V3")
	)
	(segment
		(start 185.876438 -74.4728)
		(end 180.132482 -68.728844)
		(width 1.016)
		(layer "F.Cu")
		(net "P3V3")
	)
	(segment
		(start 204.5462 -67.01536)
		(end 204.534516 -67.027044)
		(width 0.508)
		(layer "F.Cu")
		(net "P3V3")
	)
	(segment
		(start 60.67552 -16.970248)
		(end 60.672218 -16.966946)
		(width 0.508)
		(layer "F.Cu")
		(net "P3V3")
	)
	(segment
		(start 18.7071 -74.2188)
		(end 17.3482 -74.2188)
		(width 0.508)
		(layer "F.Cu")
		(net "P3V3")
	)
	(segment
		(start 159.8295 -87.6046)
		(end 159.8295 -86.7283)
		(width 0.508)
		(layer "F.Cu")
		(net "P3V3")
	)
	(segment
		(start 19.6088 -94.1197)
		(end 19.6088 -94.996)
		(width 0.508)
		(layer "F.Cu")
		(net "P3V3")
	)
	(segment
		(start 156.998162 -92.90177)
		(end 156.01188 -92.90177)
		(width 0.3048)
		(layer "F.Cu")
		(net "P3V3")
	)
	(segment
		(start 159.8295 -78.864714)
		(end 158.9532 -78.864714)
		(width 0.508)
		(layer "F.Cu")
		(net "P3V3")
	)
	(segment
		(start 159.8295 -85.725)
		(end 159.054292 -85.725)
		(width 0.3048)
		(layer "F.Cu")
		(net "P3V3")
	)
	(segment
		(start 192.492376 -83.018376)
		(end 191.549782 -82.075782)
		(width 0.508)
		(layer "F.Cu")
		(net "P3V3")
	)
	(segment
		(start 173.3169 -112.0013)
		(end 172.3898 -112.0013)
		(width 0.508)
		(layer "F.Cu")
		(net "P3V3")
	)
	(segment
		(start 6.8453 -75.3618)
		(end 5.969 -75.3618)
		(width 0.508)
		(layer "F.Cu")
		(net "P3V3")
	)
	(segment
		(start 166.31158 -101.11994)
		(end 166.31158 -101.896164)
		(width 0.508)
		(layer "F.Cu")
		(net "P3V3")
	)
	(segment
		(start 52.7685 -72.136)
		(end 52.324 -72.136)
		(width 0.508)
		(layer "F.Cu")
		(net "P3V3")
	)
	(segment
		(start 159.10687 -80.007714)
		(end 158.3182 -80.007714)
		(width 0.508)
		(layer "F.Cu")
		(net "P3V3")
	)
	(segment
		(start 171.605956 -108.065824)
		(end 173.110144 -108.065824)
		(width 0.3556)
		(layer "F.Cu")
		(net "P3V3")
	)
	(segment
		(start 158.3182 -90.7034)
		(end 158.3182 -89.7636)
		(width 0.508)
		(layer "F.Cu")
		(net "P3V3")
	)
	(segment
		(start 50.8635 -77.9272)
		(end 49.9364 -77.9272)
		(width 0.508)
		(layer "F.Cu")
		(net "P3V3")
	)
	(segment
		(start 159.004 -76.019406)
		(end 157.81528 -76.019406)
		(width 0.3048)
		(layer "F.Cu")
		(net "P3V3")
	)
	(segment
		(start 61.4045 -24.13)
		(end 61.4045 -24.9555)
		(width 0.508)
		(layer "F.Cu")
		(net "P3V3")
	)
	(segment
		(start 153.070306 -88.656922)
		(end 153.072846 -88.654382)
		(width 0.508)
		(layer "F.Cu")
		(net "P3V3")
	)
	(segment
		(start 9.7028 -94.0689)
		(end 9.7028 -94.9452)
		(width 0.508)
		(layer "F.Cu")
		(net "P3V3")
	)
	(segment
		(start 61.0743 -71.8566)
		(end 61.557154 -71.8566)
		(width 0.508)
		(layer "F.Cu")
		(net "P3V3")
	)
	(segment
		(start 159.8295 -86.7283)
		(end 159.8295 -85.725)
		(width 0.508)
		(layer "F.Cu")
		(net "P3V3")
	)
	(segment
		(start 157.903672 -93.80728)
		(end 156.998162 -92.90177)
		(width 0.3048)
		(layer "F.Cu")
		(net "P3V3")
	)
	(segment
		(start 52.324 -72.136)
		(end 51.9176 -72.5424)
		(width 0.508)
		(layer "F.Cu")
		(net "P3V3")
	)
	(segment
		(start 159.8168 -76.934314)
		(end 159.8295 -76.921614)
		(width 0.508)
		(layer "F.Cu")
		(net "P3V3")
	)
	(segment
		(start 159.8168 -86.741)
		(end 159.8295 -86.7283)
		(width 0.508)
		(layer "F.Cu")
		(net "P3V3")
	)
	(segment
		(start 61.734446 -23.228554)
		(end 61.4045 -23.5585)
		(width 0.381)
		(layer "F.Cu")
		(net "P3V3")
	)
	(segment
		(start 159.8295 -75.969114)
		(end 159.054292 -75.969114)
		(width 0.3048)
		(layer "F.Cu")
		(net "P3V3")
	)
	(segment
		(start 61.734446 -22.326346)
		(end 61.734446 -23.228554)
		(width 0.381)
		(layer "F.Cu")
		(net "P3V3")
	)
	(segment
		(start 173.11116 -108.06684)
		(end 173.11116 -109.12856)
		(width 0.508)
		(layer "F.Cu")
		(net "P3V3")
	)
	(segment
		(start 18.5674 -95.3897)
		(end 18.5674 -96.1898)
		(width 0.508)
		(layer "F.Cu")
		(net "P3V3")
	)
	(segment
		(start 6.7564 -69.9643)
		(end 5.7785 -69.9643)
		(width 0.508)
		(layer "F.Cu")
		(net "P3V3")
	)
	(segment
		(start 12.51966 -101.23424)
		(end 12.6238 -101.1301)
		(width 0.4064)
		(layer "F.Cu")
		(net "P3V3")
	)
	(segment
		(start 191.549782 -82.075782)
		(end 191.549782 -81.707736)
		(width 0.508)
		(layer "F.Cu")
		(net "P3V3")
	)
	(segment
		(start 7.112 -82.931)
		(end 6.9215 -82.7405)
		(width 0.508)
		(layer "F.Cu")
		(net "P3V3")
	)
	(segment
		(start 7.5946 -95.275908)
		(end 7.5946 -96.076008)
		(width 0.508)
		(layer "F.Cu")
		(net "P3V3")
	)
	(segment
		(start 158.19628 -93.80728)
		(end 157.903672 -93.80728)
		(width 0.3048)
		(layer "F.Cu")
		(net "P3V3")
	)
	(segment
		(start 17.3482 -74.2188)
		(end 15.875 -74.2188)
		(width 0.508)
		(layer "F.Cu")
		(net "P3V3")
	)
	(segment
		(start 165.090094 -12.96289)
		(end 165.090094 -12.056872)
		(width 0.2032)
		(layer "F.Cu")
		(net "P3V3")
	)
	(segment
		(start 173.110144 -108.065824)
		(end 173.11116 -108.06684)
		(width 0.3556)
		(layer "F.Cu")
		(net "P3V3")
	)
	(segment
		(start 66.04 -72.2503)
		(end 66.04 -71.468234)
		(width 0.508)
		(layer "F.Cu")
		(net "P3V3")
	)
	(segment
		(start 189.73038 -80.377284)
		(end 189.73038 -78.93558)
		(width 0.508)
		(layer "F.Cu")
		(net "P3V3")
	)
	(segment
		(start 158.37408 -99.04476)
		(end 157.54604 -99.04476)
		(width 0.3048)
		(layer "F.Cu")
		(net "P3V3")
	)
	(segment
		(start 80.7847 -74.4601)
		(end 80.7847 -74.079608)
		(width 0.508)
		(layer "F.Cu")
		(net "P3V3")
	)
	(segment
		(start 180.132482 -68.728844)
		(end 172.014388 -68.728844)
		(width 1.016)
		(layer "F.Cu")
		(net "P3V3")
	)
	(segment
		(start 17.972278 -99.78009)
		(end 16.60525 -99.78009)
		(width 0.3556)
		(layer "F.Cu")
		(net "P3V3")
	)
	(segment
		(start 81.9912 -83.312)
		(end 87.660734 -83.312)
		(width 0.508)
		(layer "F.Cu")
		(net "P3V3")
	)
	(segment
		(start 157.54604 -99.04476)
		(end 157.46476 -99.04476)
		(width 0.3048)
		(layer "F.Cu")
		(net "P3V3")
	)
	(segment
		(start 157.00629 -98.58629)
		(end 156.01188 -98.58629)
		(width 0.3048)
		(layer "F.Cu")
		(net "P3V3")
	)
	(segment
		(start 158.258002 -90.763598)
		(end 158.3182 -90.7034)
		(width 0.508)
		(layer "F.Cu")
		(net "P3V3")
	)
	(segment
		(start 89.0397 -83.312)
		(end 90.5637 -84.836)
		(width 0.508)
		(layer "F.Cu")
		(net "P3V3")
	)
	(segment
		(start 8.6614 -94.0689)
		(end 8.6614 -94.9452)
		(width 0.508)
		(layer "F.Cu")
		(net "P3V3")
	)
	(segment
		(start 6.9215 -82.7405)
		(end 6.9215 -82.042)
		(width 0.508)
		(layer "F.Cu")
		(net "P3V3")
	)
	(segment
		(start 14.5669 -102.4001)
		(end 13.589 -102.4001)
		(width 0.508)
		(layer "F.Cu")
		(net "P3V3")
	)
	(segment
		(start 159.8295 -76.947014)
		(end 159.8168 -76.934314)
		(width 0.508)
		(layer "F.Cu")
		(net "P3V3")
	)
	(via
		(at 12.8778 -96.071182)
		(size 0.508)
		(drill 0.254)
		(layers "F.Cu" "B.Cu")
		(net "P3V3")
	)
	(via
		(at 159.8295 -87.6046)
		(size 0.508)
		(drill 0.254)
		(layers "F.Cu" "B.Cu")
		(net "P3V3")
	)
	(via
		(at 198.374 -21.3868)
		(size 0.508)
		(drill 0.254)
		(layers "F.Cu" "B.Cu")
		(net "P3V3")
	)
	(via
		(at 53.997606 -125.652276)
		(size 0.7112)
		(drill 0.4064)
		(layers "F.Cu" "B.Cu")
		(net "P3V3")
	)
	(via
		(at 183.23052 -107.67822)
		(size 0.508)
		(drill 0.254)
		(layers "F.Cu" "B.Cu")
		(net "P3V3")
	)
	(via
		(at 165.870128 -106.74223)
		(size 0.7112)
		(drill 0.4064)
		(layers "F.Cu" "B.Cu")
		(net "P3V3")
	)
	(via
		(at 72.517 -13.28039)
		(size 0.508)
		(drill 0.254)
		(layers "F.Cu" "B.Cu")
		(net "P3V3")
	)
	(via
		(at 145.965418 -121.868946)
		(size 0.508)
		(drill 0.254)
		(layers "F.Cu" "B.Cu")
		(net "P3V3")
	)
	(via
		(at 5.8674 -71.9328)
		(size 0.508)
		(drill 0.254)
		(layers "F.Cu" "B.Cu")
		(net "P3V3")
	)
	(via
		(at 24.96693 -94.943422)
		(size 0.508)
		(drill 0.254)
		(layers "F.Cu" "B.Cu")
		(net "P3V3")
	)
	(via
		(at 12.6238 -102.108)
		(size 0.508)
		(drill 0.254)
		(layers "F.Cu" "B.Cu")
		(net "P3V3")
	)
	(via
		(at 163.24707 -77.15631)
		(size 0.7112)
		(drill 0.4064)
		(layers "F.Cu" "B.Cu")
		(net "P3V3")
	)
	(via
		(at 17.2212 -80.772)
		(size 0.508)
		(drill 0.254)
		(layers "F.Cu" "B.Cu")
		(net "P3V3")
	)
	(via
		(at 194.504056 -83.018376)
		(size 0.508)
		(drill 0.254)
		(layers "F.Cu" "B.Cu")
		(net "P3V3")
	)
	(via
		(at 158.258002 -90.763598)
		(size 0.508)
		(drill 0.254)
		(layers "F.Cu" "B.Cu")
		(net "P3V3")
	)
	(via
		(at 169.8244 -61.6712)
		(size 0.508)
		(drill 0.254)
		(layers "F.Cu" "B.Cu")
		(net "P3V3")
	)
	(via
		(at 195.855082 -53.793136)
		(size 0.7112)
		(drill 0.4064)
		(layers "F.Cu" "B.Cu")
		(net "P3V3")
	)
	(via
		(at 6.096 -76.6445)
		(size 0.508)
		(drill 0.254)
		(layers "F.Cu" "B.Cu")
		(net "P3V3")
	)
	(via
		(at 165.497256 -13.370052)
		(size 0.508)
		(drill 0.254)
		(layers "F.Cu" "B.Cu")
		(net "P3V3")
	)
	(via
		(at 204.534516 -67.027044)
		(size 0.508)
		(drill 0.254)
		(layers "F.Cu" "B.Cu")
		(net "P3V3")
	)
	(via
		(at 41.95953 -91.030552)
		(size 0.7112)
		(drill 0.4064)
		(layers "F.Cu" "B.Cu")
		(net "P3V3")
	)
	(via
		(at 43.17873 -91.030552)
		(size 0.7112)
		(drill 0.4064)
		(layers "F.Cu" "B.Cu")
		(net "P3V3")
	)
	(via
		(at 26.00833 -94.943422)
		(size 0.508)
		(drill 0.254)
		(layers "F.Cu" "B.Cu")
		(net "P3V3")
	)
	(via
		(at 165.6588 -108.9914)
		(size 0.7112)
		(drill 0.4064)
		(layers "F.Cu" "B.Cu")
		(net "P3V3")
	)
	(via
		(at 159.8295 -88.6206)
		(size 0.508)
		(drill 0.254)
		(layers "F.Cu" "B.Cu")
		(net "P3V3")
	)
	(via
		(at 51.9176 -73.3298)
		(size 0.508)
		(drill 0.254)
		(layers "F.Cu" "B.Cu")
		(net "P3V3")
	)
	(via
		(at 49.9364 -77.9272)
		(size 0.508)
		(drill 0.254)
		(layers "F.Cu" "B.Cu")
		(net "P3V3")
	)
	(via
		(at 153.072846 -88.654382)
		(size 0.508)
		(drill 0.254)
		(layers "F.Cu" "B.Cu")
		(net "P3V3")
	)
	(via
		(at 163.703 -16.702786)
		(size 0.508)
		(drill 0.254)
		(layers "F.Cu" "B.Cu")
		(net "P3V3")
	)
	(via
		(at 171.6278 -117.729)
		(size 0.7112)
		(drill 0.4064)
		(layers "F.Cu" "B.Cu")
		(net "P3V3")
	)
	(via
		(at 52.981606 -124.382276)
		(size 0.7112)
		(drill 0.4064)
		(layers "F.Cu" "B.Cu")
		(net "P3V3")
	)
	(via
		(at 7.5946 -96.076008)
		(size 0.508)
		(drill 0.254)
		(layers "F.Cu" "B.Cu")
		(net "P3V3")
	)
	(via
		(at 65.945766 -71.374)
		(size 0.508)
		(drill 0.254)
		(layers "F.Cu" "B.Cu")
		(net "P3V3")
	)
	(via
		(at 61.4045 -24.9555)
		(size 0.508)
		(drill 0.254)
		(layers "F.Cu" "B.Cu")
		(net "P3V3")
	)
	(via
		(at 57.045606 -124.382276)
		(size 0.7112)
		(drill 0.4064)
		(layers "F.Cu" "B.Cu")
		(net "P3V3")
	)
	(via
		(at 147.968716 -29.555694)
		(size 0.7112)
		(drill 0.4064)
		(layers "F.Cu" "B.Cu")
		(net "P3V3")
	)
	(via
		(at 171.6278 -118.872)
		(size 0.7112)
		(drill 0.4064)
		(layers "F.Cu" "B.Cu")
		(net "P3V3")
	)
	(via
		(at 16.60525 -99.78009)
		(size 0.508)
		(drill 0.254)
		(layers "F.Cu" "B.Cu")
		(net "P3V3")
	)
	(via
		(at 159.8295 -78.864714)
		(size 0.508)
		(drill 0.254)
		(layers "F.Cu" "B.Cu")
		(net "P3V3")
	)
	(via
		(at 171.5516 -119.9642)
		(size 0.7112)
		(drill 0.4064)
		(layers "F.Cu" "B.Cu")
		(net "P3V3")
	)
	(via
		(at 55.013606 -124.382276)
		(size 0.7112)
		(drill 0.4064)
		(layers "F.Cu" "B.Cu")
		(net "P3V3")
	)
	(via
		(at 167.140128 -106.74223)
		(size 0.7112)
		(drill 0.4064)
		(layers "F.Cu" "B.Cu")
		(net "P3V3")
	)
	(via
		(at 17.1958 -81.661)
		(size 0.508)
		(drill 0.254)
		(layers "F.Cu" "B.Cu")
		(net "P3V3")
	)
	(via
		(at 19.6088 -94.996)
		(size 0.508)
		(drill 0.254)
		(layers "F.Cu" "B.Cu")
		(net "P3V3")
	)
	(via
		(at 5.969 -75.3618)
		(size 0.508)
		(drill 0.254)
		(layers "F.Cu" "B.Cu")
		(net "P3V3")
	)
	(via
		(at 81.163922 -73.700386)
		(size 0.508)
		(drill 0.254)
		(layers "F.Cu" "B.Cu")
		(net "P3V3")
	)
	(via
		(at 50.0634 -75.8952)
		(size 0.508)
		(drill 0.254)
		(layers "F.Cu" "B.Cu")
		(net "P3V3")
	)
	(via
		(at 172.3898 -112.0013)
		(size 0.508)
		(drill 0.254)
		(layers "F.Cu" "B.Cu")
		(net "P3V3")
	)
	(via
		(at 90.5637 -85.6488)
		(size 0.508)
		(drill 0.254)
		(layers "F.Cu" "B.Cu")
		(net "P3V3")
	)
	(via
		(at 173.11116 -109.12856)
		(size 0.508)
		(drill 0.254)
		(layers "F.Cu" "B.Cu")
		(net "P3V3")
	)
	(via
		(at 180.3908 -112.0648)
		(size 0.508)
		(drill 0.254)
		(layers "F.Cu" "B.Cu")
		(net "P3V3")
	)
	(via
		(at 68.1736 -71.374)
		(size 0.508)
		(drill 0.254)
		(layers "F.Cu" "B.Cu")
		(net "P3V3")
	)
	(via
		(at 161.97707 -77.15631)
		(size 0.7112)
		(drill 0.4064)
		(layers "F.Cu" "B.Cu")
		(net "P3V3")
	)
	(via
		(at 5.9436 -78.613)
		(size 0.508)
		(drill 0.254)
		(layers "F.Cu" "B.Cu")
		(net "P3V3")
	)
	(via
		(at 71.5518 -13.28039)
		(size 0.508)
		(drill 0.254)
		(layers "F.Cu" "B.Cu")
		(net "P3V3")
	)
	(via
		(at 166.614856 -13.270992)
		(size 0.7112)
		(drill 0.4064)
		(layers "F.Cu" "B.Cu")
		(net "P3V3")
	)
	(via
		(at 159.10687 -80.007714)
		(size 0.508)
		(drill 0.254)
		(layers "F.Cu" "B.Cu")
		(net "P3V3")
	)
	(via
		(at 158.5468 -94.615)
		(size 0.508)
		(drill 0.254)
		(layers "F.Cu" "B.Cu")
		(net "P3V3")
	)
	(via
		(at 191.573658 -75.593194)
		(size 0.508)
		(drill 0.254)
		(layers "F.Cu" "B.Cu")
		(net "P3V3")
	)
	(via
		(at 169.7482 -117.9322)
		(size 0.6096)
		(drill 0.3048)
		(layers "F.Cu" "B.Cu")
		(net "P3V3")
	)
	(via
		(at 167.386 -108.9406)
		(size 0.7112)
		(drill 0.4064)
		(layers "F.Cu" "B.Cu")
		(net "P3V3")
	)
	(via
		(at 13.589 -102.4001)
		(size 0.508)
		(drill 0.254)
		(layers "F.Cu" "B.Cu")
		(net "P3V3")
	)
	(via
		(at 85.852 -106.934)
		(size 0.508)
		(drill 0.254)
		(layers "F.Cu" "B.Cu")
		(net "P3V3")
	)
	(via
		(at 20.6502 -94.996)
		(size 0.508)
		(drill 0.254)
		(layers "F.Cu" "B.Cu")
		(net "P3V3")
	)
	(via
		(at 23.79853 -96.120204)
		(size 0.508)
		(drill 0.254)
		(layers "F.Cu" "B.Cu")
		(net "P3V3")
	)
	(via
		(at 193.04 -73.787)
		(size 0.6604)
		(drill 0.3302)
		(layers "F.Cu" "B.Cu")
		(net "P3V3")
	)
	(via
		(at 82.709766 -112.65154)
		(size 0.508)
		(drill 0.254)
		(layers "F.Cu" "B.Cu")
		(net "P3V3")
	)
	(via
		(at 13.9192 -94.8944)
		(size 0.508)
		(drill 0.254)
		(layers "F.Cu" "B.Cu")
		(net "P3V3")
	)
	(via
		(at 162.414204 -12.44981)
		(size 0.6096)
		(drill 0.3048)
		(layers "F.Cu" "B.Cu")
		(net "P3V3")
	)
	(via
		(at 63.2206 -71.864728)
		(size 0.508)
		(drill 0.254)
		(layers "F.Cu" "B.Cu")
		(net "P3V3")
	)
	(via
		(at 161.97707 -75.88631)
		(size 0.7112)
		(drill 0.4064)
		(layers "F.Cu" "B.Cu")
		(net "P3V3")
	)
	(via
		(at 17.3482 -74.2188)
		(size 0.508)
		(drill 0.254)
		(layers "F.Cu" "B.Cu")
		(net "P3V3")
	)
	(via
		(at 18.5674 -96.1898)
		(size 0.508)
		(drill 0.254)
		(layers "F.Cu" "B.Cu")
		(net "P3V3")
	)
	(via
		(at 170.9674 -60.5282)
		(size 0.6096)
		(drill 0.3048)
		(layers "F.Cu" "B.Cu")
		(net "P3V3")
	)
	(via
		(at 80.6704 -70.8152)
		(size 0.508)
		(drill 0.254)
		(layers "F.Cu" "B.Cu")
		(net "P3V3")
	)
	(via
		(at 198.374 -22.352)
		(size 0.508)
		(drill 0.254)
		(layers "F.Cu" "B.Cu")
		(net "P3V3")
	)
	(via
		(at 44.44873 -91.030552)
		(size 0.7112)
		(drill 0.4064)
		(layers "F.Cu" "B.Cu")
		(net "P3V3")
	)
	(via
		(at 61.557154 -71.8566)
		(size 0.508)
		(drill 0.254)
		(layers "F.Cu" "B.Cu")
		(net "P3V3")
	)
	(via
		(at 82.2198 -72.263)
		(size 0.6096)
		(drill 0.3048)
		(layers "F.Cu" "B.Cu")
		(net "P3V3")
	)
	(via
		(at 9.7028 -94.9452)
		(size 0.508)
		(drill 0.254)
		(layers "F.Cu" "B.Cu")
		(net "P3V3")
	)
	(via
		(at 169.8752 -121.412)
		(size 0.6096)
		(drill 0.3048)
		(layers "F.Cu" "B.Cu")
		(net "P3V3")
	)
	(via
		(at 5.7785 -69.9643)
		(size 0.508)
		(drill 0.254)
		(layers "F.Cu" "B.Cu")
		(net "P3V3")
	)
	(via
		(at 157.54604 -99.04476)
		(size 0.508)
		(drill 0.254)
		(layers "F.Cu" "B.Cu")
		(net "P3V3")
	)
	(via
		(at 15.3416 -94.8944)
		(size 0.508)
		(drill 0.254)
		(layers "F.Cu" "B.Cu")
		(net "P3V3")
	)
	(via
		(at 57.9882 -71.3486)
		(size 0.508)
		(drill 0.254)
		(layers "F.Cu" "B.Cu")
		(net "P3V3")
	)
	(via
		(at 60.672218 -16.1671)
		(size 0.508)
		(drill 0.254)
		(layers "F.Cu" "B.Cu")
		(net "P3V3")
	)
	(via
		(at 159.8295 -77.848714)
		(size 0.508)
		(drill 0.254)
		(layers "F.Cu" "B.Cu")
		(net "P3V3")
	)
	(via
		(at 38.8112 -28.8036)
		(size 0.508)
		(drill 0.254)
		(layers "F.Cu" "B.Cu")
		(net "P3V3")
	)
	(via
		(at 163.24707 -75.88631)
		(size 0.7112)
		(drill 0.4064)
		(layers "F.Cu" "B.Cu")
		(net "P3V3")
	)
	(via
		(at 55.7276 -70.9676)
		(size 0.508)
		(drill 0.254)
		(layers "F.Cu" "B.Cu")
		(net "P3V3")
	)
	(via
		(at 44.44873 -89.811352)
		(size 0.7112)
		(drill 0.4064)
		(layers "F.Cu" "B.Cu")
		(net "P3V3")
	)
	(via
		(at 76.970128 -73.6346)
		(size 0.508)
		(drill 0.254)
		(layers "F.Cu" "B.Cu")
		(net "P3V3")
	)
	(via
		(at 172.72 -120.269)
		(size 0.6604)
		(drill 0.3302)
		(layers "F.Cu" "B.Cu")
		(net "P3V3")
	)
	(via
		(at 171.484544 -68.199)
		(size 0.7112)
		(drill 0.4064)
		(layers "F.Cu" "B.Cu")
		(net "P3V3")
	)
	(via
		(at 7.112 -82.931)
		(size 0.508)
		(drill 0.254)
		(layers "F.Cu" "B.Cu")
		(net "P3V3")
	)
	(via
		(at 166.505128 -108.01223)
		(size 0.7112)
		(drill 0.4064)
		(layers "F.Cu" "B.Cu")
		(net "P3V3")
	)
	(via
		(at 78.5622 -71.9582)
		(size 0.6096)
		(drill 0.3048)
		(layers "F.Cu" "B.Cu")
		(net "P3V3")
	)
	(via
		(at 8.6614 -94.9452)
		(size 0.508)
		(drill 0.254)
		(layers "F.Cu" "B.Cu")
		(net "P3V3")
	)
	(via
		(at 166.31158 -101.896164)
		(size 0.508)
		(drill 0.254)
		(layers "F.Cu" "B.Cu")
		(net "P3V3")
	)
	(via
		(at 147.57908 -119.86006)
		(size 0.508)
		(drill 0.254)
		(layers "F.Cu" "B.Cu")
		(net "P3V3")
	)
	(via
		(at 166.878 -11.811)
		(size 0.6604)
		(drill 0.3302)
		(layers "F.Cu" "B.Cu")
		(net "P3V3")
	)
	(via
		(at 56.029606 -125.652276)
		(size 0.7112)
		(drill 0.4064)
		(layers "F.Cu" "B.Cu")
		(net "P3V3")
	)
	(via
		(at 43.17873 -89.811352)
		(size 0.7112)
		(drill 0.4064)
		(layers "F.Cu" "B.Cu")
		(net "P3V3")
	)
	(segment
		(start 162.742372 -14.429486)
		(end 157.816042 -14.429486)
		(width 1.016)
		(layer "B.Cu")
		(net "P3V3")
	)
	(segment
		(start 79.436214 -71.07936)
		(end 79.012288 -70.655434)
		(width 1.016)
		(layer "B.Cu")
		(net "P3V3")
	)
	(segment
		(start 80.26781 -75.6031)
		(end 80.26781 -73.69429)
		(width 0.3048)
		(layer "B.Cu")
		(net "P3V3")
	)
	(segment
		(start 163.703 -16.702786)
		(end 162.814762 -16.702786)
		(width 0.508)
		(layer "B.Cu")
		(net "P3V3")
	)
	(segment
		(start 204.534516 -67.027044)
		(end 204.724 -66.83756)
		(width 0.508)
		(layer "B.Cu")
		(net "P3V3")
	)
	(segment
		(start 72.517 -13.28039)
		(end 72.517 -14.114272)
		(width 0.508)
		(layer "B.Cu")
		(net "P3V3")
	)
	(segment
		(start 145.817082 -121.72061)
		(end 145.965418 -121.868946)
		(width 0.508)
		(layer "B.Cu")
		(net "P3V3")
	)
	(segment
		(start 157.816042 -14.429486)
		(end 147.968716 -24.276812)
		(width 1.016)
		(layer "B.Cu")
		(net "P3V3")
	)
	(segment
		(start 80.26781 -73.69429)
		(end 80.2767 -73.6854)
		(width 0.3048)
		(layer "B.Cu")
		(net "P3V3")
	)
	(segment
		(start 147.968716 -24.276812)
		(end 147.968716 -29.555694)
		(width 1.016)
		(layer "B.Cu")
		(net "P3V3")
	)
	(segment
		(start 71.922894 -70.655434)
		(end 71.204328 -71.374)
		(width 1.016)
		(layer "B.Cu")
		(net "P3V3")
	)
	(segment
		(start 90.5637 -85.2043)
		(end 90.5637 -85.6488)
		(width 0.508)
		(layer "B.Cu")
		(net "P3V3")
	)
	(segment
		(start 163.836096 -13.335762)
		(end 162.742372 -14.429486)
		(width 1.016)
		(layer "B.Cu")
		(net "P3V3")
	)
	(segment
		(start 204.724 -66.83756)
		(end 204.724 -58.1914)
		(width 0.508)
		(layer "B.Cu")
		(net "P3V3")
	)
	(segment
		(start 145.965418 -121.868946)
		(end 146.6977 -122.601228)
		(width 0.508)
		(layer "B.Cu")
		(net "P3V3")
	)
	(segment
		(start 204.724 -58.1914)
		(end 201.6506 -55.118)
		(width 0.508)
		(layer "B.Cu")
		(net "P3V3")
	)
	(segment
		(start 79.012288 -70.655434)
		(end 71.922894 -70.655434)
		(width 1.016)
		(layer "B.Cu")
		(net "P3V3")
	)
	(segment
		(start 146.6977 -122.601228)
		(end 146.6977 -122.7836)
		(width 0.508)
		(layer "B.Cu")
		(net "P3V3")
	)
	(segment
		(start 197.179946 -55.118)
		(end 195.855082 -53.793136)
		(width 0.508)
		(layer "B.Cu")
		(net "P3V3")
	)
	(segment
		(start 145.817082 -121.027952)
		(end 145.817082 -121.72061)
		(width 0.508)
		(layer "B.Cu")
		(net "P3V3")
	)
	(segment
		(start 201.6506 -55.118)
		(end 197.179946 -55.118)
		(width 0.508)
		(layer "B.Cu")
		(net "P3V3")
	)
	(segment
		(start 172.399706 -68.199)
		(end 171.484544 -68.199)
		(width 0.508)
		(layer "B.Cu")
		(net "P3V3")
	)
	(segment
		(start 91.0717 -83.947)
		(end 91.0717 -84.6963)
		(width 0.508)
		(layer "B.Cu")
		(net "P3V3")
	)
	(segment
		(start 71.204328 -71.374)
		(end 68.1736 -71.374)
		(width 1.016)
		(layer "B.Cu")
		(net "P3V3")
	)
	(segment
		(start 91.0717 -84.6963)
		(end 90.5637 -85.2043)
		(width 0.508)
		(layer "B.Cu")
		(net "P3V3")
	)
	(segment
		(start 71.5518 -13.28039)
		(end 71.5518 -14.114272)
		(width 0.508)
		(layer "B.Cu")
		(net "P3V3")
	)
	(segment
		(start 203.22032 -67.027044)
		(end 204.534516 -67.027044)
		(width 0.3048)
		(layer "B.Cu")
		(net "P3V3")
	)
	(segment
		(start 149.86 -72.590914)
		(end 149.86 -58.780934)
		(width 1.016)
		(layer "In2.Cu")
		(net "P3V3")
	)
	(segment
		(start 196.759322 -39.623492)
		(end 200.6854 -35.697414)
		(width 1.016)
		(layer "In2.Cu")
		(net "P3V3")
	)
	(segment
		(start 147.20951 -30.3149)
		(end 147.968716 -29.555694)
		(width 1.016)
		(layer "In2.Cu")
		(net "P3V3")
	)
	(segment
		(start 143.249396 -31.787338)
		(end 144.721834 -30.3149)
		(width 1.016)
		(layer "In2.Cu")
		(net "P3V3")
	)
	(segment
		(start 198.374 -21.3868)
		(end 198.374 -22.352)
		(width 1.016)
		(layer "In2.Cu")
		(net "P3V3")
	)
	(segment
		(start 159.10687 -80.007714)
		(end 157.2768 -80.007714)
		(width 1.016)
		(layer "In2.Cu")
		(net "P3V3")
	)
	(segment
		(start 194.504056 -83.018376)
		(end 194.504056 -78.045056)
		(width 0.508)
		(layer "In2.Cu")
		(net "P3V3")
	)
	(segment
		(start 158.258002 -90.763598)
		(end 156.148786 -88.654382)
		(width 0.508)
		(layer "In2.Cu")
		(net "P3V3")
	)
	(segment
		(start 196.759322 -45.554646)
		(end 196.759322 -39.623492)
		(width 1.016)
		(layer "In2.Cu")
		(net "P3V3")
	)
	(segment
		(start 144.721834 -30.3149)
		(end 147.20951 -30.3149)
		(width 1.016)
		(layer "In2.Cu")
		(net "P3V3")
	)
	(segment
		(start 156.148786 -88.654382)
		(end 153.072846 -88.654382)
		(width 0.508)
		(layer "In2.Cu")
		(net "P3V3")
	)
	(segment
		(start 149.86 -58.780934)
		(end 143.249396 -52.17033)
		(width 1.016)
		(layer "In2.Cu")
		(net "P3V3")
	)
	(segment
		(start 194.504056 -78.045056)
		(end 192.052194 -75.593194)
		(width 0.508)
		(layer "In2.Cu")
		(net "P3V3")
	)
	(segment
		(start 157.2768 -80.007714)
		(end 149.86 -72.590914)
		(width 1.016)
		(layer "In2.Cu")
		(net "P3V3")
	)
	(segment
		(start 192.052194 -75.593194)
		(end 191.573658 -75.593194)
		(width 0.508)
		(layer "In2.Cu")
		(net "P3V3")
	)
	(segment
		(start 194.327526 -47.986442)
		(end 196.759322 -45.554646)
		(width 1.016)
		(layer "In2.Cu")
		(net "P3V3")
	)
	(segment
		(start 143.249396 -52.17033)
		(end 143.249396 -31.787338)
		(width 1.016)
		(layer "In2.Cu")
		(net "P3V3")
	)
	(segment
		(start 200.6854 -24.6634)
		(end 198.374 -22.352)
		(width 1.016)
		(layer "In2.Cu")
		(net "P3V3")
	)
	(segment
		(start 194.327526 -52.26558)
		(end 194.327526 -47.986442)
		(width 1.016)
		(layer "In2.Cu")
		(net "P3V3")
	)
	(segment
		(start 195.855082 -53.793136)
		(end 194.327526 -52.26558)
		(width 1.016)
		(layer "In2.Cu")
		(net "P3V3")
	)
	(segment
		(start 200.6854 -35.697414)
		(end 200.6854 -24.6634)
		(width 1.016)
		(layer "In2.Cu")
		(net "P3V3")
	)
	(segment
		(start 194.504056 -83.018376)
		(end 200.756774 -83.018376)
		(width 0.762)
		(layer "In5.Cu")
		(net "P3V3")
	)
	(segment
		(start 163.703 -16.702786)
		(end 165.60927 -16.702786)
		(width 0.508)
		(layer "In5.Cu")
		(net "P3V3")
	)
	(segment
		(start 200.756774 -83.018376)
		(end 204.534516 -79.240634)
		(width 0.762)
		(layer "In5.Cu")
		(net "P3V3")
	)
	(segment
		(start 165.60927 -16.702786)
		(end 166.614856 -15.6972)
		(width 0.508)
		(layer "In5.Cu")
		(net "P3V3")
	)
	(segment
		(start 204.534516 -79.240634)
		(end 204.534516 -67.027044)
		(width 0.762)
		(layer "In5.Cu")
		(net "P3V3")
	)
	(segment
		(start 166.614856 -15.6972)
		(end 166.614856 -13.270992)
		(width 0.508)
		(layer "In5.Cu")
		(net "P3V3")
	)
	(segment
		(start 24.19223 -85.799422)
		(end 24.19223 -84.846922)
		(width 0.508)
		(layer "F.Cu")
		(net "P1V8_E")
	)
	(segment
		(start 134.339076 -89.17051)
		(end 135.355076 -89.17051)
		(width 0.508)
		(layer "F.Cu")
		(net "P1V8_E")
	)
	(segment
		(start 126.9238 -90.3605)
		(end 126.9238 -90.985086)
		(width 0.508)
		(layer "F.Cu")
		(net "P1V8_E")
	)
	(segment
		(start 112.00003 -72.00011)
		(end 111.499904 -72.500236)
		(width 0.4572)
		(layer "F.Cu")
		(net "P1V8_E")
	)
	(segment
		(start 58.8518 -81.3054)
		(end 58.8518 -80.5307)
		(width 0.508)
		(layer "F.Cu")
		(net "P1V8_E")
	)
	(segment
		(start 71.2851 -82.5881)
		(end 71.3232 -82.55)
		(width 0.508)
		(layer "F.Cu")
		(net "P1V8_E")
	)
	(segment
		(start 87.9475 -76.7715)
		(end 88.011 -76.835)
		(width 0.508)
		(layer "F.Cu")
		(net "P1V8_E")
	)
	(segment
		(start 118.500144 -79.500222)
		(end 119.000016 -80.000094)
		(width 0.4572)
		(layer "F.Cu")
		(net "P1V8_E")
	)
	(segment
		(start 71.3105 -82.5373)
		(end 71.3232 -82.55)
		(width 0.508)
		(layer "F.Cu")
		(net "P1V8_E")
	)
	(segment
		(start 165.090094 -5.421122)
		(end 165.090094 -6.418072)
		(width 0.2032)
		(layer "F.Cu")
		(net "P1V8_E")
	)
	(segment
		(start 68.41871 -80.619854)
		(end 68.48221 -80.556354)
		(width 0.508)
		(layer "F.Cu")
		(net "P1V8_E")
	)
	(segment
		(start 140.054076 -85.150452)
		(end 139.01801 -85.150452)
		(width 0.508)
		(layer "F.Cu")
		(net "P1V8_E")
	)
	(segment
		(start 128.500124 -79.500222)
		(end 128.999996 -80.000094)
		(width 0.4572)
		(layer "F.Cu")
		(net "P1V8_E")
	)
	(segment
		(start 105.877614 -87.333836)
		(end 105.877614 -88.166956)
		(width 0.508)
		(layer "F.Cu")
		(net "P1V8_E")
	)
	(segment
		(start 24.08428 -85.907372)
		(end 24.19223 -85.799422)
		(width 0.3556)
		(layer "F.Cu")
		(net "P1V8_E")
	)
	(segment
		(start 107.499912 -61.500004)
		(end 107.999784 -61.000132)
		(width 0.4572)
		(layer "F.Cu")
		(net "P1V8_E")
	)
	(segment
		(start 122.7582 -92.0496)
		(end 122.3645 -92.0496)
		(width 0.508)
		(layer "F.Cu")
		(net "P1V8_E")
	)
	(segment
		(start 13.21435 -85.85835)
		(end 13.3223 -85.7504)
		(width 0.3556)
		(layer "F.Cu")
		(net "P1V8_E")
	)
	(segment
		(start 121.500138 -72.500236)
		(end 121.000266 -73.000108)
		(width 0.4572)
		(layer "F.Cu")
		(net "P1V8_E")
	)
	(segment
		(start 120.4341 -88.9)
		(end 121.031 -88.3031)
		(width 0.508)
		(layer "F.Cu")
		(net "P1V8_E")
	)
	(segment
		(start 159.909256 -91.5924)
		(end 160.166812 -91.849956)
		(width 0.508)
		(layer "F.Cu")
		(net "P1V8_E")
	)
	(segment
		(start 74.0283 -81.9277)
		(end 73.8505 -82.1055)
		(width 0.508)
		(layer "F.Cu")
		(net "P1V8_E")
	)
	(segment
		(start 63.55715 -80.509618)
		(end 63.55715 -81.208118)
		(width 0.508)
		(layer "F.Cu")
		(net "P1V8_E")
	)
	(segment
		(start 134.96671 -84.246466)
		(end 134.96671 -85.262466)
		(width 0.508)
		(layer "F.Cu")
		(net "P1V8_E")
	)
	(segment
		(start 121.500138 -75.50023)
		(end 122.00001 -76.000102)
		(width 0.4572)
		(layer "F.Cu")
		(net "P1V8_E")
	)
	(segment
		(start 91.4908 -77.0128)
		(end 92.1385 -77.0128)
		(width 0.508)
		(layer "F.Cu")
		(net "P1V8_E")
	)
	(segment
		(start 125.2728 -90.3605)
		(end 125.2728 -91.1352)
		(width 0.508)
		(layer "F.Cu")
		(net "P1V8_E")
	)
	(segment
		(start 73.8505 -82.8802)
		(end 73.8505 -82.55)
		(width 0.508)
		(layer "F.Cu")
		(net "P1V8_E")
	)
	(segment
		(start 121.031 -88.3031)
		(end 121.031 -87.4395)
		(width 0.508)
		(layer "F.Cu")
		(net "P1V8_E")
	)
	(segment
		(start 158.75 -91.8718)
		(end 158.75 -91.849956)
		(width 0.508)
		(layer "F.Cu")
		(net "P1V8_E")
	)
	(segment
		(start 151.897842 -98.161094)
		(end 152.363678 -98.161094)
		(width 0.3048)
		(layer "F.Cu")
		(net "P1V8_E")
	)
	(segment
		(start 152.438862 -98.08591)
		(end 153.67508 -98.08591)
		(width 0.3048)
		(layer "F.Cu")
		(net "P1V8_E")
	)
	(segment
		(start 134.339076 -89.17051)
		(end 133.604762 -89.17051)
		(width 0.508)
		(layer "F.Cu")
		(net "P1V8_E")
	)
	(segment
		(start 134.96671 -85.28431)
		(end 135.636 -85.9536)
		(width 0.508)
		(layer "F.Cu")
		(net "P1V8_E")
	)
	(segment
		(start 105.499916 -82.500216)
		(end 105.000044 -83.000088)
		(width 0.4572)
		(layer "F.Cu")
		(net "P1V8_E")
	)
	(segment
		(start 7.88035 -85.90915)
		(end 7.9883 -85.8012)
		(width 0.3556)
		(layer "F.Cu")
		(net "P1V8_E")
	)
	(segment
		(start 130.50012 -79.500222)
		(end 131.189222 -79.500222)
		(width 0.4572)
		(layer "F.Cu")
		(net "P1V8_E")
	)
	(segment
		(start 74.0029 -83.0326)
		(end 73.8505 -82.8802)
		(width 0.508)
		(layer "F.Cu")
		(net "P1V8_E")
	)
	(segment
		(start 116.500148 -79.500222)
		(end 117.00002 -80.000094)
		(width 0.4572)
		(layer "F.Cu")
		(net "P1V8_E")
	)
	(segment
		(start 158.75 -91.849956)
		(end 159.007556 -91.5924)
		(width 0.508)
		(layer "F.Cu")
		(net "P1V8_E")
	)
	(segment
		(start 131.189222 -79.500222)
		(end 131.191 -79.502)
		(width 0.4572)
		(layer "F.Cu")
		(net "P1V8_E")
	)
	(segment
		(start 54.4703 -80.518)
		(end 54.37632 -80.42402)
		(width 0.3556)
		(layer "F.Cu")
		(net "P1V8_E")
	)
	(segment
		(start 71.2851 -83.4136)
		(end 71.2851 -82.5881)
		(width 0.508)
		(layer "F.Cu")
		(net "P1V8_E")
	)
	(segment
		(start 110.499906 -71.500238)
		(end 110.000034 -72.00011)
		(width 0.4572)
		(layer "F.Cu")
		(net "P1V8_E")
	)
	(segment
		(start 110.226856 -90.518742)
		(end 110.49 -90.255598)
		(width 0.508)
		(layer "F.Cu")
		(net "P1V8_E")
	)
	(segment
		(start 123.2154 -92.3036)
		(end 123.0122 -92.3036)
		(width 0.508)
		(layer "F.Cu")
		(net "P1V8_E")
	)
	(segment
		(start 165.453314 -5.057902)
		(end 165.090094 -5.421122)
		(width 0.2032)
		(layer "F.Cu")
		(net "P1V8_E")
	)
	(segment
		(start 111.125 -87.7062)
		(end 111.125 -87.4395)
		(width 0.508)
		(layer "F.Cu")
		(net "P1V8_E")
	)
	(segment
		(start 13.21435 -87.377778)
		(end 13.21435 -85.85835)
		(width 0.3556)
		(layer "F.Cu")
		(net "P1V8_E")
	)
	(segment
		(start 110.49 -88.3412)
		(end 111.125 -87.7062)
		(width 0.508)
		(layer "F.Cu")
		(net "P1V8_E")
	)
	(segment
		(start 119.500142 -75.50023)
		(end 120.000014 -76.000102)
		(width 0.4572)
		(layer "F.Cu")
		(net "P1V8_E")
	)
	(segment
		(start 109.499908 -65.499996)
		(end 109.000036 -65.000124)
		(width 0.4572)
		(layer "F.Cu")
		(net "P1V8_E")
	)
	(segment
		(start 97.536 -86.0044)
		(end 97.1804 -85.6488)
		(width 0.508)
		(layer "F.Cu")
		(net "P1V8_E")
	)
	(segment
		(start 151.930608 -92.148914)
		(end 152.561036 -92.148914)
		(width 0.3048)
		(layer "F.Cu")
		(net "P1V8_E")
	)
	(segment
		(start 95.0595 -85.872828)
		(end 95.287592 -85.644736)
		(width 0.508)
		(layer "F.Cu")
		(net "P1V8_E")
	)
	(segment
		(start 113.000028 -73.000108)
		(end 113.4999 -72.500236)
		(width 0.4572)
		(layer "F.Cu")
		(net "P1V8_E")
	)
	(segment
		(start 101.499924 -60.500006)
		(end 101.000052 -60.000134)
		(width 0.4572)
		(layer "F.Cu")
		(net "P1V8_E")
	)
	(segment
		(start 110.49 -90.255598)
		(end 110.49 -88.3412)
		(width 0.508)
		(layer "F.Cu")
		(net "P1V8_E")
	)
	(segment
		(start 135.636 -85.9536)
		(end 135.975344 -85.614256)
		(width 0.508)
		(layer "F.Cu")
		(net "P1V8_E")
	)
	(segment
		(start 58.8518 -80.5307)
		(end 58.8899 -80.4926)
		(width 0.508)
		(layer "F.Cu")
		(net "P1V8_E")
	)
	(segment
		(start 118.500144 -71.500238)
		(end 119.000016 -72.00011)
		(width 0.4572)
		(layer "F.Cu")
		(net "P1V8_E")
	)
	(segment
		(start 117.00002 -72.00011)
		(end 117.500146 -72.500236)
		(width 0.4572)
		(layer "F.Cu")
		(net "P1V8_E")
	)
	(segment
		(start 68.41871 -81.369154)
		(end 68.41871 -80.619854)
		(width 0.508)
		(layer "F.Cu")
		(net "P1V8_E")
	)
	(segment
		(start 108.49991 -72.500236)
		(end 108.000038 -73.000108)
		(width 0.4572)
		(layer "F.Cu")
		(net "P1V8_E")
	)
	(segment
		(start 134.96671 -85.262466)
		(end 134.96671 -85.28431)
		(width 0.508)
		(layer "F.Cu")
		(net "P1V8_E")
	)
	(segment
		(start 87.122 -76.7715)
		(end 87.9475 -76.7715)
		(width 0.508)
		(layer "F.Cu")
		(net "P1V8_E")
	)
	(segment
		(start 119.000016 -72.00011)
		(end 119.500142 -72.500236)
		(width 0.4572)
		(layer "F.Cu")
		(net "P1V8_E")
	)
	(segment
		(start 101.499924 -62.500002)
		(end 101.000052 -62.00013)
		(width 0.4572)
		(layer "F.Cu")
		(net "P1V8_E")
	)
	(segment
		(start 95.287592 -84.509864)
		(end 95.105728 -84.328)
		(width 0.508)
		(layer "F.Cu")
		(net "P1V8_E")
	)
	(segment
		(start 95.0595 -86.487)
		(end 95.0595 -85.872828)
		(width 0.508)
		(layer "F.Cu")
		(net "P1V8_E")
	)
	(segment
		(start 104.499918 -63.5)
		(end 104.000046 -63.000128)
		(width 0.4572)
		(layer "F.Cu")
		(net "P1V8_E")
	)
	(segment
		(start 120.50014 -79.500222)
		(end 121.000012 -80.000094)
		(width 0.4572)
		(layer "F.Cu")
		(net "P1V8_E")
	)
	(segment
		(start 74.0029 -83.3882)
		(end 74.0029 -83.0326)
		(width 0.508)
		(layer "F.Cu")
		(net "P1V8_E")
	)
	(segment
		(start 7.88035 -87.428578)
		(end 7.88035 -85.90915)
		(width 0.3556)
		(layer "F.Cu")
		(net "P1V8_E")
	)
	(segment
		(start 113.0681 -88.3412)
		(end 112.014 -88.3412)
		(width 0.508)
		(layer "F.Cu")
		(net "P1V8_E")
	)
	(segment
		(start 59.007248 -80.375252)
		(end 59.007248 -79.12227)
		(width 0.3556)
		(layer "F.Cu")
		(net "P1V8_E")
	)
	(segment
		(start 110.499906 -77.500226)
		(end 110.000034 -78.000098)
		(width 0.4572)
		(layer "F.Cu")
		(net "P1V8_E")
	)
	(segment
		(start 108.6358 -87.843868)
		(end 108.321856 -88.157812)
		(width 0.508)
		(layer "F.Cu")
		(net "P1V8_E")
	)
	(segment
		(start 128.5748 -90.3605)
		(end 128.5748 -91.137486)
		(width 0.508)
		(layer "F.Cu")
		(net "P1V8_E")
	)
	(segment
		(start 18.72615 -87.479378)
		(end 18.72615 -85.95995)
		(width 0.3556)
		(layer "F.Cu")
		(net "P1V8_E")
	)
	(segment
		(start 149.9489 -83.058)
		(end 149.9489 -82.044794)
		(width 0.508)
		(layer "F.Cu")
		(net "P1V8_E")
	)
	(segment
		(start 68.599558 -80.439006)
		(end 68.599558 -79.186024)
		(width 0.3556)
		(layer "F.Cu")
		(net "P1V8_E")
	)
	(segment
		(start 63.55715 -81.208118)
		(end 63.44285 -81.322418)
		(width 0.508)
		(layer "F.Cu")
		(net "P1V8_E")
	)
	(segment
		(start 92.1385 -75.9968)
		(end 92.1385 -74.422)
		(width 0.508)
		(layer "F.Cu")
		(net "P1V8_E")
	)
	(segment
		(start 54.37632 -80.42402)
		(end 54.37632 -79.121)
		(width 0.3556)
		(layer "F.Cu")
		(net "P1V8_E")
	)
	(segment
		(start 101.6762 -86.7791)
		(end 101.6762 -86.4362)
		(width 0.508)
		(layer "F.Cu")
		(net "P1V8_E")
	)
	(segment
		(start 63.55715 -80.509618)
		(end 63.66637 -80.400398)
		(width 0.3556)
		(layer "F.Cu")
		(net "P1V8_E")
	)
	(segment
		(start 95.105728 -84.328)
		(end 95.105728 -83.439762)
		(width 0.508)
		(layer "F.Cu")
		(net "P1V8_E")
	)
	(segment
		(start 126.9238 -90.985086)
		(end 126.6698 -91.239086)
		(width 0.508)
		(layer "F.Cu")
		(net "P1V8_E")
	)
	(segment
		(start 130.985514 -91.239086)
		(end 130.556 -91.239086)
		(width 0.508)
		(layer "F.Cu")
		(net "P1V8_E")
	)
	(segment
		(start 104.499918 -59.500008)
		(end 104.000046 -59.000136)
		(width 0.4572)
		(layer "F.Cu")
		(net "P1V8_E")
	)
	(segment
		(start 123.0122 -92.3036)
		(end 122.7582 -92.0496)
		(width 0.508)
		(layer "F.Cu")
		(net "P1V8_E")
	)
	(segment
		(start 139.01801 -85.925152)
		(end 139.034266 -85.941408)
		(width 0.508)
		(layer "F.Cu")
		(net "P1V8_E")
	)
	(segment
		(start 93.7895 -70.993)
		(end 92.62237 -70.993)
		(width 0.508)
		(layer "F.Cu")
		(net "P1V8_E")
	)
	(segment
		(start 119.500142 -72.500236)
		(end 119.00027 -73.000108)
		(width 0.4572)
		(layer "F.Cu")
		(net "P1V8_E")
	)
	(segment
		(start 159.007556 -91.5924)
		(end 159.909256 -91.5924)
		(width 0.508)
		(layer "F.Cu")
		(net "P1V8_E")
	)
	(segment
		(start 113.6142 -87.4395)
		(end 113.6142 -87.7951)
		(width 0.508)
		(layer "F.Cu")
		(net "P1V8_E")
	)
	(segment
		(start 71.3105 -81.6864)
		(end 71.3105 -82.5373)
		(width 0.508)
		(layer "F.Cu")
		(net "P1V8_E")
	)
	(segment
		(start 24.08428 -87.4268)
		(end 24.08428 -85.907372)
		(width 0.3556)
		(layer "F.Cu")
		(net "P1V8_E")
	)
	(segment
		(start 115.50015 -75.50023)
		(end 116.000022 -76.000102)
		(width 0.4572)
		(layer "F.Cu")
		(net "P1V8_E")
	)
	(segment
		(start 108.49991 -77.500226)
		(end 108.000038 -78.000098)
		(width 0.4572)
		(layer "F.Cu")
		(net "P1V8_E")
	)
	(segment
		(start 108.6358 -87.3887)
		(end 108.6358 -87.843868)
		(width 0.508)
		(layer "F.Cu")
		(net "P1V8_E")
	)
	(segment
		(start 88.011 -76.835)
		(end 91.313 -76.835)
		(width 0.508)
		(layer "F.Cu")
		(net "P1V8_E")
	)
	(segment
		(start 113.6142 -87.7951)
		(end 113.0681 -88.3412)
		(width 0.508)
		(layer "F.Cu")
		(net "P1V8_E")
	)
	(segment
		(start 7.9883 -85.8012)
		(end 7.9883 -84.8487)
		(width 0.508)
		(layer "F.Cu")
		(net "P1V8_E")
	)
	(segment
		(start 54.5338 -81.3308)
		(end 54.5338 -80.5815)
		(width 0.508)
		(layer "F.Cu")
		(net "P1V8_E")
	)
	(segment
		(start 54.5338 -80.5815)
		(end 54.4703 -80.518)
		(width 0.508)
		(layer "F.Cu")
		(net "P1V8_E")
	)
	(segment
		(start 160.166812 -91.849956)
		(end 160.166812 -92.563696)
		(width 0.508)
		(layer "F.Cu")
		(net "P1V8_E")
	)
	(segment
		(start 95.105728 -80.264508)
		(end 94.255336 -79.414116)
		(width 0.508)
		(layer "F.Cu")
		(net "P1V8_E")
	)
	(segment
		(start 112.499902 -71.500238)
		(end 112.00003 -72.00011)
		(width 0.4572)
		(layer "F.Cu")
		(net "P1V8_E")
	)
	(segment
		(start 131.572 -90.6526)
		(end 130.985514 -91.239086)
		(width 0.508)
		(layer "F.Cu")
		(net "P1V8_E")
	)
	(segment
		(start 74.0283 -81.7118)
		(end 74.0283 -81.9277)
		(width 0.508)
		(layer "F.Cu")
		(net "P1V8_E")
	)
	(segment
		(start 94.255336 -79.414116)
		(end 92.653358 -79.414116)
		(width 0.508)
		(layer "F.Cu")
		(net "P1V8_E")
	)
	(segment
		(start 116.500148 -71.500238)
		(end 117.00002 -72.00011)
		(width 0.4572)
		(layer "F.Cu")
		(net "P1V8_E")
	)
	(segment
		(start 104.7496 -87.333836)
		(end 104.7496 -88.17102)
		(width 0.508)
		(layer "F.Cu")
		(net "P1V8_E")
	)
	(segment
		(start 131.572 -90.1446)
		(end 131.572 -90.6526)
		(width 0.508)
		(layer "F.Cu")
		(net "P1V8_E")
	)
	(segment
		(start 112.499902 -79.500222)
		(end 112.00003 -80.000094)
		(width 0.4572)
		(layer "F.Cu")
		(net "P1V8_E")
	)
	(segment
		(start 152.561036 -92.148914)
		(end 152.813512 -92.40139)
		(width 0.3048)
		(layer "F.Cu")
		(net "P1V8_E")
	)
	(segment
		(start 114.499898 -71.500238)
		(end 114.000026 -72.00011)
		(width 0.4572)
		(layer "F.Cu")
		(net "P1V8_E")
	)
	(segment
		(start 117.500146 -75.50023)
		(end 117.000274 -75.000358)
		(width 0.4572)
		(layer "F.Cu")
		(net "P1V8_E")
	)
	(segment
		(start 58.8899 -80.4926)
		(end 59.007248 -80.375252)
		(width 0.3556)
		(layer "F.Cu")
		(net "P1V8_E")
	)
	(segment
		(start 122.500136 -79.500222)
		(end 123.000008 -80.000094)
		(width 0.4572)
		(layer "F.Cu")
		(net "P1V8_E")
	)
	(segment
		(start 108.49991 -64.499998)
		(end 109.000036 -65.000124)
		(width 0.4572)
		(layer "F.Cu")
		(net "P1V8_E")
	)
	(segment
		(start 13.3223 -85.7504)
		(end 13.3223 -84.7979)
		(width 0.508)
		(layer "F.Cu")
		(net "P1V8_E")
	)
	(segment
		(start 150.950168 -92.021914)
		(end 151.077168 -92.148914)
		(width 0.508)
		(layer "F.Cu")
		(net "P1V8_E")
	)
	(segment
		(start 87.376 -80.264)
		(end 87.376 -78.695042)
		(width 0.508)
		(layer "F.Cu")
		(net "P1V8_E")
	)
	(segment
		(start 114.000026 -72.00011)
		(end 113.4999 -72.500236)
		(width 0.4572)
		(layer "F.Cu")
		(net "P1V8_E")
	)
	(segment
		(start 91.313 -76.835)
		(end 91.4908 -77.0128)
		(width 0.508)
		(layer "F.Cu")
		(net "P1V8_E")
	)
	(segment
		(start 135.975344 -85.614256)
		(end 135.975344 -85.159088)
		(width 0.508)
		(layer "F.Cu")
		(net "P1V8_E")
	)
	(segment
		(start 101.499924 -58.50001)
		(end 101.000052 -58.000138)
		(width 0.4572)
		(layer "F.Cu")
		(net "P1V8_E")
	)
	(segment
		(start 152.363678 -98.161094)
		(end 152.438862 -98.08591)
		(width 0.3048)
		(layer "F.Cu")
		(net "P1V8_E")
	)
	(segment
		(start 114.499898 -79.500222)
		(end 114.000026 -80.000094)
		(width 0.4572)
		(layer "F.Cu")
		(net "P1V8_E")
	)
	(segment
		(start 139.01801 -85.150452)
		(end 139.01801 -85.925152)
		(width 0.508)
		(layer "F.Cu")
		(net "P1V8_E")
	)
	(segment
		(start 68.48221 -80.556354)
		(end 68.599558 -80.439006)
		(width 0.3556)
		(layer "F.Cu")
		(net "P1V8_E")
	)
	(segment
		(start 137.595356 -85.154262)
		(end 137.595356 -85.467444)
		(width 0.508)
		(layer "F.Cu")
		(net "P1V8_E")
	)
	(segment
		(start 104.7496 -88.17102)
		(end 104.744774 -88.175846)
		(width 0.508)
		(layer "F.Cu")
		(net "P1V8_E")
	)
	(segment
		(start 120.4341 -89.1032)
		(end 120.4341 -88.9)
		(width 0.508)
		(layer "F.Cu")
		(net "P1V8_E")
	)
	(segment
		(start 92.62237 -70.993)
		(end 90.930984 -69.301614)
		(width 0.508)
		(layer "F.Cu")
		(net "P1V8_E")
	)
	(segment
		(start 119.963184 -87.4395)
		(end 121.031 -87.4395)
		(width 0.508)
		(layer "F.Cu")
		(net "P1V8_E")
	)
	(segment
		(start 126.500128 -79.500222)
		(end 127 -79.00035)
		(width 0.4572)
		(layer "F.Cu")
		(net "P1V8_E")
	)
	(segment
		(start 105.877614 -88.166956)
		(end 105.872788 -88.171782)
		(width 0.508)
		(layer "F.Cu")
		(net "P1V8_E")
	)
	(segment
		(start 73.8505 -82.1055)
		(end 73.8505 -82.55)
		(width 0.508)
		(layer "F.Cu")
		(net "P1V8_E")
	)
	(segment
		(start 63.66637 -80.400398)
		(end 63.66637 -79.112618)
		(width 0.3556)
		(layer "F.Cu")
		(net "P1V8_E")
	)
	(segment
		(start 18.72615 -85.95995)
		(end 18.8341 -85.852)
		(width 0.3556)
		(layer "F.Cu")
		(net "P1V8_E")
	)
	(segment
		(start 152.813512 -92.40139)
		(end 153.67508 -92.40139)
		(width 0.3048)
		(layer "F.Cu")
		(net "P1V8_E")
	)
	(segment
		(start 124.500132 -79.500222)
		(end 125.000004 -80.000094)
		(width 0.4572)
		(layer "F.Cu")
		(net "P1V8_E")
	)
	(segment
		(start 101.6762 -86.4362)
		(end 100.838 -85.598)
		(width 0.508)
		(layer "F.Cu")
		(net "P1V8_E")
	)
	(segment
		(start 92.1385 -77.0128)
		(end 92.1385 -75.9968)
		(width 0.508)
		(layer "F.Cu")
		(net "P1V8_E")
	)
	(segment
		(start 137.595356 -85.467444)
		(end 137.1346 -85.9282)
		(width 0.508)
		(layer "F.Cu")
		(net "P1V8_E")
	)
	(segment
		(start 97.536 -86.614)
		(end 97.536 -86.0044)
		(width 0.508)
		(layer "F.Cu")
		(net "P1V8_E")
	)
	(segment
		(start 106.499914 -79.500222)
		(end 106.000042 -80.000094)
		(width 0.4572)
		(layer "F.Cu")
		(net "P1V8_E")
	)
	(segment
		(start 18.8341 -85.852)
		(end 18.8341 -84.8995)
		(width 0.508)
		(layer "F.Cu")
		(net "P1V8_E")
	)
	(segment
		(start 113.4999 -75.50023)
		(end 113.000028 -76.000102)
		(width 0.4572)
		(layer "F.Cu")
		(net "P1V8_E")
	)
	(segment
		(start 130.556 -91.239086)
		(end 130.556 -90.1827)
		(width 0.508)
		(layer "F.Cu")
		(net "P1V8_E")
	)
	(segment
		(start 133.604762 -89.17051)
		(end 133.461252 -89.027)
		(width 0.508)
		(layer "F.Cu")
		(net "P1V8_E")
	)
	(segment
		(start 95.287592 -85.644736)
		(end 95.287592 -84.509864)
		(width 0.508)
		(layer "F.Cu")
		(net "P1V8_E")
	)
	(segment
		(start 151.077168 -92.148914)
		(end 151.930608 -92.148914)
		(width 0.508)
		(layer "F.Cu")
		(net "P1V8_E")
	)
	(segment
		(start 151.897842 -97.302574)
		(end 151.897842 -98.161094)
		(width 0.508)
		(layer "F.Cu")
		(net "P1V8_E")
	)
	(segment
		(start 132.588 -90.1446)
		(end 131.572 -90.1446)
		(width 0.508)
		(layer "F.Cu")
		(net "P1V8_E")
	)
	(segment
		(start 104.499918 -61.500004)
		(end 104.000046 -61.000132)
		(width 0.4572)
		(layer "F.Cu")
		(net "P1V8_E")
	)
	(segment
		(start 123.500134 -75.50023)
		(end 124.000006 -76.000102)
		(width 0.4572)
		(layer "F.Cu")
		(net "P1V8_E")
	)
	(segment
		(start 115.50015 -72.500236)
		(end 116.000022 -73.000108)
		(width 0.4572)
		(layer "F.Cu")
		(net "P1V8_E")
	)
	(via
		(at 133.461252 -89.027)
		(size 0.508)
		(drill 0.254)
		(layers "F.Cu" "B.Cu")
		(net "P1V8_E")
	)
	(via
		(at 117.4623 -91.17584)
		(size 0.508)
		(drill 0.254)
		(layers "F.Cu" "B.Cu")
		(net "P1V8_E")
	)
	(via
		(at 116.962936 -89.142062)
		(size 0.6096)
		(drill 0.3048)
		(layers "F.Cu" "B.Cu")
		(net "P1V8_E")
	)
	(via
		(at 127 -79.00035)
		(size 0.4572)
		(drill 0.2032)
		(layers "F.Cu" "B.Cu")
		(net "P1V8_E")
	)
	(via
		(at 150.950168 -92.021914)
		(size 0.508)
		(drill 0.254)
		(layers "F.Cu" "B.Cu")
		(net "P1V8_E")
	)
	(via
		(at 73.8505 -82.55)
		(size 0.508)
		(drill 0.254)
		(layers "F.Cu" "B.Cu")
		(net "P1V8_E")
	)
	(via
		(at 117.000274 -75.000358)
		(size 0.4572)
		(drill 0.2032)
		(layers "F.Cu" "B.Cu")
		(net "P1V8_E")
	)
	(via
		(at 112.014 -88.3412)
		(size 0.508)
		(drill 0.254)
		(layers "F.Cu" "B.Cu")
		(net "P1V8_E")
	)
	(via
		(at 138.99515 -90.931238)
		(size 0.508)
		(drill 0.254)
		(layers "F.Cu" "B.Cu")
		(net "P1V8_E")
	)
	(via
		(at 121.031 -88.3031)
		(size 0.508)
		(drill 0.254)
		(layers "F.Cu" "B.Cu")
		(net "P1V8_E")
	)
	(via
		(at 7.9883 -84.8487)
		(size 0.508)
		(drill 0.254)
		(layers "F.Cu" "B.Cu")
		(net "P1V8_E")
	)
	(via
		(at 166.7002 -5.1054)
		(size 0.508)
		(drill 0.254)
		(layers "F.Cu" "B.Cu")
		(net "P1V8_E")
	)
	(via
		(at 123.000008 -80.000094)
		(size 0.4572)
		(drill 0.2032)
		(layers "F.Cu" "B.Cu")
		(net "P1V8_E")
	)
	(via
		(at 105.000044 -83.000088)
		(size 0.4572)
		(drill 0.2032)
		(layers "F.Cu" "B.Cu")
		(net "P1V8_E")
	)
	(via
		(at 68.41871 -81.369154)
		(size 0.508)
		(drill 0.254)
		(layers "F.Cu" "B.Cu")
		(net "P1V8_E")
	)
	(via
		(at 65.940686 -13.21435)
		(size 0.6604)
		(drill 0.3302)
		(layers "F.Cu" "B.Cu")
		(net "P1V8_E")
	)
	(via
		(at 87.498936 -67.328288)
		(size 0.6096)
		(drill 0.3048)
		(layers "F.Cu" "B.Cu")
		(net "P1V8_E")
	)
	(via
		(at 146.506438 -28.924758)
		(size 0.7112)
		(drill 0.4064)
		(layers "F.Cu" "B.Cu")
		(net "P1V8_E")
	)
	(via
		(at 134.496048 -89.412064)
		(size 0.6096)
		(drill 0.3048)
		(layers "F.Cu" "B.Cu")
		(net "P1V8_E")
	)
	(via
		(at 139.034266 -85.941408)
		(size 0.508)
		(drill 0.254)
		(layers "F.Cu" "B.Cu")
		(net "P1V8_E")
	)
	(via
		(at 124.000006 -76.000102)
		(size 0.4572)
		(drill 0.2032)
		(layers "F.Cu" "B.Cu")
		(net "P1V8_E")
	)
	(via
		(at 66.420746 -14.059662)
		(size 0.508)
		(drill 0.254)
		(layers "F.Cu" "B.Cu")
		(net "P1V8_E")
	)
	(via
		(at 104.000046 -63.000128)
		(size 0.4572)
		(drill 0.2032)
		(layers "F.Cu" "B.Cu")
		(net "P1V8_E")
	)
	(via
		(at 18.8341 -84.8995)
		(size 0.508)
		(drill 0.254)
		(layers "F.Cu" "B.Cu")
		(net "P1V8_E")
	)
	(via
		(at 101.000052 -60.000134)
		(size 0.4572)
		(drill 0.2032)
		(layers "F.Cu" "B.Cu")
		(net "P1V8_E")
	)
	(via
		(at 107.999784 -61.000132)
		(size 0.4572)
		(drill 0.2032)
		(layers "F.Cu" "B.Cu")
		(net "P1V8_E")
	)
	(via
		(at 131.191 -79.502)
		(size 0.4572)
		(drill 0.2032)
		(layers "F.Cu" "B.Cu")
		(net "P1V8_E")
	)
	(via
		(at 117.00002 -72.00011)
		(size 0.4572)
		(drill 0.2032)
		(layers "F.Cu" "B.Cu")
		(net "P1V8_E")
	)
	(via
		(at 108.321856 -88.157812)
		(size 0.508)
		(drill 0.254)
		(layers "F.Cu" "B.Cu")
		(net "P1V8_E")
	)
	(via
		(at 114.9604 -84.5058)
		(size 0.508)
		(drill 0.254)
		(layers "F.Cu" "B.Cu")
		(net "P1V8_E")
	)
	(via
		(at 121.000012 -80.000094)
		(size 0.4572)
		(drill 0.2032)
		(layers "F.Cu" "B.Cu")
		(net "P1V8_E")
	)
	(via
		(at 108.000038 -78.000098)
		(size 0.4572)
		(drill 0.2032)
		(layers "F.Cu" "B.Cu")
		(net "P1V8_E")
	)
	(via
		(at 130.556 -91.239086)
		(size 0.508)
		(drill 0.254)
		(layers "F.Cu" "B.Cu")
		(net "P1V8_E")
	)
	(via
		(at 137.1346 -85.9282)
		(size 0.508)
		(drill 0.254)
		(layers "F.Cu" "B.Cu")
		(net "P1V8_E")
	)
	(via
		(at 126.6698 -91.239086)
		(size 0.508)
		(drill 0.254)
		(layers "F.Cu" "B.Cu")
		(net "P1V8_E")
	)
	(via
		(at 112.00003 -80.000094)
		(size 0.4572)
		(drill 0.2032)
		(layers "F.Cu" "B.Cu")
		(net "P1V8_E")
	)
	(via
		(at 112.00003 -72.00011)
		(size 0.4572)
		(drill 0.2032)
		(layers "F.Cu" "B.Cu")
		(net "P1V8_E")
	)
	(via
		(at 114.000026 -80.000094)
		(size 0.4572)
		(drill 0.2032)
		(layers "F.Cu" "B.Cu")
		(net "P1V8_E")
	)
	(via
		(at 141.147038 -90.56751)
		(size 0.508)
		(drill 0.254)
		(layers "F.Cu" "B.Cu")
		(net "P1V8_E")
	)
	(via
		(at 105.872788 -88.171782)
		(size 0.508)
		(drill 0.254)
		(layers "F.Cu" "B.Cu")
		(net "P1V8_E")
	)
	(via
		(at 106.000042 -80.000094)
		(size 0.4572)
		(drill 0.2032)
		(layers "F.Cu" "B.Cu")
		(net "P1V8_E")
	)
	(via
		(at 110.000034 -72.00011)
		(size 0.4572)
		(drill 0.2032)
		(layers "F.Cu" "B.Cu")
		(net "P1V8_E")
	)
	(via
		(at 119.000016 -80.000094)
		(size 0.4572)
		(drill 0.2032)
		(layers "F.Cu" "B.Cu")
		(net "P1V8_E")
	)
	(via
		(at 101.000052 -58.000138)
		(size 0.4572)
		(drill 0.2032)
		(layers "F.Cu" "B.Cu")
		(net "P1V8_E")
	)
	(via
		(at 87.376 -80.264)
		(size 0.508)
		(drill 0.254)
		(layers "F.Cu" "B.Cu")
		(net "P1V8_E")
	)
	(via
		(at 97.1804 -85.6488)
		(size 0.508)
		(drill 0.254)
		(layers "F.Cu" "B.Cu")
		(net "P1V8_E")
	)
	(via
		(at 128.999996 -80.000094)
		(size 0.4572)
		(drill 0.2032)
		(layers "F.Cu" "B.Cu")
		(net "P1V8_E")
	)
	(via
		(at 95.287592 -85.644736)
		(size 0.508)
		(drill 0.254)
		(layers "F.Cu" "B.Cu")
		(net "P1V8_E")
	)
	(via
		(at 109.000036 -65.000124)
		(size 0.4572)
		(drill 0.2032)
		(layers "F.Cu" "B.Cu")
		(net "P1V8_E")
	)
	(via
		(at 174.879 -123.0376)
		(size 0.7112)
		(drill 0.4064)
		(layers "F.Cu" "B.Cu")
		(net "P1V8_E")
	)
	(via
		(at 149.9489 -82.044794)
		(size 0.508)
		(drill 0.254)
		(layers "F.Cu" "B.Cu")
		(net "P1V8_E")
	)
	(via
		(at 13.3223 -84.7979)
		(size 0.508)
		(drill 0.254)
		(layers "F.Cu" "B.Cu")
		(net "P1V8_E")
	)
	(via
		(at 122.00001 -76.000102)
		(size 0.4572)
		(drill 0.2032)
		(layers "F.Cu" "B.Cu")
		(net "P1V8_E")
	)
	(via
		(at 161.9377 -98.8187)
		(size 0.7112)
		(drill 0.4064)
		(layers "F.Cu" "B.Cu")
		(net "P1V8_E")
	)
	(via
		(at 125.2728 -91.1352)
		(size 0.508)
		(drill 0.254)
		(layers "F.Cu" "B.Cu")
		(net "P1V8_E")
	)
	(via
		(at 136.70915 -90.931238)
		(size 0.508)
		(drill 0.254)
		(layers "F.Cu" "B.Cu")
		(net "P1V8_E")
	)
	(via
		(at 110.49 -88.3412)
		(size 0.508)
		(drill 0.254)
		(layers "F.Cu" "B.Cu")
		(net "P1V8_E")
	)
	(via
		(at 117.00002 -80.000094)
		(size 0.4572)
		(drill 0.2032)
		(layers "F.Cu" "B.Cu")
		(net "P1V8_E")
	)
	(via
		(at 167.767 -6.2484)
		(size 0.6604)
		(drill 0.3302)
		(layers "F.Cu" "B.Cu")
		(net "P1V8_E")
	)
	(via
		(at 65.404746 -14.059662)
		(size 0.508)
		(drill 0.254)
		(layers "F.Cu" "B.Cu")
		(net "P1V8_E")
	)
	(via
		(at 95.105728 -80.264508)
		(size 0.4572)
		(drill 0.2032)
		(layers "F.Cu" "B.Cu")
		(net "P1V8_E")
	)
	(via
		(at 113.000028 -73.000108)
		(size 0.4572)
		(drill 0.2032)
		(layers "F.Cu" "B.Cu")
		(net "P1V8_E")
	)
	(via
		(at 119.000016 -72.00011)
		(size 0.4572)
		(drill 0.2032)
		(layers "F.Cu" "B.Cu")
		(net "P1V8_E")
	)
	(via
		(at 120.000014 -76.000102)
		(size 0.4572)
		(drill 0.2032)
		(layers "F.Cu" "B.Cu")
		(net "P1V8_E")
	)
	(via
		(at 100.838 -85.598)
		(size 0.508)
		(drill 0.254)
		(layers "F.Cu" "B.Cu")
		(net "P1V8_E")
	)
	(via
		(at 104.000046 -61.000132)
		(size 0.4572)
		(drill 0.2032)
		(layers "F.Cu" "B.Cu")
		(net "P1V8_E")
	)
	(via
		(at 110.000034 -78.000098)
		(size 0.4572)
		(drill 0.2032)
		(layers "F.Cu" "B.Cu")
		(net "P1V8_E")
	)
	(via
		(at 88.011 -76.835)
		(size 0.508)
		(drill 0.254)
		(layers "F.Cu" "B.Cu")
		(net "P1V8_E")
	)
	(via
		(at 123.2154 -92.3036)
		(size 0.508)
		(drill 0.254)
		(layers "F.Cu" "B.Cu")
		(net "P1V8_E")
	)
	(via
		(at 120.3706 -94.4372)
		(size 0.508)
		(drill 0.254)
		(layers "F.Cu" "B.Cu")
		(net "P1V8_E")
	)
	(via
		(at 167.6908 -5.1308)
		(size 0.508)
		(drill 0.254)
		(layers "F.Cu" "B.Cu")
		(net "P1V8_E")
	)
	(via
		(at 131.607052 -88.4809)
		(size 0.508)
		(drill 0.254)
		(layers "F.Cu" "B.Cu")
		(net "P1V8_E")
	)
	(via
		(at 174.879 -124.1044)
		(size 0.7112)
		(drill 0.4064)
		(layers "F.Cu" "B.Cu")
		(net "P1V8_E")
	)
	(via
		(at 90.930984 -69.301614)
		(size 0.508)
		(drill 0.254)
		(layers "F.Cu" "B.Cu")
		(net "P1V8_E")
	)
	(via
		(at 24.19223 -84.846922)
		(size 0.508)
		(drill 0.254)
		(layers "F.Cu" "B.Cu")
		(net "P1V8_E")
	)
	(via
		(at 87.201756 -69.241416)
		(size 0.6096)
		(drill 0.3048)
		(layers "F.Cu" "B.Cu")
		(net "P1V8_E")
	)
	(via
		(at 110.109 -85.725)
		(size 0.508)
		(drill 0.254)
		(layers "F.Cu" "B.Cu")
		(net "P1V8_E")
	)
	(via
		(at 121.000266 -73.000108)
		(size 0.4572)
		(drill 0.2032)
		(layers "F.Cu" "B.Cu")
		(net "P1V8_E")
	)
	(via
		(at 108.000038 -73.000108)
		(size 0.4572)
		(drill 0.2032)
		(layers "F.Cu" "B.Cu")
		(net "P1V8_E")
	)
	(via
		(at 135.636 -85.9536)
		(size 0.508)
		(drill 0.254)
		(layers "F.Cu" "B.Cu")
		(net "P1V8_E")
	)
	(via
		(at 75.730608 -99.057968)
		(size 0.6096)
		(drill 0.3048)
		(layers "F.Cu" "B.Cu")
		(net "P1V8_E")
	)
	(via
		(at 87.1474 -71.4502)
		(size 0.508)
		(drill 0.254)
		(layers "F.Cu" "B.Cu")
		(net "P1V8_E")
	)
	(via
		(at 88.1126 -71.4502)
		(size 0.508)
		(drill 0.254)
		(layers "F.Cu" "B.Cu")
		(net "P1V8_E")
	)
	(via
		(at 130.591052 -88.519)
		(size 0.508)
		(drill 0.254)
		(layers "F.Cu" "B.Cu")
		(net "P1V8_E")
	)
	(via
		(at 158.75 -91.8718)
		(size 0.508)
		(drill 0.254)
		(layers "F.Cu" "B.Cu")
		(net "P1V8_E")
	)
	(via
		(at 114.000026 -72.00011)
		(size 0.4572)
		(drill 0.2032)
		(layers "F.Cu" "B.Cu")
		(net "P1V8_E")
	)
	(via
		(at 54.5338 -81.3308)
		(size 0.508)
		(drill 0.254)
		(layers "F.Cu" "B.Cu")
		(net "P1V8_E")
	)
	(via
		(at 101.000052 -62.00013)
		(size 0.4572)
		(drill 0.2032)
		(layers "F.Cu" "B.Cu")
		(net "P1V8_E")
	)
	(via
		(at 125.000004 -80.000094)
		(size 0.4572)
		(drill 0.2032)
		(layers "F.Cu" "B.Cu")
		(net "P1V8_E")
	)
	(via
		(at 119.00027 -73.000108)
		(size 0.4572)
		(drill 0.2032)
		(layers "F.Cu" "B.Cu")
		(net "P1V8_E")
	)
	(via
		(at 113.000028 -76.000102)
		(size 0.4572)
		(drill 0.2032)
		(layers "F.Cu" "B.Cu")
		(net "P1V8_E")
	)
	(via
		(at 128.5748 -91.137486)
		(size 0.508)
		(drill 0.254)
		(layers "F.Cu" "B.Cu")
		(net "P1V8_E")
	)
	(via
		(at 151.897842 -97.302574)
		(size 0.508)
		(drill 0.254)
		(layers "F.Cu" "B.Cu")
		(net "P1V8_E")
	)
	(via
		(at 58.8518 -81.3054)
		(size 0.508)
		(drill 0.254)
		(layers "F.Cu" "B.Cu")
		(net "P1V8_E")
	)
	(via
		(at 165.757098 -5.461)
		(size 0.6096)
		(drill 0.3048)
		(layers "F.Cu" "B.Cu")
		(net "P1V8_E")
	)
	(via
		(at 116.000022 -73.000108)
		(size 0.4572)
		(drill 0.2032)
		(layers "F.Cu" "B.Cu")
		(net "P1V8_E")
	)
	(via
		(at 104.744774 -88.175846)
		(size 0.508)
		(drill 0.254)
		(layers "F.Cu" "B.Cu")
		(net "P1V8_E")
	)
	(via
		(at 126.527052 -88.519)
		(size 0.508)
		(drill 0.254)
		(layers "F.Cu" "B.Cu")
		(net "P1V8_E")
	)
	(via
		(at 71.175118 -89.135458)
		(size 0.508)
		(drill 0.254)
		(layers "F.Cu" "B.Cu")
		(net "P1V8_E")
	)
	(via
		(at 63.44285 -81.322418)
		(size 0.508)
		(drill 0.254)
		(layers "F.Cu" "B.Cu")
		(net "P1V8_E")
	)
	(via
		(at 71.3232 -82.55)
		(size 0.508)
		(drill 0.254)
		(layers "F.Cu" "B.Cu")
		(net "P1V8_E")
	)
	(via
		(at 160.5661 -98.8314)
		(size 0.7112)
		(drill 0.4064)
		(layers "F.Cu" "B.Cu")
		(net "P1V8_E")
	)
	(via
		(at 116.000022 -76.000102)
		(size 0.4572)
		(drill 0.2032)
		(layers "F.Cu" "B.Cu")
		(net "P1V8_E")
	)
	(via
		(at 104.000046 -59.000136)
		(size 0.4572)
		(drill 0.2032)
		(layers "F.Cu" "B.Cu")
		(net "P1V8_E")
	)
	(segment
		(start 140.716 -90.136472)
		(end 141.147038 -90.56751)
		(width 0.508)
		(layer "B.Cu")
		(net "P1V8_E")
	)
	(segment
		(start 129.8956 -80.6196)
		(end 129.276094 -80.000094)
		(width 0.3048)
		(layer "B.Cu")
		(net "P1V8_E")
	)
	(segment
		(start 125.001528 -75.380342)
		(end 124.619766 -75.380342)
		(width 0.508)
		(layer "B.Cu")
		(net "P1V8_E")
	)
	(segment
		(start 125.2728 -91.1352)
		(end 125.806962 -91.1352)
		(width 0.508)
		(layer "B.Cu")
		(net "P1V8_E")
	)
	(segment
		(start 123.274582 -80.274668)
		(end 123.000008 -80.000094)
		(width 0.3048)
		(layer "B.Cu")
		(net "P1V8_E")
	)
	(segment
		(start 100.8126 -58.4962)
		(end 100.8126 -58.18759)
		(width 0.3048)
		(layer "B.Cu")
		(net "P1V8_E")
	)
	(segment
		(start 123.2154 -92.3036)
		(end 122.3899 -92.3036)
		(width 0.508)
		(layer "B.Cu")
		(net "P1V8_E")
	)
	(segment
		(start 134.606538 -85.381338)
		(end 135.1788 -85.9536)
		(width 0.508)
		(layer "B.Cu")
		(net "P1V8_E")
	)
	(segment
		(start 106.0196 -88.02497)
		(end 106.0196 -87.3887)
		(width 0.508)
		(layer "B.Cu")
		(net "P1V8_E")
	)
	(segment
		(start 97.1804 -85.011006)
		(end 96.703134 -84.53374)
		(width 0.508)
		(layer "B.Cu")
		(net "P1V8_E")
	)
	(segment
		(start 130.7084 -79.0194)
		(end 131.191 -79.502)
		(width 0.3048)
		(layer "B.Cu")
		(net "P1V8_E")
	)
	(segment
		(start 121.56313 -87.10041)
		(end 121.568972 -87.094568)
		(width 0.508)
		(layer "B.Cu")
		(net "P1V8_E")
	)
	(segment
		(start 141.732 -89.982548)
		(end 141.147038 -90.56751)
		(width 0.508)
		(layer "B.Cu")
		(net "P1V8_E")
	)
	(segment
		(start 108.8136 -64.813688)
		(end 109.000036 -65.000124)
		(width 0.254)
		(layer "B.Cu")
		(net "P1V8_E")
	)
	(segment
		(start 116.760244 -80.23987)
		(end 117.00002 -80.000094)
		(width 0.3048)
		(layer "B.Cu")
		(net "P1V8_E")
	)
	(segment
		(start 125.806962 -91.1352)
		(end 126.0094 -90.932762)
		(width 0.508)
		(layer "B.Cu")
		(net "P1V8_E")
	)
	(segment
		(start 121.2596 -89.1159)
		(end 121.2596 -88.5317)
		(width 0.508)
		(layer "B.Cu")
		(net "P1V8_E")
	)
	(segment
		(start 126.0094 -90.932762)
		(end 126.0094 -90.2589)
		(width 0.508)
		(layer "B.Cu")
		(net "P1V8_E")
	)
	(segment
		(start 104.397302 -88.175846)
		(end 103.9114 -87.689944)
		(width 0.508)
		(layer "B.Cu")
		(net "P1V8_E")
	)
	(segment
		(start 121.568972 -87.765128)
		(end 121.031 -88.3031)
		(width 0.508)
		(layer "B.Cu")
		(net "P1V8_E")
	)
	(segment
		(start 103.886 -63.7286)
		(end 103.886 -63.114174)
		(width 0.3048)
		(layer "B.Cu")
		(net "P1V8_E")
	)
	(segment
		(start 95.727774 -82.832702)
		(end 94.151958 -82.832702)
		(width 0.381)
		(layer "B.Cu")
		(net "P1V8_E")
	)
	(segment
		(start 71.175118 -96.0755)
		(end 74.157586 -99.057968)
		(width 0.508)
		(layer "B.Cu")
		(net "P1V8_E")
	)
	(segment
		(start 119.25046 -73.250298)
		(end 119.25046 -74.160888)
		(width 0.508)
		(layer "B.Cu")
		(net "P1V8_E")
	)
	(segment
		(start 121.568972 -87.094568)
		(end 121.568972 -87.765128)
		(width 0.508)
		(layer "B.Cu")
		(net "P1V8_E")
	)
	(segment
		(start 96.703134 -83.808062)
		(end 95.727774 -82.832702)
		(width 0.381)
		(layer "B.Cu")
		(net "P1V8_E")
	)
	(segment
		(start 139.034266 -85.270594)
		(end 139.034266 -85.941408)
		(width 0.508)
		(layer "B.Cu")
		(net "P1V8_E")
	)
	(segment
		(start 74.157586 -99.057968)
		(end 75.730608 -99.057968)
		(width 0.508)
		(layer "B.Cu")
		(net "P1V8_E")
	)
	(segment
		(start 108.247942 -61.463174)
		(end 107.999784 -61.215016)
		(width 0.3048)
		(layer "B.Cu")
		(net "P1V8_E")
	)
	(segment
		(start 110.03153 -85.80247)
		(end 110.03153 -86.50097)
		(width 0.508)
		(layer "B.Cu")
		(net "P1V8_E")
	)
	(segment
		(start 100.8126 -58.18759)
		(end 101.000052 -58.000138)
		(width 0.3048)
		(layer "B.Cu")
		(net "P1V8_E")
	)
	(segment
		(start 122.3899 -92.3036)
		(end 122.3899 -91.551506)
		(width 0.508)
		(layer "B.Cu")
		(net "P1V8_E")
	)
	(segment
		(start 95.918782 -79.98333)
		(end 95.386906 -79.98333)
		(width 0.508)
		(layer "B.Cu")
		(net "P1V8_E")
	)
	(segment
		(start 100.838 -85.598)
		(end 100.838 -86.2711)
		(width 0.508)
		(layer "B.Cu")
		(net "P1V8_E")
	)
	(segment
		(start 66.487548 -14.126464)
		(end 66.487548 -15.142972)
		(width 0.508)
		(layer "B.Cu")
		(net "P1V8_E")
	)
	(segment
		(start 94.151958 -82.832702)
		(end 93.6244 -82.305144)
		(width 0.381)
		(layer "B.Cu")
		(net "P1V8_E")
	)
	(segment
		(start 136.1948 -90.1319)
		(end 136.1948 -90.416888)
		(width 0.508)
		(layer "B.Cu")
		(net "P1V8_E")
	)
	(segment
		(start 116.501418 -80.23987)
		(end 116.760244 -80.23987)
		(width 0.3048)
		(layer "B.Cu")
		(net "P1V8_E")
	)
	(segment
		(start 126.99492 -78.6892)
		(end 127 -78.6892)
		(width 0.3048)
		(layer "B.Cu")
		(net "P1V8_E")
	)
	(segment
		(start 105.0036 -87.91702)
		(end 105.0036 -87.3887)
		(width 0.508)
		(layer "B.Cu")
		(net "P1V8_E")
	)
	(segment
		(start 71.3232 -74.1553)
		(end 71.882 -73.5965)
		(width 0.508)
		(layer "B.Cu")
		(net "P1V8_E")
	)
	(segment
		(start 130.7084 -78.74)
		(end 130.7084 -79.0194)
		(width 0.3048)
		(layer "B.Cu")
		(net "P1V8_E")
	)
	(segment
		(start 138.4808 -90.1319)
		(end 138.4808 -90.416888)
		(width 0.508)
		(layer "B.Cu")
		(net "P1V8_E")
	)
	(segment
		(start 113.174272 -75.825858)
		(end 113.000028 -76.000102)
		(width 0.3048)
		(layer "B.Cu")
		(net "P1V8_E")
	)
	(segment
		(start 71.3232 -82.55)
		(end 71.3232 -74.1553)
		(width 0.508)
		(layer "B.Cu")
		(net "P1V8_E")
	)
	(segment
		(start 71.175118 -89.135458)
		(end 71.175118 -96.0755)
		(width 0.508)
		(layer "B.Cu")
		(net "P1V8_E")
	)
	(segment
		(start 114.5794 -80.1878)
		(end 114.187732 -80.1878)
		(width 0.3048)
		(layer "B.Cu")
		(net "P1V8_E")
	)
	(segment
		(start 86.9061 -74.2315)
		(end 86.9061 -73.5584)
		(width 0.3048)
		(layer "B.Cu")
		(net "P1V8_E")
	)
	(segment
		(start 103.505 -60.7822)
		(end 103.782114 -60.7822)
		(width 0.3048)
		(layer "B.Cu")
		(net "P1V8_E")
	)
	(segment
		(start 112.014 -88.3412)
		(end 113.03 -88.3412)
		(width 0.508)
		(layer "B.Cu")
		(net "P1V8_E")
	)
	(segment
		(start 124.619766 -75.380342)
		(end 124.000006 -76.000102)
		(width 0.508)
		(layer "B.Cu")
		(net "P1V8_E")
	)
	(segment
		(start 114.5413 -84.5058)
		(end 114.1476 -84.8995)
		(width 0.3302)
		(layer "B.Cu")
		(net "P1V8_E")
	)
	(segment
		(start 104.173782 -58.8264)
		(end 104.000046 -59.000136)
		(width 0.3048)
		(layer "B.Cu")
		(net "P1V8_E")
	)
	(segment
		(start 108.8136 -65.18656)
		(end 109.000036 -65.000124)
		(width 0.254)
		(layer "B.Cu")
		(net "P1V8_E")
	)
	(segment
		(start 135.1788 -85.9536)
		(end 135.636 -85.9536)
		(width 0.508)
		(layer "B.Cu")
		(net "P1V8_E")
	)
	(segment
		(start 103.9114 -87.689944)
		(end 103.9114 -87.3887)
		(width 0.508)
		(layer "B.Cu")
		(net "P1V8_E")
	)
	(segment
		(start 127 -78.6892)
		(end 127 -79.00035)
		(width 0.3048)
		(layer "B.Cu")
		(net "P1V8_E")
	)
	(segment
		(start 120.52808 -72.5424)
		(end 120.985788 -73.000108)
		(width 0.3048)
		(layer "B.Cu")
		(net "P1V8_E")
	)
	(segment
		(start 137.2108 -90.1319)
		(end 137.2108 -90.429588)
		(width 0.508)
		(layer "B.Cu")
		(net "P1V8_E")
	)
	(segment
		(start 108.8136 -64.516)
		(end 108.8136 -64.813688)
		(width 0.254)
		(layer "B.Cu")
		(net "P1V8_E")
	)
	(segment
		(start 141.732 -89.3445)
		(end 141.732 -89.982548)
		(width 0.508)
		(layer "B.Cu")
		(net "P1V8_E")
	)
	(segment
		(start 97.1804 -85.6488)
		(end 97.1804 -85.011006)
		(width 0.508)
		(layer "B.Cu")
		(net "P1V8_E")
	)
	(segment
		(start 137.603738 -85.14461)
		(end 137.1346 -85.613748)
		(width 0.508)
		(layer "B.Cu")
		(net "P1V8_E")
	)
	(segment
		(start 103.886 -63.114174)
		(end 104.000046 -63.000128)
		(width 0.3048)
		(layer "B.Cu")
		(net "P1V8_E")
	)
	(segment
		(start 100.457 -59.7662)
		(end 100.766118 -59.7662)
		(width 0.3048)
		(layer "B.Cu")
		(net "P1V8_E")
	)
	(segment
		(start 87.26805 -74.59345)
		(end 86.9061 -74.2315)
		(width 0.3048)
		(layer "B.Cu")
		(net "P1V8_E")
	)
	(segment
		(start 120.542558 -87.10041)
		(end 121.56313 -87.10041)
		(width 0.508)
		(layer "B.Cu")
		(net "P1V8_E")
	)
	(segment
		(start 114.187732 -80.1878)
		(end 114.000026 -80.000094)
		(width 0.3048)
		(layer "B.Cu")
		(net "P1V8_E")
	)
	(segment
		(start 139.168632 -85.136228)
		(end 139.034266 -85.270594)
		(width 0.508)
		(layer "B.Cu")
		(net "P1V8_E")
	)
	(segment
		(start 107.999784 -61.215016)
		(end 107.999784 -61.000132)
		(width 0.3048)
		(layer "B.Cu")
		(net "P1V8_E")
	)
	(segment
		(start 108.8136 -65.5066)
		(end 108.8136 -65.18656)
		(width 0.254)
		(layer "B.Cu")
		(net "P1V8_E")
	)
	(segment
		(start 121.5136 -72.5424)
		(end 121.055892 -73.000108)
		(width 0.3048)
		(layer "B.Cu")
		(net "P1V8_E")
	)
	(segment
		(start 139.4968 -90.429588)
		(end 138.99515 -90.931238)
		(width 0.508)
		(layer "B.Cu")
		(net "P1V8_E")
	)
	(segment
		(start 110.5408 -84.8487)
		(end 110.5408 -85.2932)
		(width 0.508)
		(layer "B.Cu")
		(net "P1V8_E")
	)
	(segment
		(start 111.94796 -88.27516)
		(end 112.014 -88.3412)
		(width 0.508)
		(layer "B.Cu")
		(net "P1V8_E")
	)
	(segment
		(start 100.772722 -61.7728)
		(end 101.000052 -62.00013)
		(width 0.3048)
		(layer "B.Cu")
		(net "P1V8_E")
	)
	(segment
		(start 137.1346 -85.613748)
		(end 137.1346 -85.9282)
		(width 0.508)
		(layer "B.Cu")
		(net "P1V8_E")
	)
	(segment
		(start 95.287592 -85.644736)
		(end 95.287592 -86.63178)
		(width 0.508)
		(layer "B.Cu")
		(net "P1V8_E")
	)
	(segment
		(start 113.6142 -87.757)
		(end 113.6142 -87.4649)
		(width 0.508)
		(layer "B.Cu")
		(net "P1V8_E")
	)
	(segment
		(start 139.4968 -90.1319)
		(end 139.4968 -90.429588)
		(width 0.508)
		(layer "B.Cu")
		(net "P1V8_E")
	)
	(segment
		(start 105.872788 -88.171782)
		(end 106.0196 -88.02497)
		(width 0.508)
		(layer "B.Cu")
		(net "P1V8_E")
	)
	(segment
		(start 136.1948 -90.416888)
		(end 136.70915 -90.931238)
		(width 0.508)
		(layer "B.Cu")
		(net "P1V8_E")
	)
	(segment
		(start 140.716 -89.3445)
		(end 140.716 -90.136472)
		(width 0.508)
		(layer "B.Cu")
		(net "P1V8_E")
	)
	(segment
		(start 117.5004 -75.500484)
		(end 117.000274 -75.000358)
		(width 0.3048)
		(layer "B.Cu")
		(net "P1V8_E")
	)
	(segment
		(start 137.2108 -90.429588)
		(end 136.70915 -90.931238)
		(width 0.508)
		(layer "B.Cu")
		(net "P1V8_E")
	)
	(segment
		(start 126.7968 -78.49108)
		(end 126.99492 -78.6892)
		(width 0.3048)
		(layer "B.Cu")
		(net "P1V8_E")
	)
	(segment
		(start 104.744774 -88.175846)
		(end 105.0036 -87.91702)
		(width 0.508)
		(layer "B.Cu")
		(net "P1V8_E")
	)
	(segment
		(start 86.9061 -73.5584)
		(end 86.9061 -72.5932)
		(width 0.508)
		(layer "B.Cu")
		(net "P1V8_E")
	)
	(segment
		(start 123.522232 -80.274668)
		(end 123.274582 -80.274668)
		(width 0.3048)
		(layer "B.Cu")
		(net "P1V8_E")
	)
	(segment
		(start 93.6244 -82.305144)
		(end 93.6244 -81.52511)
		(width 0.381)
		(layer "B.Cu")
		(net "P1V8_E")
	)
	(segment
		(start 121.4755 -94.4372)
		(end 120.3706 -94.4372)
		(width 0.508)
		(layer "B.Cu")
		(net "P1V8_E")
	)
	(segment
		(start 66.420746 -14.059662)
		(end 66.487548 -14.126464)
		(width 0.508)
		(layer "B.Cu")
		(net "P1V8_E")
	)
	(segment
		(start 104.495092 -58.8264)
		(end 104.173782 -58.8264)
		(width 0.3048)
		(layer "B.Cu")
		(net "P1V8_E")
	)
	(segment
		(start 110.03153 -86.50097)
		(end 109.9566 -86.5759)
		(width 0.508)
		(layer "B.Cu")
		(net "P1V8_E")
	)
	(segment
		(start 113.174272 -75.47737)
		(end 113.174272 -75.825858)
		(width 0.3048)
		(layer "B.Cu")
		(net "P1V8_E")
	)
	(segment
		(start 104.744774 -88.175846)
		(end 104.397302 -88.175846)
		(width 0.508)
		(layer "B.Cu")
		(net "P1V8_E")
	)
	(segment
		(start 111.94796 -87.552276)
		(end 111.94796 -88.27516)
		(width 0.508)
		(layer "B.Cu")
		(net "P1V8_E")
	)
	(segment
		(start 100.457 -61.7728)
		(end 100.772722 -61.7728)
		(width 0.3048)
		(layer "B.Cu")
		(net "P1V8_E")
	)
	(segment
		(start 95.386906 -79.98333)
		(end 95.105728 -80.264508)
		(width 0.508)
		(layer "B.Cu")
		(net "P1V8_E")
	)
	(segment
		(start 87.26805 -75.6031)
		(end 87.26805 -74.59345)
		(width 0.3048)
		(layer "B.Cu")
		(net "P1V8_E")
	)
	(segment
		(start 134.606538 -85.1535)
		(end 134.606538 -85.381338)
		(width 0.508)
		(layer "B.Cu")
		(net "P1V8_E")
	)
	(segment
		(start 119.00027 -73.000108)
		(end 119.25046 -73.250298)
		(width 0.508)
		(layer "B.Cu")
		(net "P1V8_E")
	)
	(segment
		(start 120.985788 -73.000108)
		(end 121.000266 -73.000108)
		(width 0.3048)
		(layer "B.Cu")
		(net "P1V8_E")
	)
	(segment
		(start 138.4808 -90.416888)
		(end 138.99515 -90.931238)
		(width 0.508)
		(layer "B.Cu")
		(net "P1V8_E")
	)
	(segment
		(start 110.109 -85.725)
		(end 110.03153 -85.80247)
		(width 0.508)
		(layer "B.Cu")
		(net "P1V8_E")
	)
	(segment
		(start 100.766118 -59.7662)
		(end 101.000052 -60.000134)
		(width 0.3048)
		(layer "B.Cu")
		(net "P1V8_E")
	)
	(segment
		(start 120.523 -76.1746)
		(end 120.174512 -76.1746)
		(width 0.3048)
		(layer "B.Cu")
		(net "P1V8_E")
	)
	(segment
		(start 117.5004 -75.7428)
		(end 117.5004 -75.500484)
		(width 0.3048)
		(layer "B.Cu")
		(net "P1V8_E")
	)
	(segment
		(start 105.882948 -79.883)
		(end 106.000042 -80.000094)
		(width 0.254)
		(layer "B.Cu")
		(net "P1V8_E")
	)
	(segment
		(start 114.9604 -84.5058)
		(end 114.5413 -84.5058)
		(width 0.3302)
		(layer "B.Cu")
		(net "P1V8_E")
	)
	(segment
		(start 118.27256 -74.160888)
		(end 117.839744 -74.160888)
		(width 0.508)
		(layer "B.Cu")
		(net "P1V8_E")
	)
	(segment
		(start 116.282724 -75.7174)
		(end 116.000022 -76.000102)
		(width 0.254)
		(layer "B.Cu")
		(net "P1V8_E")
	)
	(segment
		(start 96.703134 -84.53374)
		(end 96.703134 -83.808062)
		(width 0.381)
		(layer "B.Cu")
		(net "P1V8_E")
	)
	(segment
		(start 108.61929 -61.463174)
		(end 108.247942 -61.463174)
		(width 0.3048)
		(layer "B.Cu")
		(net "P1V8_E")
	)
	(segment
		(start 113.03 -88.3412)
		(end 113.6142 -87.757)
		(width 0.508)
		(layer "B.Cu")
		(net "P1V8_E")
	)
	(segment
		(start 121.2596 -88.5317)
		(end 121.031 -88.3031)
		(width 0.508)
		(layer "B.Cu")
		(net "P1V8_E")
	)
	(segment
		(start 117.839744 -74.160888)
		(end 117.000274 -75.000358)
		(width 0.508)
		(layer "B.Cu")
		(net "P1V8_E")
	)
	(segment
		(start 116.5098 -75.7174)
		(end 116.282724 -75.7174)
		(width 0.254)
		(layer "B.Cu")
		(net "P1V8_E")
	)
	(segment
		(start 75.730608 -99.057968)
		(end 80.463644 -99.057968)
		(width 0.508)
		(layer "B.Cu")
		(net "P1V8_E")
	)
	(segment
		(start 130.2258 -80.6196)
		(end 129.8956 -80.6196)
		(width 0.3048)
		(layer "B.Cu")
		(net "P1V8_E")
	)
	(segment
		(start 135.622538 -85.1535)
		(end 134.606538 -85.1535)
		(width 0.508)
		(layer "B.Cu")
		(net "P1V8_E")
	)
	(segment
		(start 129.276094 -80.000094)
		(end 128.999996 -80.000094)
		(width 0.3048)
		(layer "B.Cu")
		(net "P1V8_E")
	)
	(segment
		(start 103.782114 -60.7822)
		(end 104.000046 -61.000132)
		(width 0.3048)
		(layer "B.Cu")
		(net "P1V8_E")
	)
	(segment
		(start 100.838 -86.2711)
		(end 100.584 -86.5251)
		(width 0.508)
		(layer "B.Cu")
		(net "P1V8_E")
	)
	(segment
		(start 121.055892 -73.000108)
		(end 121.000266 -73.000108)
		(width 0.3048)
		(layer "B.Cu")
		(net "P1V8_E")
	)
	(segment
		(start 105.5116 -79.883)
		(end 105.882948 -79.883)
		(width 0.254)
		(layer "B.Cu")
		(net "P1V8_E")
	)
	(segment
		(start 114.1476 -84.8995)
		(end 113.1316 -84.8995)
		(width 0.508)
		(layer "B.Cu")
		(net "P1V8_E")
	)
	(segment
		(start 122.3899 -91.551506)
		(end 122.705876 -91.23553)
		(width 0.508)
		(layer "B.Cu")
		(net "P1V8_E")
	)
	(segment
		(start 110.5408 -85.2932)
		(end 110.109 -85.725)
		(width 0.508)
		(layer "B.Cu")
		(net "P1V8_E")
	)
	(segment
		(start 120.174512 -76.1746)
		(end 120.000014 -76.000102)
		(width 0.3048)
		(layer "B.Cu")
		(net "P1V8_E")
	)
	(segment
		(start 141.928596 -31.240222)
		(end 144.174718 -28.9941)
		(width 1.016)
		(layer "In2.Cu")
		(net "P1V8_E")
	)
	(segment
		(start 141.928596 -52.717446)
		(end 141.928596 -31.240222)
		(width 1.016)
		(layer "In2.Cu")
		(net "P1V8_E")
	)
	(segment
		(start 148.5392 -59.32805)
		(end 141.928596 -52.717446)
		(width 1.016)
		(layer "In2.Cu")
		(net "P1V8_E")
	)
	(segment
		(start 149.9489 -82.044794)
		(end 149.9489 -75.230228)
		(width 1.016)
		(layer "In2.Cu")
		(net "P1V8_E")
	)
	(segment
		(start 148.5392 -73.820528)
		(end 148.5392 -59.32805)
		(width 1.016)
		(layer "In2.Cu")
		(net "P1V8_E")
	)
	(segment
		(start 149.9489 -75.230228)
		(end 148.5392 -73.820528)
		(width 1.016)
		(layer "In2.Cu")
		(net "P1V8_E")
	)
	(segment
		(start 144.174718 -28.9941)
		(end 146.437096 -28.9941)
		(width 1.016)
		(layer "In2.Cu")
		(net "P1V8_E")
	)
	(segment
		(start 146.437096 -28.9941)
		(end 146.506438 -28.924758)
		(width 1.016)
		(layer "In2.Cu")
		(net "P1V8_E")
	)
	(segment
		(start 87.0458 -75.8698)
		(end 88.011 -76.835)
		(width 1.016)
		(layer "In5.Cu")
		(net "P1V8_E")
	)
	(segment
		(start 87.376 -80.264)
		(end 87.376 -79.6036)
		(width 1.016)
		(layer "In5.Cu")
		(net "P1V8_E")
	)
	(segment
		(start 87.0458 -71.5518)
		(end 87.0458 -75.8698)
		(width 1.016)
		(layer "In5.Cu")
		(net "P1V8_E")
	)
	(segment
		(start 87.1474 -71.4502)
		(end 87.0458 -71.5518)
		(width 1.016)
		(layer "In5.Cu")
		(net "P1V8_E")
	)
	(segment
		(start 88.011 -78.9686)
		(end 88.011 -76.835)
		(width 1.016)
		(layer "In5.Cu")
		(net "P1V8_E")
	)
	(segment
		(start 87.376 -79.6036)
		(end 88.011 -78.9686)
		(width 1.016)
		(layer "In5.Cu")
		(net "P1V8_E")
	)
	(segment
		(start 183.799734 -43.999912)
		(end 183.399938 -44.399708)
		(width 0.3556)
		(layer "F.Cu")
		(net "P1V8_C")
	)
	(segment
		(start 184.19953 -40.39997)
		(end 183.799734 -40.799766)
		(width 0.3556)
		(layer "F.Cu")
		(net "P1V8_C")
	)
	(segment
		(start 179.799996 -31.20009)
		(end 180.199792 -31.599886)
		(width 0.3048)
		(layer "F.Cu")
		(net "P1V8_C")
	)
	(segment
		(start 184.199784 -48.399954)
		(end 184.19953 -48.399954)
		(width 0.3556)
		(layer "F.Cu")
		(net "P1V8_C")
	)
	(segment
		(start 165.800024 -49.1998)
		(end 165.399974 -48.79975)
		(width 0.3556)
		(layer "F.Cu")
		(net "P1V8_C")
	)
	(segment
		(start 177.4063 -49.6062)
		(end 176.9999 -49.1998)
		(width 0.2032)
		(layer "F.Cu")
		(net "P1V8_C")
	)
	(segment
		(start 181.000146 -30.80004)
		(end 180.999892 -30.80004)
		(width 0.3048)
		(layer "F.Cu")
		(net "P1V8_C")
	)
	(segment
		(start 164.075872 -58.558938)
		(end 162.984688 -58.558938)
		(width 0.508)
		(layer "F.Cu")
		(net "P1V8_C")
	)
	(segment
		(start 185.607198 -58.923428)
		(end 185.607198 -59.740546)
		(width 0.508)
		(layer "F.Cu")
		(net "P1V8_C")
	)
	(segment
		(start 168.924732 -70.245732)
		(end 167.7416 -69.0626)
		(width 1.016)
		(layer "F.Cu")
		(net "P1V8_C")
	)
	(segment
		(start 193.5353 -34.3916)
		(end 194.2719 -34.3916)
		(width 0.508)
		(layer "F.Cu")
		(net "P1V8_C")
	)
	(segment
		(start 168.599866 -48.79975)
		(end 168.20007 -48.399954)
		(width 0.3556)
		(layer "F.Cu")
		(net "P1V8_C")
	)
	(segment
		(start 182.599838 -48.399954)
		(end 181.799992 -49.1998)
		(width 0.3556)
		(layer "F.Cu")
		(net "P1V8_C")
	)
	(segment
		(start 166.19982 -45.599604)
		(end 165.800024 -45.9994)
		(width 0.3556)
		(layer "F.Cu")
		(net "P1V8_C")
	)
	(segment
		(start 168.999916 -49.1998)
		(end 168.599866 -48.79975)
		(width 0.3556)
		(layer "F.Cu")
		(net "P1V8_C")
	)
	(segment
		(start 192.384426 -37.65423)
		(end 192.397634 -37.641022)
		(width 0.508)
		(layer "F.Cu")
		(net "P1V8_C")
	)
	(segment
		(start 195.970398 -71.662036)
		(end 197.717156 -71.662036)
		(width 0.3048)
		(layer "F.Cu")
		(net "P1V8_C")
	)
	(segment
		(start 185.600848 -58.917078)
		(end 185.607198 -58.923428)
		(width 0.508)
		(layer "F.Cu")
		(net "P1V8_C")
	)
	(segment
		(start 183.799734 -40.799766)
		(end 183.399938 -41.199562)
		(width 0.3556)
		(layer "F.Cu")
		(net "P1V8_C")
	)
	(segment
		(start 181.6735 -55.245)
		(end 181.6735 -55.984394)
		(width 0.508)
		(layer "F.Cu")
		(net "P1V8_C")
	)
	(segment
		(start 184.199784 -38.800024)
		(end 184.19953 -38.800024)
		(width 0.3556)
		(layer "F.Cu")
		(net "P1V8_C")
	)
	(segment
		(start 184.01411 -57.084214)
		(end 184.3405 -56.757824)
		(width 0.508)
		(layer "F.Cu")
		(net "P1V8_C")
	)
	(segment
		(start 189.7253 -22.9616)
		(end 189.7253 -24.003)
		(width 0.508)
		(layer "F.Cu")
		(net "P1V8_C")
	)
	(segment
		(start 186.918092 -25.019)
		(end 186.865514 -24.966422)
		(width 0.508)
		(layer "F.Cu")
		(net "P1V8_C")
	)
	(segment
		(start 191.4779 -40.6527)
		(end 193.3956 -40.6527)
		(width 0.508)
		(layer "F.Cu")
		(net "P1V8_C")
	)
	(segment
		(start 195.4784 -41.7068)
		(end 194.5767 -41.7068)
		(width 0.508)
		(layer "F.Cu")
		(net "P1V8_C")
	)
	(segment
		(start 184.199784 -33.999932)
		(end 183.799734 -34.399982)
		(width 0.3556)
		(layer "F.Cu")
		(net "P1V8_C")
	)
	(segment
		(start 165.172898 -58.553096)
		(end 164.081714 -58.553096)
		(width 0.508)
		(layer "F.Cu")
		(net "P1V8_C")
	)
	(segment
		(start 188.36386 -24.765)
		(end 188.10986 -25.019)
		(width 0.508)
		(layer "F.Cu")
		(net "P1V8_C")
	)
	(segment
		(start 183.799734 -39.19982)
		(end 183.399938 -39.599616)
		(width 0.3556)
		(layer "F.Cu")
		(net "P1V8_C")
	)
	(segment
		(start 166.19982 -43.999912)
		(end 165.800024 -44.399708)
		(width 0.3048)
		(layer "F.Cu")
		(net "P1V8_C")
	)
	(segment
		(start 189.7253 -24.003)
		(end 189.7253 -24.2951)
		(width 0.508)
		(layer "F.Cu")
		(net "P1V8_C")
	)
	(segment
		(start 170.8785 -104.1654)
		(end 171.2341 -104.521)
		(width 0.508)
		(layer "F.Cu")
		(net "P1V8_C")
	)
	(segment
		(start 167.28694 -58.52795)
		(end 166.269416 -58.52795)
		(width 0.508)
		(layer "F.Cu")
		(net "P1V8_C")
	)
	(segment
		(start 197.717156 -71.662036)
		(end 197.72376 -71.66864)
		(width 0.3048)
		(layer "F.Cu")
		(net "P1V8_C")
	)
	(segment
		(start 162.961066 -58.58256)
		(end 162.173666 -58.58256)
		(width 0.508)
		(layer "F.Cu")
		(net "P1V8_C")
	)
	(segment
		(start 183.799734 -47.199804)
		(end 183.399938 -47.5996)
		(width 0.3556)
		(layer "F.Cu")
		(net "P1V8_C")
	)
	(segment
		(start 181.000146 -48.399954)
		(end 180.999892 -48.399954)
		(width 0.3556)
		(layer "F.Cu")
		(net "P1V8_C")
	)
	(segment
		(start 166.599616 -46.800008)
		(end 166.19982 -47.199804)
		(width 0.3556)
		(layer "F.Cu")
		(net "P1V8_C")
	)
	(segment
		(start 181.799992 -49.1998)
		(end 181.399942 -48.79975)
		(width 0.3556)
		(layer "F.Cu")
		(net "P1V8_C")
	)
	(segment
		(start 168.20007 -48.399954)
		(end 168.199816 -48.399954)
		(width 0.3556)
		(layer "F.Cu")
		(net "P1V8_C")
	)
	(segment
		(start 183.399938 -37.99967)
		(end 183.399938 -37.999924)
		(width 0.3556)
		(layer "F.Cu")
		(net "P1V8_C")
	)
	(segment
		(start 176.1998 -48.399954)
		(end 176.199546 -48.399954)
		(width 0.3556)
		(layer "F.Cu")
		(net "P1V8_C")
	)
	(segment
		(start 191.483742 -37.65423)
		(end 192.384426 -37.65423)
		(width 0.508)
		(layer "F.Cu")
		(net "P1V8_C")
	)
	(segment
		(start 183.399938 -39.599616)
		(end 183.399938 -39.59987)
		(width 0.3556)
		(layer "F.Cu")
		(net "P1V8_C")
	)
	(segment
		(start 172.339 -60.2615)
		(end 172.339 -61.042296)
		(width 0.508)
		(layer "F.Cu")
		(net "P1V8_C")
	)
	(segment
		(start 178.599846 -49.1998)
		(end 178.193446 -49.6062)
		(width 0.2032)
		(layer "F.Cu")
		(net "P1V8_C")
	)
	(segment
		(start 183.799734 -45.599858)
		(end 183.399938 -45.999654)
		(width 0.3556)
		(layer "F.Cu")
		(net "P1V8_C")
	)
	(segment
		(start 183.799734 -34.399982)
		(end 183.399938 -34.799778)
		(width 0.3556)
		(layer "F.Cu")
		(net "P1V8_C")
	)
	(segment
		(start 175.399954 -49.199546)
		(end 175.399954 -49.1998)
		(width 0.3556)
		(layer "F.Cu")
		(net "P1V8_C")
	)
	(segment
		(start 168.440862 -58.517028)
		(end 168.42994 -58.52795)
		(width 0.508)
		(layer "F.Cu")
		(net "P1V8_C")
	)
	(segment
		(start 170.33494 -105.50652)
		(end 171.2341 -105.50652)
		(width 0.508)
		(layer "F.Cu")
		(net "P1V8_C")
	)
	(segment
		(start 184.199784 -32.399986)
		(end 184.19953 -32.399986)
		(width 0.3556)
		(layer "F.Cu")
		(net "P1V8_C")
	)
	(segment
		(start 176.199546 -48.399954)
		(end 175.79975 -48.79975)
		(width 0.3556)
		(layer "F.Cu")
		(net "P1V8_C")
	)
	(segment
		(start 174.43958 -108.8898)
		(end 174.34306 -108.79328)
		(width 0.508)
		(layer "F.Cu")
		(net "P1V8_C")
	)
	(segment
		(start 181.6735 -55.984394)
		(end 181.51348 -56.144414)
		(width 0.508)
		(layer "F.Cu")
		(net "P1V8_C")
	)
	(segment
		(start 166.269416 -58.52795)
		(end 166.233856 -58.56351)
		(width 0.508)
		(layer "F.Cu")
		(net "P1V8_C")
	)
	(segment
		(start 170.199812 -48.79975)
		(end 170.599862 -49.1998)
		(width 0.3556)
		(layer "F.Cu")
		(net "P1V8_C")
	)
	(segment
		(start 179.399946 -30.80004)
		(end 179.799996 -31.20009)
		(width 0.3048)
		(layer "F.Cu")
		(net "P1V8_C")
	)
	(segment
		(start 171.2341 -104.521)
		(end 171.2341 -105.50652)
		(width 0.508)
		(layer "F.Cu")
		(net "P1V8_C")
	)
	(segment
		(start 182.999888 -31.199836)
		(end 182.600092 -30.80004)
		(width 0.3048)
		(layer "F.Cu")
		(net "P1V8_C")
	)
	(segment
		(start 183.399938 -31.599886)
		(end 182.999888 -31.199836)
		(width 0.3048)
		(layer "F.Cu")
		(net "P1V8_C")
	)
	(segment
		(start 174.199804 -48.79975)
		(end 174.5996 -48.399954)
		(width 0.3556)
		(layer "F.Cu")
		(net "P1V8_C")
	)
	(segment
		(start 181.03088 -60.419488)
		(end 181.03088 -61.207904)
		(width 0.508)
		(layer "F.Cu")
		(net "P1V8_C")
	)
	(segment
		(start 184.19953 -46.800008)
		(end 183.799734 -47.199804)
		(width 0.3556)
		(layer "F.Cu")
		(net "P1V8_C")
	)
	(segment
		(start 165.800024 -47.5996)
		(end 165.800024 -47.599854)
		(width 0.3556)
		(layer "F.Cu")
		(net "P1V8_C")
	)
	(segment
		(start 166.99992 -48.79975)
		(end 166.600124 -48.399954)
		(width 0.3556)
		(layer "F.Cu")
		(net "P1V8_C")
	)
	(segment
		(start 183.399938 -34.799778)
		(end 183.399938 -34.800032)
		(width 0.3556)
		(layer "F.Cu")
		(net "P1V8_C")
	)
	(segment
		(start 188.820298 -58.921142)
		(end 188.83884 -58.9026)
		(width 0.508)
		(layer "F.Cu")
		(net "P1V8_C")
	)
	(segment
		(start 181.399942 -48.79975)
		(end 181.000146 -48.399954)
		(width 0.3556)
		(layer "F.Cu")
		(net "P1V8_C")
	)
	(segment
		(start 183.399938 -45.999654)
		(end 183.399938 -45.999908)
		(width 0.3556)
		(layer "F.Cu")
		(net "P1V8_C")
	)
	(segment
		(start 178.199796 -48.79975)
		(end 178.599846 -49.1998)
		(width 0.3556)
		(layer "F.Cu")
		(net "P1V8_C")
	)
	(segment
		(start 184.19953 -32.399986)
		(end 183.799734 -32.799782)
		(width 0.3556)
		(layer "F.Cu")
		(net "P1V8_C")
	)
	(segment
		(start 166.600124 -48.399954)
		(end 166.59987 -48.399954)
		(width 0.3556)
		(layer "F.Cu")
		(net "P1V8_C")
	)
	(segment
		(start 184.19953 -38.800024)
		(end 183.799734 -39.19982)
		(width 0.3556)
		(layer "F.Cu")
		(net "P1V8_C")
	)
	(segment
		(start 183.815228 -30.415484)
		(end 182.984394 -30.415484)
		(width 0.2032)
		(layer "F.Cu")
		(net "P1V8_C")
	)
	(segment
		(start 184.19953 -48.399954)
		(end 183.799734 -48.79975)
		(width 0.3556)
		(layer "F.Cu")
		(net "P1V8_C")
	)
	(segment
		(start 191.479932 -39.1414)
		(end 193.8147 -39.1414)
		(width 0.508)
		(layer "F.Cu")
		(net "P1V8_C")
	)
	(segment
		(start 179.799742 -48.79975)
		(end 180.199792 -49.1998)
		(width 0.3556)
		(layer "F.Cu")
		(net "P1V8_C")
	)
	(segment
		(start 192.2907 -43.0657)
		(end 193.2432 -43.0657)
		(width 0.508)
		(layer "F.Cu")
		(net "P1V8_C")
	)
	(segment
		(start 183.799734 -37.599874)
		(end 183.399938 -37.99967)
		(width 0.3556)
		(layer "F.Cu")
		(net "P1V8_C")
	)
	(segment
		(start 183.799734 -35.999928)
		(end 183.399938 -36.399724)
		(width 0.3556)
		(layer "F.Cu")
		(net "P1V8_C")
	)
	(segment
		(start 174.5996 -48.399954)
		(end 174.599854 -48.399954)
		(width 0.3556)
		(layer "F.Cu")
		(net "P1V8_C")
	)
	(segment
		(start 166.19982 -47.199804)
		(end 165.800024 -47.5996)
		(width 0.3556)
		(layer "F.Cu")
		(net "P1V8_C")
	)
	(segment
		(start 165.800024 -41.199816)
		(end 164.999924 -41.999916)
		(width 0.3048)
		(layer "F.Cu")
		(net "P1V8_C")
	)
	(segment
		(start 165.183312 -58.56351)
		(end 165.172898 -58.553096)
		(width 0.508)
		(layer "F.Cu")
		(net "P1V8_C")
	)
	(segment
		(start 182.600092 -30.80004)
		(end 182.599838 -30.80004)
		(width 0.3048)
		(layer "F.Cu")
		(net "P1V8_C")
	)
	(segment
		(start 179.723796 -70.245732)
		(end 168.924732 -70.245732)
		(width 1.016)
		(layer "F.Cu")
		(net "P1V8_C")
	)
	(segment
		(start 177.8 -48.399954)
		(end 178.199796 -48.79975)
		(width 0.3556)
		(layer "F.Cu")
		(net "P1V8_C")
	)
	(segment
		(start 169.507662 -58.517028)
		(end 168.440862 -58.517028)
		(width 0.508)
		(layer "F.Cu")
		(net "P1V8_C")
	)
	(segment
		(start 165.800024 -45.9994)
		(end 165.800024 -45.999908)
		(width 0.3556)
		(layer "F.Cu")
		(net "P1V8_C")
	)
	(segment
		(start 175.8188 -108.8898)
		(end 174.43958 -108.8898)
		(width 0.508)
		(layer "F.Cu")
		(net "P1V8_C")
	)
	(segment
		(start 184.199784 -43.599862)
		(end 183.799734 -43.999912)
		(width 0.3556)
		(layer "F.Cu")
		(net "P1V8_C")
	)
	(segment
		(start 165.800024 -44.399708)
		(end 165.800024 -44.399962)
		(width 0.3048)
		(layer "F.Cu")
		(net "P1V8_C")
	)
	(segment
		(start 170.8785 -103.505)
		(end 170.8785 -104.1654)
		(width 0.508)
		(layer "F.Cu")
		(net "P1V8_C")
	)
	(segment
		(start 169.507662 -58.517028)
		(end 169.507662 -59.305444)
		(width 0.508)
		(layer "F.Cu")
		(net "P1V8_C")
	)
	(segment
		(start 184.199784 -45.199808)
		(end 183.799734 -45.599858)
		(width 0.3556)
		(layer "F.Cu")
		(net "P1V8_C")
	)
	(segment
		(start 181.799992 -31.599886)
		(end 181.399942 -31.199836)
		(width 0.3048)
		(layer "F.Cu")
		(net "P1V8_C")
	)
	(segment
		(start 162.984688 -58.558938)
		(end 162.961066 -58.58256)
		(width 0.508)
		(layer "F.Cu")
		(net "P1V8_C")
	)
	(segment
		(start 166.59987 -46.800008)
		(end 166.599616 -46.800008)
		(width 0.3556)
		(layer "F.Cu")
		(net "P1V8_C")
	)
	(segment
		(start 174.4726 -60.2615)
		(end 174.4726 -61.049916)
		(width 0.508)
		(layer "F.Cu")
		(net "P1V8_C")
	)
	(segment
		(start 189.2554 -24.765)
		(end 188.36386 -24.765)
		(width 0.508)
		(layer "F.Cu")
		(net "P1V8_C")
	)
	(segment
		(start 165.800024 -42.800016)
		(end 165.399974 -42.399966)
		(width 0.3048)
		(layer "F.Cu")
		(net "P1V8_C")
	)
	(segment
		(start 193.273934 -36.480496)
		(end 193.668904 -36.480496)
		(width 0.508)
		(layer "F.Cu")
		(net "P1V8_C")
	)
	(segment
		(start 184.199784 -37.199824)
		(end 183.799734 -37.599874)
		(width 0.3556)
		(layer "F.Cu")
		(net "P1V8_C")
	)
	(segment
		(start 183.399938 -41.199562)
		(end 183.399938 -41.199816)
		(width 0.3556)
		(layer "F.Cu")
		(net "P1V8_C")
	)
	(segment
		(start 193.668904 -36.480496)
		(end 194.2084 -35.941)
		(width 0.508)
		(layer "F.Cu")
		(net "P1V8_C")
	)
	(segment
		(start 187.651644 -58.921142)
		(end 188.820298 -58.921142)
		(width 0.508)
		(layer "F.Cu")
		(net "P1V8_C")
	)
	(segment
		(start 151.710898 -71.124318)
		(end 150.88235 -71.124318)
		(width 0.508)
		(layer "F.Cu")
		(net "P1V8_C")
	)
	(segment
		(start 179.399946 -48.399954)
		(end 179.799742 -48.79975)
		(width 0.3556)
		(layer "F.Cu")
		(net "P1V8_C")
	)
	(segment
		(start 168.42994 -58.52795)
		(end 167.28694 -58.52795)
		(width 0.508)
		(layer "F.Cu")
		(net "P1V8_C")
	)
	(segment
		(start 183.399938 -44.399708)
		(end 183.399938 -44.399962)
		(width 0.3556)
		(layer "F.Cu")
		(net "P1V8_C")
	)
	(segment
		(start 198.53656 -71.66864)
		(end 197.72376 -71.66864)
		(width 0.508)
		(layer "F.Cu")
		(net "P1V8_C")
	)
	(segment
		(start 184.199784 -35.599878)
		(end 183.799734 -35.999928)
		(width 0.3556)
		(layer "F.Cu")
		(net "P1V8_C")
	)
	(segment
		(start 178.20005 -31.20009)
		(end 178.599846 -31.599886)
		(width 0.3048)
		(layer "F.Cu")
		(net "P1V8_C")
	)
	(segment
		(start 166.59987 -45.199808)
		(end 166.599616 -45.199808)
		(width 0.3556)
		(layer "F.Cu")
		(net "P1V8_C")
	)
	(segment
		(start 184.199784 -46.800008)
		(end 184.19953 -46.800008)
		(width 0.3556)
		(layer "F.Cu")
		(net "P1V8_C")
	)
	(segment
		(start 184.3405 -56.757824)
		(end 184.3405 -56.139588)
		(width 0.508)
		(layer "F.Cu")
		(net "P1V8_C")
	)
	(segment
		(start 166.599616 -45.199808)
		(end 166.19982 -45.599604)
		(width 0.3556)
		(layer "F.Cu")
		(net "P1V8_C")
	)
	(segment
		(start 166.59987 -43.599862)
		(end 166.19982 -43.999912)
		(width 0.3048)
		(layer "F.Cu")
		(net "P1V8_C")
	)
	(segment
		(start 177.8 -30.80004)
		(end 178.20005 -31.20009)
		(width 0.3048)
		(layer "F.Cu")
		(net "P1V8_C")
	)
	(segment
		(start 165.399974 -42.399966)
		(end 164.999924 -41.999916)
		(width 0.3048)
		(layer "F.Cu")
		(net "P1V8_C")
	)
	(segment
		(start 178.193446 -49.6062)
		(end 177.4063 -49.6062)
		(width 0.2032)
		(layer "F.Cu")
		(net "P1V8_C")
	)
	(segment
		(start 194.2719 -34.3916)
		(end 194.3608 -34.4805)
		(width 0.508)
		(layer "F.Cu")
		(net "P1V8_C")
	)
	(segment
		(start 169.800016 -42.800016)
		(end 170.199812 -43.199812)
		(width 0.3048)
		(layer "F.Cu")
		(net "P1V8_C")
	)
	(segment
		(start 183.399938 -49.199546)
		(end 183.399938 -49.1998)
		(width 0.3556)
		(layer "F.Cu")
		(net "P1V8_C")
	)
	(segment
		(start 183.399938 -33.199578)
		(end 183.399938 -33.199832)
		(width 0.3556)
		(layer "F.Cu")
		(net "P1V8_C")
	)
	(segment
		(start 164.081714 -58.553096)
		(end 164.075872 -58.558938)
		(width 0.508)
		(layer "F.Cu")
		(net "P1V8_C")
	)
	(segment
		(start 184.199784 -40.39997)
		(end 184.19953 -40.39997)
		(width 0.3556)
		(layer "F.Cu")
		(net "P1V8_C")
	)
	(segment
		(start 183.799734 -32.799782)
		(end 183.399938 -33.199578)
		(width 0.3556)
		(layer "F.Cu")
		(net "P1V8_C")
	)
	(segment
		(start 167.39997 -49.1998)
		(end 166.99992 -48.79975)
		(width 0.3556)
		(layer "F.Cu")
		(net "P1V8_C")
	)
	(segment
		(start 193.2686 -35.433)
		(end 193.7004 -35.433)
		(width 0.508)
		(layer "F.Cu")
		(net "P1V8_C")
	)
	(segment
		(start 184.199784 -30.80004)
		(end 183.815228 -30.415484)
		(width 0.2032)
		(layer "F.Cu")
		(net "P1V8_C")
	)
	(segment
		(start 175.5394 -60.2615)
		(end 175.5394 -61.049916)
		(width 0.508)
		(layer "F.Cu")
		(net "P1V8_C")
	)
	(segment
		(start 193.7004 -35.433)
		(end 194.2084 -35.941)
		(width 0.508)
		(layer "F.Cu")
		(net "P1V8_C")
	)
	(segment
		(start 184.199784 -41.999916)
		(end 183.799734 -42.399966)
		(width 0.3556)
		(layer "F.Cu")
		(net "P1V8_C")
	)
	(segment
		(start 169.800016 -48.399954)
		(end 170.199812 -48.79975)
		(width 0.3556)
		(layer "F.Cu")
		(net "P1V8_C")
	)
	(segment
		(start 183.799734 -48.79975)
		(end 183.399938 -49.199546)
		(width 0.3556)
		(layer "F.Cu")
		(net "P1V8_C")
	)
	(segment
		(start 181.399942 -31.199836)
		(end 181.000146 -30.80004)
		(width 0.3048)
		(layer "F.Cu")
		(net "P1V8_C")
	)
	(segment
		(start 183.399938 -36.399724)
		(end 183.399938 -36.399978)
		(width 0.3556)
		(layer "F.Cu")
		(net "P1V8_C")
	)
	(segment
		(start 186.865514 -24.966422)
		(end 185.923174 -24.966422)
		(width 0.508)
		(layer "F.Cu")
		(net "P1V8_C")
	)
	(segment
		(start 189.7253 -24.2951)
		(end 189.2554 -24.765)
		(width 0.508)
		(layer "F.Cu")
		(net "P1V8_C")
	)
	(segment
		(start 183.399938 -47.5996)
		(end 183.399938 -47.599854)
		(width 0.3556)
		(layer "F.Cu")
		(net "P1V8_C")
	)
	(segment
		(start 188.10986 -25.019)
		(end 186.918092 -25.019)
		(width 0.508)
		(layer "F.Cu")
		(net "P1V8_C")
	)
	(segment
		(start 182.984394 -30.415484)
		(end 182.599838 -30.80004)
		(width 0.2032)
		(layer "F.Cu")
		(net "P1V8_C")
	)
	(segment
		(start 175.79975 -48.79975)
		(end 175.399954 -49.199546)
		(width 0.3556)
		(layer "F.Cu")
		(net "P1V8_C")
	)
	(segment
		(start 166.233856 -58.56351)
		(end 165.183312 -58.56351)
		(width 0.508)
		(layer "F.Cu")
		(net "P1V8_C")
	)
	(via
		(at 194.2084 -35.941)
		(size 0.508)
		(drill 0.254)
		(layers "F.Cu" "B.Cu")
		(net "P1V8_C")
	)
	(via
		(at 158.588202 -53.325776)
		(size 0.508)
		(drill 0.254)
		(layers "F.Cu" "B.Cu")
		(net "P1V8_C")
	)
	(via
		(at 175.8188 -108.8898)
		(size 0.508)
		(drill 0.254)
		(layers "F.Cu" "B.Cu")
		(net "P1V8_C")
	)
	(via
		(at 162.652202 -53.325776)
		(size 0.508)
		(drill 0.254)
		(layers "F.Cu" "B.Cu")
		(net "P1V8_C")
	)
	(via
		(at 166.99992 -48.79975)
		(size 0.508)
		(drill 0.254)
		(layers "F.Cu" "B.Cu")
		(net "P1V8_C")
	)
	(via
		(at 193.2432 -43.0657)
		(size 0.508)
		(drill 0.254)
		(layers "F.Cu" "B.Cu")
		(net "P1V8_C")
	)
	(via
		(at 175.5394 -61.049916)
		(size 0.508)
		(drill 0.254)
		(layers "F.Cu" "B.Cu")
		(net "P1V8_C")
	)
	(via
		(at 159.604202 -53.325776)
		(size 0.508)
		(drill 0.254)
		(layers "F.Cu" "B.Cu")
		(net "P1V8_C")
	)
	(via
		(at 188.1886 -119.2276)
		(size 0.7112)
		(drill 0.4064)
		(layers "F.Cu" "B.Cu")
		(net "P1V8_C")
	)
	(via
		(at 194.3608 -34.4805)
		(size 0.508)
		(drill 0.254)
		(layers "F.Cu" "B.Cu")
		(net "P1V8_C")
	)
	(via
		(at 183.799734 -35.999928)
		(size 0.508)
		(drill 0.254)
		(layers "F.Cu" "B.Cu")
		(net "P1V8_C")
	)
	(via
		(at 183.799734 -47.199804)
		(size 0.508)
		(drill 0.254)
		(layers "F.Cu" "B.Cu")
		(net "P1V8_C")
	)
	(via
		(at 204.3176 -44.45)
		(size 0.508)
		(drill 0.254)
		(layers "F.Cu" "B.Cu")
		(net "P1V8_C")
	)
	(via
		(at 183.799734 -42.399966)
		(size 0.508)
		(drill 0.254)
		(layers "F.Cu" "B.Cu")
		(net "P1V8_C")
	)
	(via
		(at 183.799734 -39.19982)
		(size 0.508)
		(drill 0.254)
		(layers "F.Cu" "B.Cu")
		(net "P1V8_C")
	)
	(via
		(at 194.2465 -45.5422)
		(size 0.508)
		(drill 0.254)
		(layers "F.Cu" "B.Cu")
		(net "P1V8_C")
	)
	(via
		(at 188.1886 -121.0056)
		(size 0.7112)
		(drill 0.4064)
		(layers "F.Cu" "B.Cu")
		(net "P1V8_C")
	)
	(via
		(at 194.1957 -46.4566)
		(size 0.508)
		(drill 0.254)
		(layers "F.Cu" "B.Cu")
		(net "P1V8_C")
	)
	(via
		(at 183.799734 -32.799782)
		(size 0.508)
		(drill 0.254)
		(layers "F.Cu" "B.Cu")
		(net "P1V8_C")
	)
	(via
		(at 174.199804 -48.79975)
		(size 0.508)
		(drill 0.254)
		(layers "F.Cu" "B.Cu")
		(net "P1V8_C")
	)
	(via
		(at 204.5208 -43.2562)
		(size 0.6096)
		(drill 0.3048)
		(layers "F.Cu" "B.Cu")
		(net "P1V8_C")
	)
	(via
		(at 193.3956 -40.6527)
		(size 0.508)
		(drill 0.254)
		(layers "F.Cu" "B.Cu")
		(net "P1V8_C")
	)
	(via
		(at 165.399974 -42.399966)
		(size 0.508)
		(drill 0.254)
		(layers "F.Cu" "B.Cu")
		(net "P1V8_C")
	)
	(via
		(at 160.147 -54.0766)
		(size 0.6096)
		(drill 0.3048)
		(layers "F.Cu" "B.Cu")
		(net "P1V8_C")
	)
	(via
		(at 170.199812 -48.79975)
		(size 0.508)
		(drill 0.254)
		(layers "F.Cu" "B.Cu")
		(net "P1V8_C")
	)
	(via
		(at 183.799734 -37.599874)
		(size 0.508)
		(drill 0.254)
		(layers "F.Cu" "B.Cu")
		(net "P1V8_C")
	)
	(via
		(at 181.03088 -61.207904)
		(size 0.508)
		(drill 0.254)
		(layers "F.Cu" "B.Cu")
		(net "P1V8_C")
	)
	(via
		(at 160.4264 -68.834)
		(size 0.6096)
		(drill 0.3048)
		(layers "F.Cu" "B.Cu")
		(net "P1V8_C")
	)
	(via
		(at 193.6369 -47.2821)
		(size 0.6604)
		(drill 0.3302)
		(layers "F.Cu" "B.Cu")
		(net "P1V8_C")
	)
	(via
		(at 183.799734 -48.79975)
		(size 0.508)
		(drill 0.254)
		(layers "F.Cu" "B.Cu")
		(net "P1V8_C")
	)
	(via
		(at 181.399942 -48.79975)
		(size 0.508)
		(drill 0.254)
		(layers "F.Cu" "B.Cu")
		(net "P1V8_C")
	)
	(via
		(at 179.799742 -48.79975)
		(size 0.508)
		(drill 0.254)
		(layers "F.Cu" "B.Cu")
		(net "P1V8_C")
	)
	(via
		(at 191.661288 -22.078442)
		(size 0.508)
		(drill 0.254)
		(layers "F.Cu" "B.Cu")
		(net "P1V8_C")
	)
	(via
		(at 179.723796 -70.245732)
		(size 0.508)
		(drill 0.254)
		(layers "F.Cu" "B.Cu")
		(net "P1V8_C")
	)
	(via
		(at 171.2341 -105.50652)
		(size 0.508)
		(drill 0.254)
		(layers "F.Cu" "B.Cu")
		(net "P1V8_C")
	)
	(via
		(at 168.599866 -48.79975)
		(size 0.508)
		(drill 0.254)
		(layers "F.Cu" "B.Cu")
		(net "P1V8_C")
	)
	(via
		(at 181.51348 -56.144414)
		(size 0.508)
		(drill 0.254)
		(layers "F.Cu" "B.Cu")
		(net "P1V8_C")
	)
	(via
		(at 193.22161 -50.0888)
		(size 0.508)
		(drill 0.254)
		(layers "F.Cu" "B.Cu")
		(net "P1V8_C")
	)
	(via
		(at 188.233558 -40.58666)
		(size 0.508)
		(drill 0.254)
		(layers "F.Cu" "B.Cu")
		(net "P1V8_C")
	)
	(via
		(at 178.20005 -31.20009)
		(size 0.508)
		(drill 0.254)
		(layers "F.Cu" "B.Cu")
		(net "P1V8_C")
	)
	(via
		(at 185.607198 -59.740546)
		(size 0.508)
		(drill 0.254)
		(layers "F.Cu" "B.Cu")
		(net "P1V8_C")
	)
	(via
		(at 172.339 -61.042296)
		(size 0.508)
		(drill 0.254)
		(layers "F.Cu" "B.Cu")
		(net "P1V8_C")
	)
	(via
		(at 150.88235 -71.124318)
		(size 0.508)
		(drill 0.254)
		(layers "F.Cu" "B.Cu")
		(net "P1V8_C")
	)
	(via
		(at 179.799996 -31.20009)
		(size 0.508)
		(drill 0.254)
		(layers "F.Cu" "B.Cu")
		(net "P1V8_C")
	)
	(via
		(at 166.19982 -45.599604)
		(size 0.508)
		(drill 0.254)
		(layers "F.Cu" "B.Cu")
		(net "P1V8_C")
	)
	(via
		(at 193.4337 -45.847)
		(size 0.508)
		(drill 0.254)
		(layers "F.Cu" "B.Cu")
		(net "P1V8_C")
	)
	(via
		(at 193.8147 -39.1414)
		(size 0.508)
		(drill 0.254)
		(layers "F.Cu" "B.Cu")
		(net "P1V8_C")
	)
	(via
		(at 170.199812 -43.199812)
		(size 0.508)
		(drill 0.254)
		(layers "F.Cu" "B.Cu")
		(net "P1V8_C")
	)
	(via
		(at 169.507662 -59.305444)
		(size 0.508)
		(drill 0.254)
		(layers "F.Cu" "B.Cu")
		(net "P1V8_C")
	)
	(via
		(at 183.799734 -40.799766)
		(size 0.508)
		(drill 0.254)
		(layers "F.Cu" "B.Cu")
		(net "P1V8_C")
	)
	(via
		(at 162.143694 -54.08422)
		(size 0.6096)
		(drill 0.3048)
		(layers "F.Cu" "B.Cu")
		(net "P1V8_C")
	)
	(via
		(at 186.929522 -120.76811)
		(size 0.6604)
		(drill 0.3302)
		(layers "F.Cu" "B.Cu")
		(net "P1V8_C")
	)
	(via
		(at 165.399974 -48.79975)
		(size 0.508)
		(drill 0.254)
		(layers "F.Cu" "B.Cu")
		(net "P1V8_C")
	)
	(via
		(at 204.3684 -33.0962)
		(size 0.6096)
		(drill 0.3048)
		(layers "F.Cu" "B.Cu")
		(net "P1V8_C")
	)
	(via
		(at 201.634598 -74.090784)
		(size 0.508)
		(drill 0.254)
		(layers "F.Cu" "B.Cu")
		(net "P1V8_C")
	)
	(via
		(at 153.162 -70.866)
		(size 0.6096)
		(drill 0.3048)
		(layers "F.Cu" "B.Cu")
		(net "P1V8_C")
	)
	(via
		(at 192.397634 -37.641022)
		(size 0.508)
		(drill 0.254)
		(layers "F.Cu" "B.Cu")
		(net "P1V8_C")
	)
	(via
		(at 162.173666 -58.58256)
		(size 0.508)
		(drill 0.254)
		(layers "F.Cu" "B.Cu")
		(net "P1V8_C")
	)
	(via
		(at 166.19982 -43.999912)
		(size 0.508)
		(drill 0.254)
		(layers "F.Cu" "B.Cu")
		(net "P1V8_C")
	)
	(via
		(at 204.29728 -34.1122)
		(size 0.508)
		(drill 0.254)
		(layers "F.Cu" "B.Cu")
		(net "P1V8_C")
	)
	(via
		(at 195.4784 -41.7068)
		(size 0.508)
		(drill 0.254)
		(layers "F.Cu" "B.Cu")
		(net "P1V8_C")
	)
	(via
		(at 181.399942 -31.199836)
		(size 0.508)
		(drill 0.254)
		(layers "F.Cu" "B.Cu")
		(net "P1V8_C")
	)
	(via
		(at 161.636202 -53.325776)
		(size 0.508)
		(drill 0.254)
		(layers "F.Cu" "B.Cu")
		(net "P1V8_C")
	)
	(via
		(at 183.799734 -43.999912)
		(size 0.508)
		(drill 0.254)
		(layers "F.Cu" "B.Cu")
		(net "P1V8_C")
	)
	(via
		(at 199.771 -34.107882)
		(size 0.508)
		(drill 0.254)
		(layers "F.Cu" "B.Cu")
		(net "P1V8_C")
	)
	(via
		(at 175.79975 -48.79975)
		(size 0.508)
		(drill 0.254)
		(layers "F.Cu" "B.Cu")
		(net "P1V8_C")
	)
	(via
		(at 191.650112 -21.139912)
		(size 0.508)
		(drill 0.254)
		(layers "F.Cu" "B.Cu")
		(net "P1V8_C")
	)
	(via
		(at 160.1724 -25.908)
		(size 0.508)
		(drill 0.254)
		(layers "F.Cu" "B.Cu")
		(net "P1V8_C")
	)
	(via
		(at 188.1886 -117.3226)
		(size 0.7112)
		(drill 0.4064)
		(layers "F.Cu" "B.Cu")
		(net "P1V8_C")
	)
	(via
		(at 160.620202 -53.325776)
		(size 0.508)
		(drill 0.254)
		(layers "F.Cu" "B.Cu")
		(net "P1V8_C")
	)
	(via
		(at 178.199796 -48.79975)
		(size 0.508)
		(drill 0.254)
		(layers "F.Cu" "B.Cu")
		(net "P1V8_C")
	)
	(via
		(at 198.53656 -71.66864)
		(size 0.508)
		(drill 0.254)
		(layers "F.Cu" "B.Cu")
		(net "P1V8_C")
	)
	(via
		(at 189.2554 -24.765)
		(size 0.508)
		(drill 0.254)
		(layers "F.Cu" "B.Cu")
		(net "P1V8_C")
	)
	(via
		(at 161.1376 -25.908)
		(size 0.508)
		(drill 0.254)
		(layers "F.Cu" "B.Cu")
		(net "P1V8_C")
	)
	(via
		(at 167.7416 -69.0626)
		(size 0.508)
		(drill 0.254)
		(layers "F.Cu" "B.Cu")
		(net "P1V8_C")
	)
	(via
		(at 188.83884 -58.9026)
		(size 0.508)
		(drill 0.254)
		(layers "F.Cu" "B.Cu")
		(net "P1V8_C")
	)
	(via
		(at 183.799734 -34.399982)
		(size 0.508)
		(drill 0.254)
		(layers "F.Cu" "B.Cu")
		(net "P1V8_C")
	)
	(via
		(at 182.999888 -31.199836)
		(size 0.508)
		(drill 0.254)
		(layers "F.Cu" "B.Cu")
		(net "P1V8_C")
	)
	(via
		(at 166.19982 -47.199804)
		(size 0.508)
		(drill 0.254)
		(layers "F.Cu" "B.Cu")
		(net "P1V8_C")
	)
	(via
		(at 183.799734 -45.599858)
		(size 0.508)
		(drill 0.254)
		(layers "F.Cu" "B.Cu")
		(net "P1V8_C")
	)
	(via
		(at 184.01411 -57.084214)
		(size 0.508)
		(drill 0.254)
		(layers "F.Cu" "B.Cu")
		(net "P1V8_C")
	)
	(via
		(at 174.4726 -61.049916)
		(size 0.508)
		(drill 0.254)
		(layers "F.Cu" "B.Cu")
		(net "P1V8_C")
	)
	(segment
		(start 185.59018 -110.65764)
		(end 189.33414 -114.4016)
		(width 0.508)
		(layer "B.Cu")
		(net "P1V8_C")
	)
	(segment
		(start 183.424068 -48.424084)
		(end 183.799734 -48.79975)
		(width 0.3048)
		(layer "B.Cu")
		(net "P1V8_C")
	)
	(segment
		(start 181.508654 -48.908462)
		(end 181.399942 -48.79975)
		(width 0.3048)
		(layer "B.Cu")
		(net "P1V8_C")
	)
	(segment
		(start 173.909228 -49.65573)
		(end 173.909228 -49.915572)
		(width 0.3048)
		(layer "B.Cu")
		(net "P1V8_C")
	)
	(segment
		(start 182.5498 -34.925)
		(end 183.274716 -34.925)
		(width 0.3048)
		(layer "B.Cu")
		(net "P1V8_C")
	)
	(segment
		(start 166.205408 -45.594016)
		(end 166.19982 -45.599604)
		(width 0.3048)
		(layer "B.Cu")
		(net "P1V8_C")
	)
	(segment
		(start 194.200018 -34.641282)
		(end 194.3608 -34.4805)
		(width 0.508)
		(layer "B.Cu")
		(net "P1V8_C")
	)
	(segment
		(start 192.3415 -43.053)
		(end 193.2305 -43.053)
		(width 0.508)
		(layer "B.Cu")
		(net "P1V8_C")
	)
	(segment
		(start 183.626252 -32.799782)
		(end 183.515 -32.68853)
		(width 0.3048)
		(layer "B.Cu")
		(net "P1V8_C")
	)
	(segment
		(start 166.88943 -47.033942)
		(end 166.365682 -47.033942)
		(width 0.3048)
		(layer "B.Cu")
		(net "P1V8_C")
	)
	(segment
		(start 189.51194 -58.2295)
		(end 188.83884 -58.9026)
		(width 0.508)
		(layer "B.Cu")
		(net "P1V8_C")
	)
	(segment
		(start 182.5244 -31.75)
		(end 182.5244 -31.675324)
		(width 0.3048)
		(layer "B.Cu")
		(net "P1V8_C")
	)
	(segment
		(start 181.995318 -48.075342)
		(end 181.995318 -48.204374)
		(width 0.3048)
		(layer "B.Cu")
		(net "P1V8_C")
	)
	(segment
		(start 184.43067 -49.430686)
		(end 183.799734 -48.79975)
		(width 0.3048)
		(layer "B.Cu")
		(net "P1V8_C")
	)
	(segment
		(start 183.756808 -34.357056)
		(end 183.799734 -34.399982)
		(width 0.3048)
		(layer "B.Cu")
		(net "P1V8_C")
	)
	(segment
		(start 165.260782 -48.660558)
		(end 165.399974 -48.79975)
		(width 0.3556)
		(layer "B.Cu")
		(net "P1V8_C")
	)
	(segment
		(start 165.46322 -43.341036)
		(end 165.399974 -43.27779)
		(width 0.508)
		(layer "B.Cu")
		(net "P1V8_C")
	)
	(segment
		(start 184.186068 -46.81347)
		(end 184.186068 -46.42993)
		(width 0.3048)
		(layer "B.Cu")
		(net "P1V8_C")
	)
	(segment
		(start 175.79975 -48.79975)
		(end 175.79975 -48.83785)
		(width 0.3556)
		(layer "B.Cu")
		(net "P1V8_C")
	)
	(segment
		(start 184.186068 -45.213524)
		(end 184.186068 -44.78401)
		(width 0.3048)
		(layer "B.Cu")
		(net "P1V8_C")
	)
	(segment
		(start 183.424068 -46.824138)
		(end 183.799734 -47.199804)
		(width 0.3048)
		(layer "B.Cu")
		(net "P1V8_C")
	)
	(segment
		(start 170.19524 -43.19524)
		(end 170.199812 -43.199812)
		(width 0.3048)
		(layer "B.Cu")
		(net "P1V8_C")
	)
	(segment
		(start 181.51348 -56.144414)
		(end 182.435246 -56.144414)
		(width 0.508)
		(layer "B.Cu")
		(net "P1V8_C")
	)
	(segment
		(start 183.358282 -49.633632)
		(end 183.358282 -49.241202)
		(width 0.3048)
		(layer "B.Cu")
		(net "P1V8_C")
	)
	(segment
		(start 166.365682 -47.033942)
		(end 166.19982 -47.199804)
		(width 0.3048)
		(layer "B.Cu")
		(net "P1V8_C")
	)
	(segment
		(start 182.245 -35.2298)
		(end 182.5498 -34.925)
		(width 0.3048)
		(layer "B.Cu")
		(net "P1V8_C")
	)
	(segment
		(start 181.508654 -49.597818)
		(end 181.508654 -48.908462)
		(width 0.3048)
		(layer "B.Cu")
		(net "P1V8_C")
	)
	(segment
		(start 178.203352 -48.796194)
		(end 178.199796 -48.79975)
		(width 0.3048)
		(layer "B.Cu")
		(net "P1V8_C")
	)
	(segment
		(start 193.2051 -40.8432)
		(end 193.3956 -40.6527)
		(width 0.508)
		(layer "B.Cu")
		(net "P1V8_C")
	)
	(segment
		(start 184.186068 -43.613578)
		(end 184.186068 -43.19651)
		(width 0.3048)
		(layer "B.Cu")
		(net "P1V8_C")
	)
	(segment
		(start 170.548808 -49.79035)
		(end 170.470068 -49.71161)
		(width 0.3048)
		(layer "B.Cu")
		(net "P1V8_C")
	)
	(segment
		(start 182.5244 -31.675324)
		(end 182.999888 -31.199836)
		(width 0.3048)
		(layer "B.Cu")
		(net "P1V8_C")
	)
	(segment
		(start 175.803814 -48.795686)
		(end 175.79975 -48.79975)
		(width 0.3048)
		(layer "B.Cu")
		(net "P1V8_C")
	)
	(segment
		(start 174.199804 -48.79975)
		(end 174.199804 -49.180496)
		(width 0.3048)
		(layer "B.Cu")
		(net "P1V8_C")
	)
	(segment
		(start 183.515 -32.68853)
		(end 183.21528 -32.68853)
		(width 0.3048)
		(layer "B.Cu")
		(net "P1V8_C")
	)
	(segment
		(start 174.310548 -107.381548)
		(end 173.109128 -107.381548)
		(width 0.508)
		(layer "B.Cu")
		(net "P1V8_C")
	)
	(segment
		(start 177.58664 -110.65764)
		(end 185.59018 -110.65764)
		(width 0.508)
		(layer "B.Cu")
		(net "P1V8_C")
	)
	(segment
		(start 174.495968 -48.503586)
		(end 174.199804 -48.79975)
		(width 0.3048)
		(layer "B.Cu")
		(net "P1V8_C")
	)
	(segment
		(start 183.756808 -33.53435)
		(end 183.756808 -34.357056)
		(width 0.3048)
		(layer "B.Cu")
		(net "P1V8_C")
	)
	(segment
		(start 182.7784 -30.353)
		(end 182.7784 -30.978348)
		(width 0.3048)
		(layer "B.Cu")
		(net "P1V8_C")
	)
	(segment
		(start 166.863776 -45.594016)
		(end 166.205408 -45.594016)
		(width 0.3048)
		(layer "B.Cu")
		(net "P1V8_C")
	)
	(segment
		(start 179.68849 -48.203358)
		(end 179.68849 -48.688498)
		(width 0.3048)
		(layer "B.Cu")
		(net "P1V8_C")
	)
	(segment
		(start 184.186068 -48.413416)
		(end 183.799734 -48.79975)
		(width 0.3048)
		(layer "B.Cu")
		(net "P1V8_C")
	)
	(segment
		(start 184.186068 -48.05299)
		(end 184.186068 -48.413416)
		(width 0.3048)
		(layer "B.Cu")
		(net "P1V8_C")
	)
	(segment
		(start 167.065198 -49.481232)
		(end 167.065198 -48.865028)
		(width 0.3048)
		(layer "B.Cu")
		(net "P1V8_C")
	)
	(segment
		(start 183.799734 -37.599874)
		(end 183.424068 -37.224208)
		(width 0.3048)
		(layer "B.Cu")
		(net "P1V8_C")
	)
	(segment
		(start 168.519348 -48.880268)
		(end 168.519348 -49.70907)
		(width 0.508)
		(layer "B.Cu")
		(net "P1V8_C")
	)
	(segment
		(start 188.068458 -40.72001)
		(end 188.201808 -40.58666)
		(width 0.508)
		(layer "B.Cu")
		(net "P1V8_C")
	)
	(segment
		(start 183.424068 -45.224192)
		(end 183.799734 -45.599858)
		(width 0.3048)
		(layer "B.Cu")
		(net "P1V8_C")
	)
	(segment
		(start 201.698098 -74.027284)
		(end 201.634598 -74.090784)
		(width 0.3048)
		(layer "B.Cu")
		(net "P1V8_C")
	)
	(segment
		(start 179.631848 -49.62271)
		(end 179.799742 -49.454816)
		(width 0.3048)
		(layer "B.Cu")
		(net "P1V8_C")
	)
	(segment
		(start 183.799734 -47.199804)
		(end 184.186068 -46.81347)
		(width 0.3048)
		(layer "B.Cu")
		(net "P1V8_C")
	)
	(segment
		(start 179.7304 -31.75)
		(end 179.7304 -31.269686)
		(width 0.3048)
		(layer "B.Cu")
		(net "P1V8_C")
	)
	(segment
		(start 180.5432 -55.890414)
		(end 180.5432 -55.3847)
		(width 0.508)
		(layer "B.Cu")
		(net "P1V8_C")
	)
	(segment
		(start 170.470068 -49.070006)
		(end 170.199812 -48.79975)
		(width 0.508)
		(layer "B.Cu")
		(net "P1V8_C")
	)
	(segment
		(start 175.8188 -108.8898)
		(end 177.58664 -110.65764)
		(width 0.508)
		(layer "B.Cu")
		(net "P1V8_C")
	)
	(segment
		(start 184.186068 -36.87191)
		(end 184.186068 -37.21354)
		(width 0.3048)
		(layer "B.Cu")
		(net "P1V8_C")
	)
	(segment
		(start 183.6928 -35.892994)
		(end 183.799734 -35.999928)
		(width 0.3048)
		(layer "B.Cu")
		(net "P1V8_C")
	)
	(segment
		(start 193.18351 -34.641282)
		(end 194.200018 -34.641282)
		(width 0.508)
		(layer "B.Cu")
		(net "P1V8_C")
	)
	(segment
		(start 179.68849 -48.688498)
		(end 179.799742 -48.79975)
		(width 0.3048)
		(layer "B.Cu")
		(net "P1V8_C")
	)
	(segment
		(start 183.424068 -37.224208)
		(end 183.424068 -36.87191)
		(width 0.3048)
		(layer "B.Cu")
		(net "P1V8_C")
	)
	(segment
		(start 173.439836 -50.384964)
		(end 173.439836 -51.19243)
		(width 0.3048)
		(layer "B.Cu")
		(net "P1V8_C")
	)
	(segment
		(start 174.199804 -49.180496)
		(end 173.909228 -49.471072)
		(width 0.3048)
		(layer "B.Cu")
		(net "P1V8_C")
	)
	(segment
		(start 189.1538 -24.8666)
		(end 189.2554 -24.765)
		(width 0.508)
		(layer "B.Cu")
		(net "P1V8_C")
	)
	(segment
		(start 182.7784 -30.978348)
		(end 182.999888 -31.199836)
		(width 0.3048)
		(layer "B.Cu")
		(net "P1V8_C")
	)
	(segment
		(start 192.397634 -37.641022)
		(end 192.397634 -36.8427)
		(width 0.508)
		(layer "B.Cu")
		(net "P1V8_C")
	)
	(segment
		(start 175.039528 -49.598072)
		(end 175.039528 -49.87163)
		(width 0.3556)
		(layer "B.Cu")
		(net "P1V8_C")
	)
	(segment
		(start 183.876188 -32.230314)
		(end 183.876188 -32.723328)
		(width 0.3048)
		(layer "B.Cu")
		(net "P1V8_C")
	)
	(segment
		(start 168.599866 -48.79975)
		(end 168.519348 -48.880268)
		(width 0.508)
		(layer "B.Cu")
		(net "P1V8_C")
	)
	(segment
		(start 187.5917 -24.8666)
		(end 189.1538 -24.8666)
		(width 0.508)
		(layer "B.Cu")
		(net "P1V8_C")
	)
	(segment
		(start 181.399942 -31.199836)
		(end 181.6862 -30.913578)
		(width 0.3048)
		(layer "B.Cu")
		(net "P1V8_C")
	)
	(segment
		(start 192.4685 -40.8432)
		(end 193.2051 -40.8432)
		(width 0.508)
		(layer "B.Cu")
		(net "P1V8_C")
	)
	(segment
		(start 183.424068 -48.05299)
		(end 183.424068 -48.424084)
		(width 0.3048)
		(layer "B.Cu")
		(net "P1V8_C")
	)
	(segment
		(start 173.909228 -49.915572)
		(end 173.439836 -50.384964)
		(width 0.3048)
		(layer "B.Cu")
		(net "P1V8_C")
	)
	(segment
		(start 178.1302 -31.13024)
		(end 178.1302 -30.353)
		(width 0.3048)
		(layer "B.Cu")
		(net "P1V8_C")
	)
	(segment
		(start 183.642 -42.242232)
		(end 183.799734 -42.399966)
		(width 0.3048)
		(layer "B.Cu")
		(net "P1V8_C")
	)
	(segment
		(start 168.530778 -48.07712)
		(end 168.530778 -48.730662)
		(width 0.3048)
		(layer "B.Cu")
		(net "P1V8_C")
	)
	(segment
		(start 179.799996 -31.20009)
		(end 179.9082 -31.091886)
		(width 0.3048)
		(layer "B.Cu")
		(net "P1V8_C")
	)
	(segment
		(start 188.043566 -40.396668)
		(end 188.043566 -39.598346)
		(width 0.508)
		(layer "B.Cu")
		(net "P1V8_C")
	)
	(segment
		(start 184.186068 -37.21354)
		(end 183.799734 -37.599874)
		(width 0.3048)
		(layer "B.Cu")
		(net "P1V8_C")
	)
	(segment
		(start 184.43067 -49.663858)
		(end 184.43067 -49.430686)
		(width 0.3048)
		(layer "B.Cu")
		(net "P1V8_C")
	)
	(segment
		(start 177.698908 -49.468278)
		(end 178.199796 -48.96739)
		(width 0.3048)
		(layer "B.Cu")
		(net "P1V8_C")
	)
	(segment
		(start 181.6862 -30.913578)
		(end 181.6862 -30.353)
		(width 0.3048)
		(layer "B.Cu")
		(net "P1V8_C")
	)
	(segment
		(start 193.2305 -43.053)
		(end 193.2432 -43.0657)
		(width 0.508)
		(layer "B.Cu")
		(net "P1V8_C")
	)
	(segment
		(start 180.7972 -56.144414)
		(end 180.5432 -55.890414)
		(width 0.508)
		(layer "B.Cu")
		(net "P1V8_C")
	)
	(segment
		(start 193.18351 -35.669982)
		(end 193.937382 -35.669982)
		(width 0.508)
		(layer "B.Cu")
		(net "P1V8_C")
	)
	(segment
		(start 203.22032 -74.027284)
		(end 201.698098 -74.027284)
		(width 0.3048)
		(layer "B.Cu")
		(net "P1V8_C")
	)
	(segment
		(start 183.424068 -43.624246)
		(end 183.799734 -43.999912)
		(width 0.3048)
		(layer "B.Cu")
		(net "P1V8_C")
	)
	(segment
		(start 181.995318 -48.204374)
		(end 181.399942 -48.79975)
		(width 0.3048)
		(layer "B.Cu")
		(net "P1V8_C")
	)
	(segment
		(start 178.20005 -31.20009)
		(end 178.1302 -31.13024)
		(width 0.3048)
		(layer "B.Cu")
		(net "P1V8_C")
	)
	(segment
		(start 188.233558 -40.58666)
		(end 188.043566 -40.396668)
		(width 0.508)
		(layer "B.Cu")
		(net "P1V8_C")
	)
	(segment
		(start 183.876188 -32.723328)
		(end 183.799734 -32.799782)
		(width 0.3048)
		(layer "B.Cu")
		(net "P1V8_C")
	)
	(segment
		(start 183.358282 -49.241202)
		(end 183.799734 -48.79975)
		(width 0.3048)
		(layer "B.Cu")
		(net "P1V8_C")
	)
	(segment
		(start 179.7304 -31.269686)
		(end 179.799996 -31.20009)
		(width 0.3048)
		(layer "B.Cu")
		(net "P1V8_C")
	)
	(segment
		(start 184.186068 -40.05961)
		(end 184.186068 -40.413432)
		(width 0.3048)
		(layer "B.Cu")
		(net "P1V8_C")
	)
	(segment
		(start 183.424068 -46.42993)
		(end 183.424068 -46.824138)
		(width 0.3048)
		(layer "B.Cu")
		(net "P1V8_C")
	)
	(segment
		(start 181.229 -35.2298)
		(end 182.245 -35.2298)
		(width 0.508)
		(layer "B.Cu")
		(net "P1V8_C")
	)
	(segment
		(start 178.199796 -48.96739)
		(end 178.199796 -48.79975)
		(width 0.3048)
		(layer "B.Cu")
		(net "P1V8_C")
	)
	(segment
		(start 200.787 -34.8869)
		(end 199.771 -34.8869)
		(width 0.508)
		(layer "B.Cu")
		(net "P1V8_C")
	)
	(segment
		(start 187.376308 -40.72001)
		(end 188.068458 -40.72001)
		(width 0.508)
		(layer "B.Cu")
		(net "P1V8_C")
	)
	(segment
		(start 175.124872 -61.702188)
		(end 174.4726 -61.049916)
		(width 0.508)
		(layer "B.Cu")
		(net "P1V8_C")
	)
	(segment
		(start 178.4096 -31.75)
		(end 178.4096 -31.40964)
		(width 0.3048)
		(layer "B.Cu")
		(net "P1V8_C")
	)
	(segment
		(start 175.803814 -48.189642)
		(end 175.803814 -48.795686)
		(width 0.3048)
		(layer "B.Cu")
		(net "P1V8_C")
	)
	(segment
		(start 189.33414 -116.17706)
		(end 188.1886 -117.3226)
		(width 0.508)
		(layer "B.Cu")
		(net "P1V8_C")
	)
	(segment
		(start 167.065198 -48.865028)
		(end 166.99992 -48.79975)
		(width 0.3048)
		(layer "B.Cu")
		(net "P1V8_C")
	)
	(segment
		(start 182.8038 -55.77586)
		(end 182.8038 -55.3847)
		(width 0.508)
		(layer "B.Cu")
		(net "P1V8_C")
	)
	(segment
		(start 182.435246 -56.144414)
		(end 182.8038 -55.77586)
		(width 0.508)
		(layer "B.Cu")
		(net "P1V8_C")
	)
	(segment
		(start 173.909228 -49.471072)
		(end 173.909228 -49.65573)
		(width 0.3048)
		(layer "B.Cu")
		(net "P1V8_C")
	)
	(segment
		(start 179.9082 -31.091886)
		(end 179.9082 -30.353)
		(width 0.3048)
		(layer "B.Cu")
		(net "P1V8_C")
	)
	(segment
		(start 183.449468 -40.05961)
		(end 183.449468 -40.4495)
		(width 0.3048)
		(layer "B.Cu")
		(net "P1V8_C")
	)
	(segment
		(start 183.799734 -43.999912)
		(end 184.186068 -43.613578)
		(width 0.3048)
		(layer "B.Cu")
		(net "P1V8_C")
	)
	(segment
		(start 183.642 -41.7068)
		(end 183.642 -42.242232)
		(width 0.3048)
		(layer "B.Cu")
		(net "P1V8_C")
	)
	(segment
		(start 177.698908 -50.311812)
		(end 177.429414 -50.581306)
		(width 0.3048)
		(layer "B.Cu")
		(net "P1V8_C")
	)
	(segment
		(start 181.1274 -31.472378)
		(end 181.399942 -31.199836)
		(width 0.3048)
		(layer "B.Cu")
		(net "P1V8_C")
	)
	(segment
		(start 201.168 -58.2295)
		(end 189.51194 -58.2295)
		(width 0.508)
		(layer "B.Cu")
		(net "P1V8_C")
	)
	(segment
		(start 175.124872 -62.65037)
		(end 175.124872 -61.702188)
		(width 0.508)
		(layer "B.Cu")
		(net "P1V8_C")
	)
	(segment
		(start 177.698908 -49.50333)
		(end 177.698908 -49.468278)
		(width 0.3048)
		(layer "B.Cu")
		(net "P1V8_C")
	)
	(segment
		(start 175.79975 -48.83785)
		(end 175.039528 -49.598072)
		(width 0.3556)
		(layer "B.Cu")
		(net "P1V8_C")
	)
	(segment
		(start 183.424068 -38.824154)
		(end 183.424068 -38.39845)
		(width 0.3048)
		(layer "B.Cu")
		(net "P1V8_C")
	)
	(segment
		(start 164.852858 -48.660558)
		(end 165.260782 -48.660558)
		(width 0.3556)
		(layer "B.Cu")
		(net "P1V8_C")
	)
	(segment
		(start 193.18351 -34.641282)
		(end 193.18351 -33.573974)
		(width 0.508)
		(layer "B.Cu")
		(net "P1V8_C")
	)
	(segment
		(start 183.799734 -45.599858)
		(end 184.186068 -45.213524)
		(width 0.3048)
		(layer "B.Cu")
		(net "P1V8_C")
	)
	(segment
		(start 183.799734 -32.799782)
		(end 183.626252 -32.799782)
		(width 0.3048)
		(layer "B.Cu")
		(net "P1V8_C")
	)
	(segment
		(start 168.530778 -48.730662)
		(end 168.599866 -48.79975)
		(width 0.3048)
		(layer "B.Cu")
		(net "P1V8_C")
	)
	(segment
		(start 178.4096 -31.40964)
		(end 178.20005 -31.20009)
		(width 0.3048)
		(layer "B.Cu")
		(net "P1V8_C")
	)
	(segment
		(start 184.186068 -38.39845)
		(end 184.186068 -38.813486)
		(width 0.3048)
		(layer "B.Cu")
		(net "P1V8_C")
	)
	(segment
		(start 184.186068 -40.413432)
		(end 183.799734 -40.799766)
		(width 0.3048)
		(layer "B.Cu")
		(net "P1V8_C")
	)
	(segment
		(start 178.203352 -48.210724)
		(end 178.203352 -48.796194)
		(width 0.3048)
		(layer "B.Cu")
		(net "P1V8_C")
	)
	(segment
		(start 179.799742 -49.454816)
		(end 179.799742 -48.79975)
		(width 0.3048)
		(layer "B.Cu")
		(net "P1V8_C")
	)
	(segment
		(start 177.698908 -49.50333)
		(end 177.698908 -50.311812)
		(width 0.3048)
		(layer "B.Cu")
		(net "P1V8_C")
	)
	(segment
		(start 183.424068 -44.78401)
		(end 183.424068 -45.224192)
		(width 0.3048)
		(layer "B.Cu")
		(net "P1V8_C")
	)
	(segment
		(start 199.771 -34.8869)
		(end 199.771 -34.107882)
		(width 0.508)
		(layer "B.Cu")
		(net "P1V8_C")
	)
	(segment
		(start 169.632122 -43.19524)
		(end 170.19524 -43.19524)
		(width 0.3048)
		(layer "B.Cu")
		(net "P1V8_C")
	)
	(segment
		(start 166.282116 -44.082208)
		(end 166.19982 -43.999912)
		(width 0.3048)
		(layer "B.Cu")
		(net "P1V8_C")
	)
	(segment
		(start 183.449468 -40.4495)
		(end 183.799734 -40.799766)
		(width 0.3048)
		(layer "B.Cu")
		(net "P1V8_C")
	)
	(segment
		(start 183.274716 -34.925)
		(end 183.799734 -34.399982)
		(width 0.3048)
		(layer "B.Cu")
		(net "P1V8_C")
	)
	(segment
		(start 184.186068 -38.813486)
		(end 183.799734 -39.19982)
		(width 0.3048)
		(layer "B.Cu")
		(net "P1V8_C")
	)
	(segment
		(start 188.201808 -40.58666)
		(end 188.233558 -40.58666)
		(width 0.508)
		(layer "B.Cu")
		(net "P1V8_C")
	)
	(segment
		(start 165.399974 -43.27779)
		(end 165.399974 -42.399966)
		(width 0.508)
		(layer "B.Cu")
		(net "P1V8_C")
	)
	(segment
		(start 170.470068 -49.71161)
		(end 170.470068 -49.070006)
		(width 0.508)
		(layer "B.Cu")
		(net "P1V8_C")
	)
	(segment
		(start 181.51348 -56.144414)
		(end 180.7972 -56.144414)
		(width 0.508)
		(layer "B.Cu")
		(net "P1V8_C")
	)
	(segment
		(start 189.33414 -114.4016)
		(end 189.33414 -116.17706)
		(width 0.508)
		(layer "B.Cu")
		(net "P1V8_C")
	)
	(segment
		(start 166.84625 -44.082208)
		(end 166.282116 -44.082208)
		(width 0.3048)
		(layer "B.Cu")
		(net "P1V8_C")
	)
	(segment
		(start 166.182802 -42.399966)
		(end 165.399974 -42.399966)
		(width 0.508)
		(layer "B.Cu")
		(net "P1V8_C")
	)
	(segment
		(start 180.999384 -70.245732)
		(end 179.723796 -70.245732)
		(width 0.508)
		(layer "B.Cu")
		(net "P1V8_C")
	)
	(segment
		(start 193.937382 -35.669982)
		(end 194.2084 -35.941)
		(width 0.508)
		(layer "B.Cu")
		(net "P1V8_C")
	)
	(segment
		(start 173.109128 -107.381548)
		(end 171.2341 -105.50652)
		(width 0.508)
		(layer "B.Cu")
		(net "P1V8_C")
	)
	(segment
		(start 175.8188 -108.8898)
		(end 174.310548 -107.381548)
		(width 0.508)
		(layer "B.Cu")
		(net "P1V8_C")
	)
	(segment
		(start 183.799734 -39.19982)
		(end 183.424068 -38.824154)
		(width 0.3048)
		(layer "B.Cu")
		(net "P1V8_C")
	)
	(segment
		(start 183.6928 -35.433)
		(end 183.6928 -35.892994)
		(width 0.3048)
		(layer "B.Cu")
		(net "P1V8_C")
	)
	(segment
		(start 183.424068 -43.19651)
		(end 183.424068 -43.624246)
		(width 0.3048)
		(layer "B.Cu")
		(net "P1V8_C")
	)
	(segment
		(start 170.548808 -50.98161)
		(end 170.548808 -49.79035)
		(width 0.3048)
		(layer "B.Cu")
		(net "P1V8_C")
	)
	(segment
		(start 174.495968 -48.194722)
		(end 174.495968 -48.503586)
		(width 0.3048)
		(layer "B.Cu")
		(net "P1V8_C")
	)
	(segment
		(start 181.1274 -31.75)
		(end 181.1274 -31.472378)
		(width 0.3048)
		(layer "B.Cu")
		(net "P1V8_C")
	)
	(segment
		(start 154.077924 -80.887824)
		(end 156.973524 -80.887824)
		(width 0.508)
		(layer "F.Cu")
		(net "P1V5_E")
	)
	(segment
		(start 156.973524 -80.887824)
		(end 157.2006 -81.1149)
		(width 0.508)
		(layer "F.Cu")
		(net "P1V5_E")
	)
	(segment
		(start 153.3271 -80.137)
		(end 154.077924 -80.887824)
		(width 0.508)
		(layer "F.Cu")
		(net "P1V5_E")
	)
	(via
		(at 144.0688 -103.5558)
		(size 0.7112)
		(drill 0.4064)
		(layers "F.Cu" "B.Cu")
		(net "P1V5_E")
	)
	(via
		(at 145.339816 -103.5558)
		(size 0.6096)
		(drill 0.3048)
		(layers "F.Cu" "B.Cu")
		(net "P1V5_E")
	)
	(via
		(at 137.7442 -101.4476)
		(size 0.6604)
		(drill 0.3302)
		(layers "F.Cu" "B.Cu")
		(net "P1V5_E")
	)
	(via
		(at 140.2588 -101.3968)
		(size 0.6604)
		(drill 0.3302)
		(layers "F.Cu" "B.Cu")
		(net "P1V5_E")
	)
	(via
		(at 153.3271 -80.137)
		(size 0.508)
		(drill 0.254)
		(layers "F.Cu" "B.Cu")
		(net "P1V5_E")
	)
	(segment
		(start 154.9146 -102.743)
		(end 154.1018 -103.5558)
		(width 0.508)
		(layer "B.Cu")
		(net "P1V5_E")
	)
	(segment
		(start 153.3271 -80.137)
		(end 151.864314 -80.137)
		(width 0.508)
		(layer "B.Cu")
		(net "P1V5_E")
	)
	(segment
		(start 154.1018 -103.5558)
		(end 145.339816 -103.5558)
		(width 0.508)
		(layer "B.Cu")
		(net "P1V5_E")
	)
	(segment
		(start 154.2288 -93.1672)
		(end 154.9146 -93.853)
		(width 0.508)
		(layer "B.Cu")
		(net "P1V5_E")
	)
	(segment
		(start 151.023828 -80.977486)
		(end 151.023828 -84.298028)
		(width 0.508)
		(layer "B.Cu")
		(net "P1V5_E")
	)
	(segment
		(start 154.2288 -87.503)
		(end 154.2288 -93.1672)
		(width 0.508)
		(layer "B.Cu")
		(net "P1V5_E")
	)
	(segment
		(start 151.023828 -84.298028)
		(end 154.2288 -87.503)
		(width 0.508)
		(layer "B.Cu")
		(net "P1V5_E")
	)
	(segment
		(start 144.0688 -103.5558)
		(end 145.339816 -103.5558)
		(width 0.508)
		(layer "B.Cu")
		(net "P1V5_E")
	)
	(segment
		(start 151.864314 -80.137)
		(end 151.023828 -80.977486)
		(width 0.508)
		(layer "B.Cu")
		(net "P1V5_E")
	)
	(segment
		(start 154.9146 -93.853)
		(end 154.9146 -102.743)
		(width 0.508)
		(layer "B.Cu")
		(net "P1V5_E")
	)
	(segment
		(start 156.685488 -68.20789)
		(end 150.433024 -68.20789)
		(width 1.016)
		(layer "F.Cu")
		(net "P1V5_C")
	)
	(segment
		(start 148.790914 -107.319826)
		(end 148.40712 -107.70362)
		(width 1.016)
		(layer "F.Cu")
		(net "P1V5_C")
	)
	(segment
		(start 157.606746 -69.129148)
		(end 156.685488 -68.20789)
		(width 1.016)
		(layer "F.Cu")
		(net "P1V5_C")
	)
	(segment
		(start 148.790914 -69.85)
		(end 148.790914 -107.319826)
		(width 1.016)
		(layer "F.Cu")
		(net "P1V5_C")
	)
	(segment
		(start 150.433024 -68.20789)
		(end 148.790914 -69.85)
		(width 1.016)
		(layer "F.Cu")
		(net "P1V5_C")
	)
	(via
		(at 204.2922 -28.2702)
		(size 0.6096)
		(drill 0.3048)
		(layers "F.Cu" "B.Cu")
		(net "P1V5_C")
	)
	(via
		(at 148.40712 -107.70362)
		(size 0.508)
		(drill 0.254)
		(layers "F.Cu" "B.Cu")
		(net "P1V5_C")
	)
	(via
		(at 134.493 -119.761)
		(size 0.7112)
		(drill 0.4064)
		(layers "F.Cu" "B.Cu")
		(net "P1V5_C")
	)
	(via
		(at 203.073 -26.924)
		(size 0.508)
		(drill 0.254)
		(layers "F.Cu" "B.Cu")
		(net "P1V5_C")
	)
	(segment
		(start 131.318 -107.1118)
		(end 130.65887 -107.77093)
		(width 0.508)
		(layer "B.Cu")
		(net "P1V5_C")
	)
	(segment
		(start 148.40712 -107.70362)
		(end 143.196056 -107.70362)
		(width 0.508)
		(layer "B.Cu")
		(net "P1V5_C")
	)
	(segment
		(start 132.1181 -111.962692)
		(end 132.1181 -116.0272)
		(width 0.508)
		(layer "B.Cu")
		(net "P1V5_C")
	)
	(segment
		(start 130.65887 -107.77093)
		(end 130.65887 -110.503462)
		(width 0.508)
		(layer "B.Cu")
		(net "P1V5_C")
	)
	(segment
		(start 130.65887 -110.503462)
		(end 132.1181 -111.962692)
		(width 0.508)
		(layer "B.Cu")
		(net "P1V5_C")
	)
	(segment
		(start 142.604236 -107.1118)
		(end 131.318 -107.1118)
		(width 0.508)
		(layer "B.Cu")
		(net "P1V5_C")
	)
	(segment
		(start 143.196056 -107.70362)
		(end 142.604236 -107.1118)
		(width 0.508)
		(layer "B.Cu")
		(net "P1V5_C")
	)
	(segment
		(start 202.441048 -59.114944)
		(end 204.076808 -60.750704)
		(width 1.016)
		(layer "In2.Cu")
		(net "P1V5_C")
	)
	(segment
		(start 202.661774 -70.993)
		(end 202.661774 -111.866426)
		(width 1.016)
		(layer "In2.Cu")
		(net "P1V5_C")
	)
	(segment
		(start 143.602456 -125.569472)
		(end 137.793984 -119.761)
		(width 1.016)
		(layer "In2.Cu")
		(net "P1V5_C")
	)
	(segment
		(start 203.595478 -66.635122)
		(end 203.595478 -70.059296)
		(width 1.016)
		(layer "In2.Cu")
		(net "P1V5_C")
	)
	(segment
		(start 202.661774 -111.866426)
		(end 188.958728 -125.569472)
		(width 1.016)
		(layer "In2.Cu")
		(net "P1V5_C")
	)
	(segment
		(start 137.793984 -119.761)
		(end 134.493 -119.761)
		(width 1.016)
		(layer "In2.Cu")
		(net "P1V5_C")
	)
	(segment
		(start 204.076808 -60.750704)
		(end 204.076808 -66.153792)
		(width 1.016)
		(layer "In2.Cu")
		(net "P1V5_C")
	)
	(segment
		(start 203.595478 -70.059296)
		(end 202.661774 -70.993)
		(width 1.016)
		(layer "In2.Cu")
		(net "P1V5_C")
	)
	(segment
		(start 204.076808 -66.153792)
		(end 203.595478 -66.635122)
		(width 1.016)
		(layer "In2.Cu")
		(net "P1V5_C")
	)
	(segment
		(start 203.073 -26.924)
		(end 203.073 -43.721274)
		(width 1.016)
		(layer "In2.Cu")
		(net "P1V5_C")
	)
	(segment
		(start 202.441048 -44.353226)
		(end 202.441048 -59.114944)
		(width 1.016)
		(layer "In2.Cu")
		(net "P1V5_C")
	)
	(segment
		(start 188.958728 -125.569472)
		(end 143.602456 -125.569472)
		(width 1.016)
		(layer "In2.Cu")
		(net "P1V5_C")
	)
	(segment
		(start 203.073 -43.721274)
		(end 202.441048 -44.353226)
		(width 1.016)
		(layer "In2.Cu")
		(net "P1V5_C")
	)
	(segment
		(start 158.660084 -75.519026)
		(end 157.81528 -75.519026)
		(width 0.127)
		(layer "F.Cu")
		(net "P0V975_SENSE")
	)
	(segment
		(start 158.806896 -75.372214)
		(end 158.660084 -75.519026)
		(width 0.127)
		(layer "F.Cu")
		(net "P0V975_SENSE")
	)
	(segment
		(start 159.8295 -73.147936)
		(end 159.8295 -73.34123)
		(width 0.127)
		(layer "F.Cu")
		(net "P0V975_SENSE")
	)
	(segment
		(start 159.8295 -73.34123)
		(end 159.8295 -74.734166)
		(width 0.127)
		(layer "F.Cu")
		(net "P0V975_SENSE")
	)
	(segment
		(start 160.245552 -72.168766)
		(end 160.245552 -72.731884)
		(width 0.127)
		(layer "F.Cu")
		(net "P0V975_SENSE")
	)
	(segment
		(start 159.8295 -71.157338)
		(end 160.245552 -71.57339)
		(width 0.127)
		(layer "F.Cu")
		(net "P0V975_SENSE")
	)
	(segment
		(start 160.245552 -72.731884)
		(end 159.8295 -73.147936)
		(width 0.127)
		(layer "F.Cu")
		(net "P0V975_SENSE")
	)
	(segment
		(start 159.191452 -75.372214)
		(end 158.806896 -75.372214)
		(width 0.127)
		(layer "F.Cu")
		(net "P0V975_SENSE")
	)
	(segment
		(start 159.8295 -74.734166)
		(end 159.191452 -75.372214)
		(width 0.127)
		(layer "F.Cu")
		(net "P0V975_SENSE")
	)
	(segment
		(start 159.8295 -70.80123)
		(end 159.8295 -71.157338)
		(width 0.127)
		(layer "F.Cu")
		(net "P0V975_SENSE")
	)
	(segment
		(start 160.245552 -71.57339)
		(end 160.245552 -72.168766)
		(width 0.127)
		(layer "F.Cu")
		(net "P0V975_SENSE")
	)
	(via
		(at 160.245552 -72.168766)
		(size 0.6604)
		(drill 0.3302)
		(layers "F.Cu" "B.Cu")
		(net "P0V975_SENSE")
	)
	(segment
		(start 172.599858 -44.000166)
		(end 172.999654 -44.399962)
		(width 0.3048)
		(layer "F.Cu")
		(net "P0V975")
	)
	(segment
		(start 174.599854 -37.999924)
		(end 174.199804 -37.599874)
		(width 0.3048)
		(layer "F.Cu")
		(net "P0V975")
	)
	(segment
		(start 177.8 -37.999924)
		(end 177.39995 -37.599874)
		(width 0.3048)
		(layer "F.Cu")
		(net "P0V975")
	)
	(segment
		(start 174.645574 -100.830126)
		(end 174.391574 -101.084126)
		(width 0.508)
		(layer "F.Cu")
		(net "P0V975")
	)
	(segment
		(start 176.1998 -39.599616)
		(end 176.1998 -39.59987)
		(width 0.3048)
		(layer "F.Cu")
		(net "P0V975")
	)
	(segment
		(start 175.399954 -38.800024)
		(end 175.400208 -38.800024)
		(width 0.3048)
		(layer "F.Cu")
		(net "P0V975")
	)
	(segment
		(start 174.599854 -42.800016)
		(end 174.199804 -42.399966)
		(width 0.3048)
		(layer "F.Cu")
		(net "P0V975")
	)
	(segment
		(start 179.399692 -36.399978)
		(end 178.599846 -37.199824)
		(width 0.3048)
		(layer "F.Cu")
		(net "P0V975")
	)
	(segment
		(start 174.199804 -43.999912)
		(end 173.800008 -43.600116)
		(width 0.3048)
		(layer "F.Cu")
		(net "P0V975")
	)
	(segment
		(start 174.378874 -101.084126)
		(end 173.8376 -101.6254)
		(width 0.508)
		(layer "F.Cu")
		(net "P0V975")
	)
	(segment
		(start 179.399946 -36.399978)
		(end 179.399692 -36.399978)
		(width 0.3048)
		(layer "F.Cu")
		(net "P0V975")
	)
	(segment
		(start 172.199808 -38.800024)
		(end 172.200062 -38.800024)
		(width 0.3556)
		(layer "F.Cu")
		(net "P0V975")
	)
	(segment
		(start 179.399946 -39.59987)
		(end 178.999896 -39.19982)
		(width 0.3048)
		(layer "F.Cu")
		(net "P0V975")
	)
	(segment
		(start 175.399954 -41.999916)
		(end 175.800004 -42.399966)
		(width 0.3048)
		(layer "F.Cu")
		(net "P0V975")
	)
	(segment
		(start 175.800004 -39.19982)
		(end 176.1998 -39.599616)
		(width 0.3048)
		(layer "F.Cu")
		(net "P0V975")
	)
	(segment
		(start 172.200062 -40.39997)
		(end 172.599858 -40.799766)
		(width 0.3556)
		(layer "F.Cu")
		(net "P0V975")
	)
	(segment
		(start 174.199804 -37.599874)
		(end 173.800008 -37.200078)
		(width 0.3048)
		(layer "F.Cu")
		(net "P0V975")
	)
	(segment
		(start 176.1998 -37.99967)
		(end 176.1998 -37.999924)
		(width 0.3048)
		(layer "F.Cu")
		(net "P0V975")
	)
	(segment
		(start 172.200062 -38.800024)
		(end 172.599858 -39.19982)
		(width 0.3556)
		(layer "F.Cu")
		(net "P0V975")
	)
	(segment
		(start 175.399954 -37.199824)
		(end 175.800004 -37.599874)
		(width 0.3048)
		(layer "F.Cu")
		(net "P0V975")
	)
	(segment
		(start 177.39995 -39.19982)
		(end 177.000154 -38.800024)
		(width 0.3048)
		(layer "F.Cu")
		(net "P0V975")
	)
	(segment
		(start 174.645574 -100.554282)
		(end 174.645574 -100.830126)
		(width 0.508)
		(layer "F.Cu")
		(net "P0V975")
	)
	(segment
		(start 176.1998 -42.799762)
		(end 176.1998 -42.800016)
		(width 0.3048)
		(layer "F.Cu")
		(net "P0V975")
	)
	(segment
		(start 172.999908 -39.59987)
		(end 172.599858 -39.19982)
		(width 0.3556)
		(layer "F.Cu")
		(net "P0V975")
	)
	(segment
		(start 173.800008 -37.200078)
		(end 173.800008 -37.199824)
		(width 0.3048)
		(layer "F.Cu")
		(net "P0V975")
	)
	(segment
		(start 172.200062 -45.199808)
		(end 172.999908 -44.399962)
		(width 0.3556)
		(layer "F.Cu")
		(net "P0V975")
	)
	(segment
		(start 177.39995 -42.399966)
		(end 176.9999 -41.999916)
		(width 0.3048)
		(layer "F.Cu")
		(net "P0V975")
	)
	(segment
		(start 175.800004 -40.799766)
		(end 176.1998 -41.199562)
		(width 0.3048)
		(layer "F.Cu")
		(net "P0V975")
	)
	(segment
		(start 178.999896 -39.19982)
		(end 178.6001 -38.800024)
		(width 0.3048)
		(layer "F.Cu")
		(net "P0V975")
	)
	(segment
		(start 172.999654 -44.399962)
		(end 172.999908 -44.399962)
		(width 0.3048)
		(layer "F.Cu")
		(net "P0V975")
	)
	(segment
		(start 179.399946 -42.800016)
		(end 178.999896 -42.399966)
		(width 0.3048)
		(layer "F.Cu")
		(net "P0V975")
	)
	(segment
		(start 172.199808 -40.39997)
		(end 172.200062 -40.39997)
		(width 0.3556)
		(layer "F.Cu")
		(net "P0V975")
	)
	(segment
		(start 175.399954 -43.599862)
		(end 175.800004 -43.999912)
		(width 0.3048)
		(layer "F.Cu")
		(net "P0V975")
	)
	(segment
		(start 177.39995 -37.599874)
		(end 176.9999 -37.199824)
		(width 0.3048)
		(layer "F.Cu")
		(net "P0V975")
	)
	(segment
		(start 174.199804 -42.399966)
		(end 173.800008 -42.00017)
		(width 0.3048)
		(layer "F.Cu")
		(net "P0V975")
	)
	(segment
		(start 175.800004 -42.399966)
		(end 176.1998 -42.799762)
		(width 0.3048)
		(layer "F.Cu")
		(net "P0V975")
	)
	(segment
		(start 172.599858 -42.399966)
		(end 172.199808 -41.999916)
		(width 0.3048)
		(layer "F.Cu")
		(net "P0V975")
	)
	(segment
		(start 175.800004 -37.599874)
		(end 176.1998 -37.99967)
		(width 0.3048)
		(layer "F.Cu")
		(net "P0V975")
	)
	(segment
		(start 175.800004 -35.999928)
		(end 176.1998 -36.399724)
		(width 0.3048)
		(layer "F.Cu")
		(net "P0V975")
	)
	(segment
		(start 172.199808 -45.199808)
		(end 172.200062 -45.199808)
		(width 0.3556)
		(layer "F.Cu")
		(net "P0V975")
	)
	(segment
		(start 177.8 -41.199816)
		(end 177.39995 -40.799766)
		(width 0.3048)
		(layer "F.Cu")
		(net "P0V975")
	)
	(segment
		(start 160.7185 -70.80123)
		(end 163.614862 -70.80123)
		(width 0.508)
		(layer "F.Cu")
		(net "P0V975")
	)
	(segment
		(start 176.9999 -43.599862)
		(end 177.39995 -43.999912)
		(width 0.3048)
		(layer "F.Cu")
		(net "P0V975")
	)
	(segment
		(start 177.39995 -40.799766)
		(end 177.000154 -40.39997)
		(width 0.3048)
		(layer "F.Cu")
		(net "P0V975")
	)
	(segment
		(start 176.1998 -41.199562)
		(end 176.1998 -41.199816)
		(width 0.3048)
		(layer "F.Cu")
		(net "P0V975")
	)
	(segment
		(start 178.999896 -42.399966)
		(end 178.599846 -41.999916)
		(width 0.3048)
		(layer "F.Cu")
		(net "P0V975")
	)
	(segment
		(start 178.999896 -40.799766)
		(end 178.6001 -40.39997)
		(width 0.3048)
		(layer "F.Cu")
		(net "P0V975")
	)
	(segment
		(start 173.800008 -38.800024)
		(end 174.199804 -39.19982)
		(width 0.3048)
		(layer "F.Cu")
		(net "P0V975")
	)
	(segment
		(start 173.800008 -42.00017)
		(end 173.800008 -41.999916)
		(width 0.3048)
		(layer "F.Cu")
		(net "P0V975")
	)
	(segment
		(start 172.999908 -41.199816)
		(end 172.599858 -40.799766)
		(width 0.3556)
		(layer "F.Cu")
		(net "P0V975")
	)
	(segment
		(start 176.1998 -36.399724)
		(end 176.1998 -36.399978)
		(width 0.3048)
		(layer "F.Cu")
		(net "P0V975")
	)
	(segment
		(start 177.8 -36.399978)
		(end 177.39995 -35.999928)
		(width 0.3048)
		(layer "F.Cu")
		(net "P0V975")
	)
	(segment
		(start 178.999896 -37.599874)
		(end 178.599846 -37.199824)
		(width 0.3048)
		(layer "F.Cu")
		(net "P0V975")
	)
	(segment
		(start 174.199804 -40.799766)
		(end 173.800008 -40.39997)
		(width 0.3048)
		(layer "F.Cu")
		(net "P0V975")
	)
	(segment
		(start 177.8 -42.800016)
		(end 177.39995 -42.399966)
		(width 0.3048)
		(layer "F.Cu")
		(net "P0V975")
	)
	(segment
		(start 178.999896 -43.999912)
		(end 179.399946 -44.399962)
		(width 0.3048)
		(layer "F.Cu")
		(net "P0V975")
	)
	(segment
		(start 177.000154 -40.39997)
		(end 176.9999 -40.39997)
		(width 0.3048)
		(layer "F.Cu")
		(net "P0V975")
	)
	(segment
		(start 171.399962 -42.80027)
		(end 171.000166 -43.200066)
		(width 0.3556)
		(layer "F.Cu")
		(net "P0V975")
	)
	(segment
		(start 175.400208 -38.800024)
		(end 175.800004 -39.19982)
		(width 0.3048)
		(layer "F.Cu")
		(net "P0V975")
	)
	(segment
		(start 174.391574 -101.084126)
		(end 174.378874 -101.084126)
		(width 0.508)
		(layer "F.Cu")
		(net "P0V975")
	)
	(segment
		(start 174.199804 -39.19982)
		(end 174.599854 -39.59987)
		(width 0.3048)
		(layer "F.Cu")
		(net "P0V975")
	)
	(segment
		(start 179.399946 -41.199816)
		(end 178.999896 -40.799766)
		(width 0.3048)
		(layer "F.Cu")
		(net "P0V975")
	)
	(segment
		(start 178.599846 -43.599862)
		(end 178.999896 -43.999912)
		(width 0.3048)
		(layer "F.Cu")
		(net "P0V975")
	)
	(segment
		(start 178.6001 -40.39997)
		(end 178.599846 -40.39997)
		(width 0.3048)
		(layer "F.Cu")
		(net "P0V975")
	)
	(segment
		(start 177.000154 -38.800024)
		(end 176.9999 -38.800024)
		(width 0.3048)
		(layer "F.Cu")
		(net "P0V975")
	)
	(segment
		(start 171.399962 -42.800016)
		(end 171.399962 -42.80027)
		(width 0.3556)
		(layer "F.Cu")
		(net "P0V975")
	)
	(segment
		(start 175.400208 -40.39997)
		(end 175.800004 -40.799766)
		(width 0.3048)
		(layer "F.Cu")
		(net "P0V975")
	)
	(segment
		(start 174.599854 -41.199816)
		(end 174.199804 -40.799766)
		(width 0.3048)
		(layer "F.Cu")
		(net "P0V975")
	)
	(segment
		(start 172.999908 -42.800016)
		(end 172.599858 -42.399966)
		(width 0.3048)
		(layer "F.Cu")
		(net "P0V975")
	)
	(segment
		(start 172.999908 -37.999924)
		(end 172.599858 -37.599874)
		(width 0.3048)
		(layer "F.Cu")
		(net "P0V975")
	)
	(segment
		(start 178.6001 -38.800024)
		(end 178.599846 -38.800024)
		(width 0.3048)
		(layer "F.Cu")
		(net "P0V975")
	)
	(segment
		(start 177.8 -39.59987)
		(end 177.39995 -39.19982)
		(width 0.3048)
		(layer "F.Cu")
		(net "P0V975")
	)
	(segment
		(start 175.399954 -40.39997)
		(end 175.400208 -40.39997)
		(width 0.3048)
		(layer "F.Cu")
		(net "P0V975")
	)
	(segment
		(start 173.800008 -43.600116)
		(end 173.800008 -43.599862)
		(width 0.3048)
		(layer "F.Cu")
		(net "P0V975")
	)
	(segment
		(start 179.399946 -37.999924)
		(end 178.999896 -37.599874)
		(width 0.3048)
		(layer "F.Cu")
		(net "P0V975")
	)
	(via
		(at 181.5084 -88.519)
		(size 0.7112)
		(drill 0.4064)
		(layers "F.Cu" "B.Cu")
		(net "P0V975")
	)
	(via
		(at 188.5188 -95.4024)
		(size 0.7112)
		(drill 0.4064)
		(layers "F.Cu" "B.Cu")
		(net "P0V975")
	)
	(via
		(at 174.199804 -37.599874)
		(size 0.508)
		(drill 0.254)
		(layers "F.Cu" "B.Cu")
		(net "P0V975")
	)
	(via
		(at 178.2318 -85.8012)
		(size 0.7112)
		(drill 0.4064)
		(layers "F.Cu" "B.Cu")
		(net "P0V975")
	)
	(via
		(at 179.6034 -90.9828)
		(size 0.7112)
		(drill 0.4064)
		(layers "F.Cu" "B.Cu")
		(net "P0V975")
	)
	(via
		(at 180.975 -93.5482)
		(size 0.7112)
		(drill 0.4064)
		(layers "F.Cu" "B.Cu")
		(net "P0V975")
	)
	(via
		(at 182.1942 -92.329)
		(size 0.7112)
		(drill 0.4064)
		(layers "F.Cu" "B.Cu")
		(net "P0V975")
	)
	(via
		(at 181.5084 -86.0806)
		(size 0.7112)
		(drill 0.4064)
		(layers "F.Cu" "B.Cu")
		(net "P0V975")
	)
	(via
		(at 174.199804 -43.999912)
		(size 0.508)
		(drill 0.254)
		(layers "F.Cu" "B.Cu")
		(net "P0V975")
	)
	(via
		(at 181.5084 -87.2998)
		(size 0.7112)
		(drill 0.4064)
		(layers "F.Cu" "B.Cu")
		(net "P0V975")
	)
	(via
		(at 177.39995 -42.399966)
		(size 0.508)
		(drill 0.254)
		(layers "F.Cu" "B.Cu")
		(net "P0V975")
	)
	(via
		(at 175.800004 -40.799766)
		(size 0.508)
		(drill 0.254)
		(layers "F.Cu" "B.Cu")
		(net "P0V975")
	)
	(via
		(at 172.599858 -39.19982)
		(size 0.508)
		(drill 0.254)
		(layers "F.Cu" "B.Cu")
		(net "P0V975")
	)
	(via
		(at 172.599858 -40.799766)
		(size 0.508)
		(drill 0.254)
		(layers "F.Cu" "B.Cu")
		(net "P0V975")
	)
	(via
		(at 178.3842 -90.9828)
		(size 0.7112)
		(drill 0.4064)
		(layers "F.Cu" "B.Cu")
		(net "P0V975")
	)
	(via
		(at 185.0898 -95.5548)
		(size 0.7112)
		(drill 0.4064)
		(layers "F.Cu" "B.Cu")
		(net "P0V975")
	)
	(via
		(at 175.800004 -43.999912)
		(size 0.508)
		(drill 0.254)
		(layers "F.Cu" "B.Cu")
		(net "P0V975")
	)
	(via
		(at 175.800004 -35.999928)
		(size 0.508)
		(drill 0.254)
		(layers "F.Cu" "B.Cu")
		(net "P0V975")
	)
	(via
		(at 181.991 -95.631)
		(size 0.6604)
		(drill 0.3302)
		(layers "F.Cu" "B.Cu")
		(net "P0V975")
	)
	(via
		(at 172.599858 -44.000166)
		(size 0.508)
		(drill 0.254)
		(layers "F.Cu" "B.Cu")
		(net "P0V975")
	)
	(via
		(at 172.599858 -42.399966)
		(size 0.508)
		(drill 0.254)
		(layers "F.Cu" "B.Cu")
		(net "P0V975")
	)
	(via
		(at 182.1942 -93.5482)
		(size 0.7112)
		(drill 0.4064)
		(layers "F.Cu" "B.Cu")
		(net "P0V975")
	)
	(via
		(at 177.0126 -85.8012)
		(size 0.7112)
		(drill 0.4064)
		(layers "F.Cu" "B.Cu")
		(net "P0V975")
	)
	(via
		(at 175.800004 -39.19982)
		(size 0.508)
		(drill 0.254)
		(layers "F.Cu" "B.Cu")
		(net "P0V975")
	)
	(via
		(at 180.2892 -88.519)
		(size 0.7112)
		(drill 0.4064)
		(layers "F.Cu" "B.Cu")
		(net "P0V975")
	)
	(via
		(at 174.199804 -42.399966)
		(size 0.508)
		(drill 0.254)
		(layers "F.Cu" "B.Cu")
		(net "P0V975")
	)
	(via
		(at 174.333408 -52.6288)
		(size 0.508)
		(drill 0.254)
		(layers "F.Cu" "B.Cu")
		(net "P0V975")
	)
	(via
		(at 177.39995 -39.19982)
		(size 0.508)
		(drill 0.254)
		(layers "F.Cu" "B.Cu")
		(net "P0V975")
	)
	(via
		(at 178.999896 -42.399966)
		(size 0.508)
		(drill 0.254)
		(layers "F.Cu" "B.Cu")
		(net "P0V975")
	)
	(via
		(at 177.39995 -43.999912)
		(size 0.508)
		(drill 0.254)
		(layers "F.Cu" "B.Cu")
		(net "P0V975")
	)
	(via
		(at 175.800004 -37.599874)
		(size 0.508)
		(drill 0.254)
		(layers "F.Cu" "B.Cu")
		(net "P0V975")
	)
	(via
		(at 180.975 -92.329)
		(size 0.7112)
		(drill 0.4064)
		(layers "F.Cu" "B.Cu")
		(net "P0V975")
	)
	(via
		(at 178.999896 -40.799766)
		(size 0.508)
		(drill 0.254)
		(layers "F.Cu" "B.Cu")
		(net "P0V975")
	)
	(via
		(at 178.999896 -37.599874)
		(size 0.508)
		(drill 0.254)
		(layers "F.Cu" "B.Cu")
		(net "P0V975")
	)
	(via
		(at 188.5188 -96.6216)
		(size 0.7112)
		(drill 0.4064)
		(layers "F.Cu" "B.Cu")
		(net "P0V975")
	)
	(via
		(at 173.8376 -101.6254)
		(size 0.7112)
		(drill 0.4064)
		(layers "F.Cu" "B.Cu")
		(net "P0V975")
	)
	(via
		(at 177.39995 -37.599874)
		(size 0.508)
		(drill 0.254)
		(layers "F.Cu" "B.Cu")
		(net "P0V975")
	)
	(via
		(at 178.999896 -39.19982)
		(size 0.508)
		(drill 0.254)
		(layers "F.Cu" "B.Cu")
		(net "P0V975")
	)
	(via
		(at 180.2892 -87.2998)
		(size 0.7112)
		(drill 0.4064)
		(layers "F.Cu" "B.Cu")
		(net "P0V975")
	)
	(via
		(at 183.4134 -92.329)
		(size 0.7112)
		(drill 0.4064)
		(layers "F.Cu" "B.Cu")
		(net "P0V975")
	)
	(via
		(at 174.199804 -39.19982)
		(size 0.508)
		(drill 0.254)
		(layers "F.Cu" "B.Cu")
		(net "P0V975")
	)
	(via
		(at 183.4134 -93.5482)
		(size 0.7112)
		(drill 0.4064)
		(layers "F.Cu" "B.Cu")
		(net "P0V975")
	)
	(via
		(at 185.0898 -94.3356)
		(size 0.7112)
		(drill 0.4064)
		(layers "F.Cu" "B.Cu")
		(net "P0V975")
	)
	(via
		(at 177.165 -90.9828)
		(size 0.7112)
		(drill 0.4064)
		(layers "F.Cu" "B.Cu")
		(net "P0V975")
	)
	(via
		(at 179.451 -85.8012)
		(size 0.7112)
		(drill 0.4064)
		(layers "F.Cu" "B.Cu")
		(net "P0V975")
	)
	(via
		(at 163.614862 -70.80123)
		(size 0.508)
		(drill 0.254)
		(layers "F.Cu" "B.Cu")
		(net "P0V975")
	)
	(via
		(at 175.800004 -42.399966)
		(size 0.508)
		(drill 0.254)
		(layers "F.Cu" "B.Cu")
		(net "P0V975")
	)
	(via
		(at 177.39995 -35.999928)
		(size 0.508)
		(drill 0.254)
		(layers "F.Cu" "B.Cu")
		(net "P0V975")
	)
	(via
		(at 177.39995 -40.799766)
		(size 0.508)
		(drill 0.254)
		(layers "F.Cu" "B.Cu")
		(net "P0V975")
	)
	(via
		(at 172.599858 -37.599874)
		(size 0.508)
		(drill 0.254)
		(layers "F.Cu" "B.Cu")
		(net "P0V975")
	)
	(via
		(at 185.0898 -96.774)
		(size 0.7112)
		(drill 0.4064)
		(layers "F.Cu" "B.Cu")
		(net "P0V975")
	)
	(via
		(at 178.999896 -43.999912)
		(size 0.508)
		(drill 0.254)
		(layers "F.Cu" "B.Cu")
		(net "P0V975")
	)
	(via
		(at 188.5188 -94.1832)
		(size 0.7112)
		(drill 0.4064)
		(layers "F.Cu" "B.Cu")
		(net "P0V975")
	)
	(via
		(at 174.199804 -40.799766)
		(size 0.508)
		(drill 0.254)
		(layers "F.Cu" "B.Cu")
		(net "P0V975")
	)
	(via
		(at 171.000166 -43.200066)
		(size 0.508)
		(drill 0.254)
		(layers "F.Cu" "B.Cu")
		(net "P0V975")
	)
	(segment
		(start 176.2252 -95.946976)
		(end 176.2252 -99.2378)
		(width 0.508)
		(layer "B.Cu")
		(net "P0V975")
	)
	(segment
		(start 176.2252 -99.2378)
		(end 173.8376 -101.6254)
		(width 0.508)
		(layer "B.Cu")
		(net "P0V975")
	)
	(segment
		(start 173.9265 -53.3908)
		(end 173.9265 -53.035708)
		(width 0.508)
		(layer "B.Cu")
		(net "P0V975")
	)
	(segment
		(start 177.814224 -94.357952)
		(end 176.2252 -95.946976)
		(width 0.508)
		(layer "B.Cu")
		(net "P0V975")
	)
	(segment
		(start 173.9265 -53.035708)
		(end 174.333408 -52.6288)
		(width 0.508)
		(layer "B.Cu")
		(net "P0V975")
	)
	(segment
		(start 45.911262 -31.850076)
		(end 45.911262 -30.87497)
		(width 0.254)
		(layer "F.Cu")
		(net "P0V9_VSNS")
	)
	(segment
		(start 49.114202 -29.119576)
		(end 49.101502 -29.106876)
		(width 0.254)
		(layer "F.Cu")
		(net "P0V9_VSNS")
	)
	(segment
		(start 45.911262 -30.87497)
		(end 46.67504 -30.111192)
		(width 0.254)
		(layer "F.Cu")
		(net "P0V9_VSNS")
	)
	(segment
		(start 49.139602 -29.144976)
		(end 49.139602 -30.110176)
		(width 0.254)
		(layer "F.Cu")
		(net "P0V9_VSNS")
	)
	(segment
		(start 48.110902 -29.106876)
		(end 47.679356 -29.106876)
		(width 0.254)
		(layer "F.Cu")
		(net "P0V9_VSNS")
	)
	(segment
		(start 49.114202 -29.119576)
		(end 49.139602 -29.144976)
		(width 0.254)
		(layer "F.Cu")
		(net "P0V9_VSNS")
	)
	(segment
		(start 49.101502 -29.106876)
		(end 48.110902 -29.106876)
		(width 0.254)
		(layer "F.Cu")
		(net "P0V9_VSNS")
	)
	(segment
		(start 47.679356 -29.106876)
		(end 46.67504 -30.111192)
		(width 0.254)
		(layer "F.Cu")
		(net "P0V9_VSNS")
	)
	(via
		(at 46.67504 -30.111192)
		(size 0.6604)
		(drill 0.3302)
		(layers "F.Cu" "B.Cu")
		(net "P0V9_VSNS")
	)
	(segment
		(start 43.1927 -27.84475)
		(end 43.1927 -29.083)
		(width 0.254)
		(layer "F.Cu")
		(net "P0V9_VREF")
	)
	(segment
		(start 43.1927 -29.6291)
		(end 43.1927 -29.083)
		(width 0.254)
		(layer "F.Cu")
		(net "P0V9_VREF")
	)
	(segment
		(start 43.2562 -26.543)
		(end 43.1927 -26.6065)
		(width 0.254)
		(layer "F.Cu")
		(net "P0V9_VREF")
	)
	(segment
		(start 43.1927 -26.6065)
		(end 43.1927 -27.84475)
		(width 0.254)
		(layer "F.Cu")
		(net "P0V9_VREF")
	)
	(segment
		(start 44.411138 -31.850076)
		(end 44.411138 -30.847538)
		(width 0.254)
		(layer "F.Cu")
		(net "P0V9_VREF")
	)
	(segment
		(start 44.411138 -30.847538)
		(end 43.1927 -29.6291)
		(width 0.254)
		(layer "F.Cu")
		(net "P0V9_VREF")
	)
	(via
		(at 43.1927 -27.84475)
		(size 0.6604)
		(drill 0.3302)
		(layers "F.Cu" "B.Cu")
		(net "P0V9_VREF")
	)
	(segment
		(start 51.089306 -28.432506)
		(end 51.089306 -29.11983)
		(width 0.254)
		(layer "F.Cu")
		(net "P0V9_VFB")
	)
	(segment
		(start 50.9397 -28.2829)
		(end 51.089306 -28.432506)
		(width 0.254)
		(layer "F.Cu")
		(net "P0V9_VFB")
	)
	(segment
		(start 51.089306 -29.11983)
		(end 51.089052 -29.119576)
		(width 0.254)
		(layer "F.Cu")
		(net "P0V9_VFB")
	)
	(segment
		(start 51.089052 -29.119576)
		(end 50.003202 -29.119576)
		(width 0.254)
		(layer "F.Cu")
		(net "P0V9_VFB")
	)
	(via
		(at 52.023772 -27.199082)
		(size 0.6096)
		(drill 0.3048)
		(layers "F.Cu" "B.Cu")
		(net "P0V9_VFB")
	)
	(via
		(at 109.000036 -67.000374)
		(size 0.4572)
		(drill 0.2032)
		(layers "F.Cu" "B.Cu")
		(net "P0V9_VFB")
	)
	(via
		(at 50.9397 -28.2829)
		(size 0.508)
		(drill 0.254)
		(layers "F.Cu" "B.Cu")
		(net "P0V9_VFB")
	)
	(via
		(at 91.62034 -58.901838)
		(size 0.508)
		(drill 0.254)
		(layers "F.Cu" "B.Cu")
		(net "P0V9_VFB")
	)
	(segment
		(start 82.53476 -56.660288)
		(end 84.954618 -59.080146)
		(width 0.254)
		(layer "B.Cu")
		(net "P0V9_VFB")
	)
	(segment
		(start 109.052106 -67.052444)
		(end 109.000036 -67.000374)
		(width 0.254)
		(layer "B.Cu")
		(net "P0V9_VFB")
	)
	(segment
		(start 71.220584 -26.718514)
		(end 77.80274 -33.30067)
		(width 0.254)
		(layer "B.Cu")
		(net "P0V9_VFB")
	)
	(segment
		(start 77.80274 -33.30067)
		(end 77.80274 -37.295328)
		(width 0.254)
		(layer "B.Cu")
		(net "P0V9_VFB")
	)
	(segment
		(start 52.023772 -27.199082)
		(end 52.50434 -26.718514)
		(width 0.254)
		(layer "B.Cu")
		(net "P0V9_VFB")
	)
	(segment
		(start 77.80274 -37.295328)
		(end 82.53476 -42.027348)
		(width 0.254)
		(layer "B.Cu")
		(net "P0V9_VFB")
	)
	(segment
		(start 91.442032 -59.080146)
		(end 91.62034 -58.901838)
		(width 0.254)
		(layer "B.Cu")
		(net "P0V9_VFB")
	)
	(segment
		(start 82.53476 -42.027348)
		(end 82.53476 -56.660288)
		(width 0.254)
		(layer "B.Cu")
		(net "P0V9_VFB")
	)
	(segment
		(start 52.50434 -26.718514)
		(end 71.220584 -26.718514)
		(width 0.254)
		(layer "B.Cu")
		(net "P0V9_VFB")
	)
	(segment
		(start 51.30292 -27.91968)
		(end 51.303174 -27.91968)
		(width 0.254)
		(layer "B.Cu")
		(net "P0V9_VFB")
	)
	(segment
		(start 50.9397 -28.2829)
		(end 51.30292 -27.91968)
		(width 0.254)
		(layer "B.Cu")
		(net "P0V9_VFB")
	)
	(segment
		(start 84.954618 -59.080146)
		(end 91.442032 -59.080146)
		(width 0.254)
		(layer "B.Cu")
		(net "P0V9_VFB")
	)
	(segment
		(start 51.303174 -27.91968)
		(end 52.023772 -27.199082)
		(width 0.254)
		(layer "B.Cu")
		(net "P0V9_VFB")
	)
	(segment
		(start 109.052106 -67.87896)
		(end 109.052106 -67.052444)
		(width 0.254)
		(layer "B.Cu")
		(net "P0V9_VFB")
	)
	(segment
		(start 95.776796 -56.54294)
		(end 108.189522 -56.54294)
		(width 0.254)
		(layer "In2.Cu")
		(net "P0V9_VFB")
	)
	(segment
		(start 93.417898 -58.901838)
		(end 95.776796 -56.54294)
		(width 0.254)
		(layer "In2.Cu")
		(net "P0V9_VFB")
	)
	(segment
		(start 108.457238 -66.457576)
		(end 109.000036 -67.000374)
		(width 0.254)
		(layer "In2.Cu")
		(net "P0V9_VFB")
	)
	(segment
		(start 108.457238 -56.810656)
		(end 108.457238 -66.457576)
		(width 0.254)
		(layer "In2.Cu")
		(net "P0V9_VFB")
	)
	(segment
		(start 108.189522 -56.54294)
		(end 108.457238 -56.810656)
		(width 0.254)
		(layer "In2.Cu")
		(net "P0V9_VFB")
	)
	(segment
		(start 91.62034 -58.901838)
		(end 93.417898 -58.901838)
		(width 0.254)
		(layer "In2.Cu")
		(net "P0V9_VFB")
	)
	(segment
		(start 46.608492 -36.245292)
		(end 46.608492 -36.92652)
		(width 0.254)
		(layer "F.Cu")
		(net "P0V9_V5")
	)
	(segment
		(start 47.018448 -38.911784)
		(end 46.608492 -38.501828)
		(width 0.254)
		(layer "F.Cu")
		(net "P0V9_V5")
	)
	(segment
		(start 45.911262 -35.548062)
		(end 46.608492 -36.245292)
		(width 0.254)
		(layer "F.Cu")
		(net "P0V9_V5")
	)
	(segment
		(start 45.911262 -34.951924)
		(end 45.911262 -35.548062)
		(width 0.254)
		(layer "F.Cu")
		(net "P0V9_V5")
	)
	(segment
		(start 47.918878 -38.911784)
		(end 47.018448 -38.911784)
		(width 0.254)
		(layer "F.Cu")
		(net "P0V9_V5")
	)
	(segment
		(start 46.608492 -38.501828)
		(end 46.608492 -36.92652)
		(width 0.254)
		(layer "F.Cu")
		(net "P0V9_V5")
	)
	(via
		(at 46.608492 -38.501828)
		(size 0.6604)
		(drill 0.3302)
		(layers "F.Cu" "B.Cu")
		(net "P0V9_V5")
	)
	(segment
		(start 49.570894 -32.529018)
		(end 48.377094 -32.529018)
		(width 0.254)
		(layer "F.Cu")
		(net "P0V9_TRIP")
	)
	(segment
		(start 46.712124 -33.151064)
		(end 47.25416 -33.151064)
		(width 0.254)
		(layer "F.Cu")
		(net "P0V9_TRIP")
	)
	(segment
		(start 47.25416 -33.151064)
		(end 47.876206 -32.529018)
		(width 0.254)
		(layer "F.Cu")
		(net "P0V9_TRIP")
	)
	(segment
		(start 47.876206 -32.529018)
		(end 48.377094 -32.529018)
		(width 0.254)
		(layer "F.Cu")
		(net "P0V9_TRIP")
	)
	(via
		(at 48.377094 -32.529018)
		(size 0.6604)
		(drill 0.3302)
		(layers "F.Cu" "B.Cu")
		(net "P0V9_TRIP")
	)
	(segment
		(start 44.831 -45.5676)
		(end 45.0977 -45.8343)
		(width 0.508)
		(layer "F.Cu")
		(net "P0V9_TG")
	)
	(segment
		(start 45.1104 -45.847)
		(end 45.0977 -45.8343)
		(width 0.508)
		(layer "F.Cu")
		(net "P0V9_TG")
	)
	(segment
		(start 44.831 -44.6024)
		(end 44.831 -45.5676)
		(width 0.508)
		(layer "F.Cu")
		(net "P0V9_TG")
	)
	(segment
		(start 47.190406 -45.847)
		(end 45.1104 -45.847)
		(width 0.508)
		(layer "F.Cu")
		(net "P0V9_TG")
	)
	(via
		(at 45.0977 -45.8343)
		(size 0.6604)
		(drill 0.3302)
		(layers "F.Cu" "B.Cu")
		(net "P0V9_TG")
	)
	(segment
		(start 44.411138 -35.510724)
		(end 44.1452 -35.776662)
		(width 0.3048)
		(layer "F.Cu")
		(net "P0V9_SW")
	)
	(segment
		(start 43.1292 -36.2458)
		(end 43.1292 -36.576)
		(width 0.508)
		(layer "F.Cu")
		(net "P0V9_SW")
	)
	(segment
		(start 44.1452 -35.776662)
		(end 43.928792 -35.776662)
		(width 0.3048)
		(layer "F.Cu")
		(net "P0V9_SW")
	)
	(segment
		(start 43.890946 -35.814)
		(end 43.561 -35.814)
		(width 0.508)
		(layer "F.Cu")
		(net "P0V9_SW")
	)
	(segment
		(start 45.7962 -44.5516)
		(end 45.8216 -44.577)
		(width 0.508)
		(layer "F.Cu")
		(net "P0V9_SW")
	)
	(segment
		(start 44.411138 -34.951924)
		(end 44.411138 -35.510724)
		(width 0.3048)
		(layer "F.Cu")
		(net "P0V9_SW")
	)
	(segment
		(start 43.561 -35.814)
		(end 43.1292 -36.2458)
		(width 0.508)
		(layer "F.Cu")
		(net "P0V9_SW")
	)
	(segment
		(start 45.8216 -44.577)
		(end 47.190406 -44.577)
		(width 0.508)
		(layer "F.Cu")
		(net "P0V9_SW")
	)
	(segment
		(start 43.928792 -35.776662)
		(end 43.8912 -35.814254)
		(width 0.3048)
		(layer "F.Cu")
		(net "P0V9_SW")
	)
	(segment
		(start 43.8912 -35.814254)
		(end 43.890946 -35.814)
		(width 0.508)
		(layer "F.Cu")
		(net "P0V9_SW")
	)
	(via
		(at 45.0596 -38.0238)
		(size 0.6096)
		(drill 0.3048)
		(layers "F.Cu" "B.Cu")
		(net "P0V9_SW")
	)
	(via
		(at 45.7962 -44.5516)
		(size 0.508)
		(drill 0.254)
		(layers "F.Cu" "B.Cu")
		(net "P0V9_SW")
	)
	(via
		(at 43.8912 -35.814254)
		(size 0.508)
		(drill 0.254)
		(layers "F.Cu" "B.Cu")
		(net "P0V9_SW")
	)
	(segment
		(start 45.7962 -38.9636)
		(end 45.0596 -38.227)
		(width 0.508)
		(layer "B.Cu")
		(net "P0V9_SW")
	)
	(segment
		(start 45.0596 -36.982654)
		(end 43.8912 -35.814254)
		(width 0.508)
		(layer "B.Cu")
		(net "P0V9_SW")
	)
	(segment
		(start 45.7962 -44.5516)
		(end 45.7962 -38.9636)
		(width 0.508)
		(layer "B.Cu")
		(net "P0V9_SW")
	)
	(segment
		(start 45.0596 -38.227)
		(end 45.0596 -38.0238)
		(width 0.508)
		(layer "B.Cu")
		(net "P0V9_SW")
	)
	(segment
		(start 45.0596 -38.0238)
		(end 45.0596 -36.982654)
		(width 0.508)
		(layer "B.Cu")
		(net "P0V9_SW")
	)
	(segment
		(start 51.979576 -53.33619)
		(end 52.55641 -53.33619)
		(width 0.508)
		(layer "F.Cu")
		(net "P0V9_SNB")
	)
	(segment
		(start 52.55641 -53.33619)
		(end 53.467 -52.4256)
		(width 0.508)
		(layer "F.Cu")
		(net "P0V9_SNB")
	)
	(segment
		(start 159.8295 -84.852764)
		(end 159.604456 -85.077808)
		(width 0.127)
		(layer "F.Cu")
		(net "P0V9_SENSE")
	)
	(segment
		(start 159.8295 -82.878422)
		(end 159.8295 -83.224116)
		(width 0.127)
		(layer "F.Cu")
		(net "P0V9_SENSE")
	)
	(segment
		(start 159.604456 -85.077808)
		(end 159.016192 -85.077808)
		(width 0.127)
		(layer "F.Cu")
		(net "P0V9_SENSE")
	)
	(segment
		(start 160.4772 -81.9785)
		(end 160.4772 -82.230722)
		(width 0.127)
		(layer "F.Cu")
		(net "P0V9_SENSE")
	)
	(segment
		(start 159.8295 -84.409026)
		(end 159.8295 -84.852764)
		(width 0.127)
		(layer "F.Cu")
		(net "P0V9_SENSE")
	)
	(segment
		(start 159.016192 -85.077808)
		(end 158.819088 -85.274912)
		(width 0.127)
		(layer "F.Cu")
		(net "P0V9_SENSE")
	)
	(segment
		(start 159.8295 -83.224116)
		(end 159.8295 -84.409026)
		(width 0.127)
		(layer "F.Cu")
		(net "P0V9_SENSE")
	)
	(segment
		(start 160.4772 -82.230722)
		(end 159.8295 -82.878422)
		(width 0.127)
		(layer "F.Cu")
		(net "P0V9_SENSE")
	)
	(segment
		(start 158.819088 -85.274912)
		(end 157.81528 -85.274912)
		(width 0.127)
		(layer "F.Cu")
		(net "P0V9_SENSE")
	)
	(via
		(at 159.8295 -84.409026)
		(size 0.6604)
		(drill 0.3302)
		(layers "F.Cu" "B.Cu")
		(net "P0V9_SENSE")
	)
	(segment
		(start 44.0817 -29.578808)
		(end 44.725082 -30.22219)
		(width 0.254)
		(layer "F.Cu")
		(net "P0V9_REFIN")
	)
	(segment
		(start 44.0817 -29.083)
		(end 44.0817 -29.578808)
		(width 0.254)
		(layer "F.Cu")
		(net "P0V9_REFIN")
	)
	(segment
		(start 45.0977 -29.083)
		(end 44.0817 -29.083)
		(width 0.254)
		(layer "F.Cu")
		(net "P0V9_REFIN")
	)
	(segment
		(start 44.725082 -30.22219)
		(end 44.911264 -30.408372)
		(width 0.254)
		(layer "F.Cu")
		(net "P0V9_REFIN")
	)
	(segment
		(start 44.911264 -30.408372)
		(end 44.911264 -31.850076)
		(width 0.254)
		(layer "F.Cu")
		(net "P0V9_REFIN")
	)
	(segment
		(start 45.0977 -29.083)
		(end 45.0977 -28.321)
		(width 0.254)
		(layer "F.Cu")
		(net "P0V9_REFIN")
	)
	(segment
		(start 45.0977 -28.321)
		(end 44.7167 -27.94)
		(width 0.254)
		(layer "F.Cu")
		(net "P0V9_REFIN")
	)
	(via
		(at 44.725082 -30.22219)
		(size 0.6604)
		(drill 0.3302)
		(layers "F.Cu" "B.Cu")
		(net "P0V9_REFIN")
	)
	(segment
		(start 168.11244 -17.9705)
		(end 168.913048 -17.169892)
		(width 0.254)
		(layer "F.Cu")
		(net "P0V9_PG_Q")
	)
	(segment
		(start 168.913048 -17.169892)
		(end 168.913048 -16.677386)
		(width 0.254)
		(layer "F.Cu")
		(net "P0V9_PG_Q")
	)
	(segment
		(start 168.656 -15.389352)
		(end 168.656 -14.5415)
		(width 0.254)
		(layer "F.Cu")
		(net "P0V9_PG_Q")
	)
	(segment
		(start 167.73525 -17.9705)
		(end 168.11244 -17.9705)
		(width 0.254)
		(layer "F.Cu")
		(net "P0V9_PG_Q")
	)
	(segment
		(start 168.913048 -15.6464)
		(end 168.656 -15.389352)
		(width 0.254)
		(layer "F.Cu")
		(net "P0V9_PG_Q")
	)
	(segment
		(start 168.913048 -16.677386)
		(end 168.913048 -15.6464)
		(width 0.254)
		(layer "F.Cu")
		(net "P0V9_PG_Q")
	)
	(via
		(at 168.913048 -16.677386)
		(size 0.6604)
		(drill 0.3302)
		(layers "F.Cu" "B.Cu")
		(net "P0V9_PG_Q")
	)
	(segment
		(start 193.289174 -63.364618)
		(end 191.372998 -63.364618)
		(width 0.254)
		(layer "F.Cu")
		(net "P0V9_PG")
	)
	(segment
		(start 168.656 -13.6525)
		(end 169.1005 -13.6525)
		(width 0.254)
		(layer "F.Cu")
		(net "P0V9_PG")
	)
	(segment
		(start 71.318882 -73.7108)
		(end 71.318882 -73.177146)
		(width 0.254)
		(layer "F.Cu")
		(net "P0V9_PG")
	)
	(segment
		(start 200.53681 -33.425892)
		(end 200.53681 -47.87773)
		(width 0.254)
		(layer "F.Cu")
		(net "P0V9_PG")
	)
	(segment
		(start 69.85 -75.179682)
		(end 71.318882 -73.7108)
		(width 0.254)
		(layer "F.Cu")
		(net "P0V9_PG")
	)
	(segment
		(start 56.388 -77.9145)
		(end 56.388 -78.8924)
		(width 0.254)
		(layer "F.Cu")
		(net "P0V9_PG")
	)
	(segment
		(start 60.9854 -77.9145)
		(end 61.0108 -77.9399)
		(width 0.254)
		(layer "F.Cu")
		(net "P0V9_PG")
	)
	(segment
		(start 10.922 -95.245682)
		(end 10.922 -96.071182)
		(width 0.254)
		(layer "F.Cu")
		(net "P0V9_PG")
	)
	(segment
		(start 39.621714 -26.977086)
		(end 39.621714 -27.955494)
		(width 0.254)
		(layer "F.Cu")
		(net "P0V9_PG")
	)
	(segment
		(start 86.7791 -82.2706)
		(end 86.7791 -81.210404)
		(width 0.254)
		(layer "F.Cu")
		(net "P0V9_PG")
	)
	(segment
		(start 190.235586 -64.50203)
		(end 190.235586 -68.391786)
		(width 0.254)
		(layer "F.Cu")
		(net "P0V9_PG")
	)
	(segment
		(start 71.318882 -73.177146)
		(end 72.206104 -72.289924)
		(width 0.254)
		(layer "F.Cu")
		(net "P0V9_PG")
	)
	(segment
		(start 79.73822 -79.883)
		(end 84.6328 -79.883)
		(width 0.254)
		(layer "F.Cu")
		(net "P0V9_PG")
	)
	(segment
		(start 200.53681 -47.87773)
		(end 201.938382 -49.279302)
		(width 0.254)
		(layer "F.Cu")
		(net "P0V9_PG")
	)
	(segment
		(start 64.9859 -77.3049)
		(end 64.3509 -77.9399)
		(width 0.254)
		(layer "F.Cu")
		(net "P0V9_PG")
	)
	(segment
		(start 72.895714 -71.307452)
		(end 72.895714 -70.758304)
		(width 0.254)
		(layer "F.Cu")
		(net "P0V9_PG")
	)
	(segment
		(start 190.40348 -68.55968)
		(end 190.40348 -69.49948)
		(width 0.254)
		(layer "F.Cu")
		(net "P0V9_PG")
	)
	(segment
		(start 65.7098 -77.3049)
		(end 69.2277 -77.3049)
		(width 0.254)
		(layer "F.Cu")
		(net "P0V9_PG")
	)
	(segment
		(start 200.800208 -33.162494)
		(end 200.53681 -33.425892)
		(width 0.254)
		(layer "F.Cu")
		(net "P0V9_PG")
	)
	(segment
		(start 86.7791 -81.210404)
		(end 86.776814 -81.208118)
		(width 0.254)
		(layer "F.Cu")
		(net "P0V9_PG")
	)
	(segment
		(start 16.637 -95.3897)
		(end 16.637 -96.2152)
		(width 0.254)
		(layer "F.Cu")
		(net "P0V9_PG")
	)
	(segment
		(start 191.372998 -63.364618)
		(end 190.235586 -64.50203)
		(width 0.254)
		(layer "F.Cu")
		(net "P0V9_PG")
	)
	(segment
		(start 85.957918 -81.208118)
		(end 86.776814 -81.208118)
		(width 0.254)
		(layer "F.Cu")
		(net "P0V9_PG")
	)
	(segment
		(start 5.588 -95.275908)
		(end 5.588 -96.101408)
		(width 0.254)
		(layer "F.Cu")
		(net "P0V9_PG")
	)
	(segment
		(start 72.206104 -71.997062)
		(end 72.895714 -71.307452)
		(width 0.254)
		(layer "F.Cu")
		(net "P0V9_PG")
	)
	(segment
		(start 200.800208 -21.400008)
		(end 200.800208 -33.162494)
		(width 0.254)
		(layer "F.Cu")
		(net "P0V9_PG")
	)
	(segment
		(start 199.46493 -20.06473)
		(end 200.800208 -21.400008)
		(width 0.254)
		(layer "F.Cu")
		(net "P0V9_PG")
	)
	(segment
		(start 72.206104 -72.289924)
		(end 72.206104 -71.997062)
		(width 0.254)
		(layer "F.Cu")
		(net "P0V9_PG")
	)
	(segment
		(start 77.03439 -70.758304)
		(end 77.6732 -71.397114)
		(width 0.254)
		(layer "F.Cu")
		(net "P0V9_PG")
	)
	(segment
		(start 189.187582 -20.06473)
		(end 199.46493 -20.06473)
		(width 0.254)
		(layer "F.Cu")
		(net "P0V9_PG")
	)
	(segment
		(start 65.7098 -77.3049)
		(end 64.9859 -77.3049)
		(width 0.254)
		(layer "F.Cu")
		(net "P0V9_PG")
	)
	(segment
		(start 201.938382 -49.279302)
		(end 201.938382 -54.71541)
		(width 0.254)
		(layer "F.Cu")
		(net "P0V9_PG")
	)
	(segment
		(start 201.938382 -54.71541)
		(end 193.289174 -63.364618)
		(width 0.254)
		(layer "F.Cu")
		(net "P0V9_PG")
	)
	(segment
		(start 169.1005 -13.6525)
		(end 169.6974 -14.2494)
		(width 0.254)
		(layer "F.Cu")
		(net "P0V9_PG")
	)
	(segment
		(start 72.895714 -70.758304)
		(end 77.03439 -70.758304)
		(width 0.254)
		(layer "F.Cu")
		(net "P0V9_PG")
	)
	(segment
		(start 190.235586 -68.391786)
		(end 190.40348 -68.55968)
		(width 0.254)
		(layer "F.Cu")
		(net "P0V9_PG")
	)
	(segment
		(start 64.3509 -77.9399)
		(end 61.0108 -77.9399)
		(width 0.254)
		(layer "F.Cu")
		(net "P0V9_PG")
	)
	(segment
		(start 21.79193 -95.294704)
		(end 21.79193 -96.120204)
		(width 0.254)
		(layer "F.Cu")
		(net "P0V9_PG")
	)
	(segment
		(start 40.10406 -26.49474)
		(end 39.621714 -26.977086)
		(width 0.254)
		(layer "F.Cu")
		(net "P0V9_PG")
	)
	(segment
		(start 77.6732 -71.397114)
		(end 77.6732 -77.81798)
		(width 0.254)
		(layer "F.Cu")
		(net "P0V9_PG")
	)
	(segment
		(start 56.388 -77.9145)
		(end 60.9854 -77.9145)
		(width 0.254)
		(layer "F.Cu")
		(net "P0V9_PG")
	)
	(segment
		(start 77.6732 -77.81798)
		(end 79.73822 -79.883)
		(width 0.254)
		(layer "F.Cu")
		(net "P0V9_PG")
	)
	(segment
		(start 84.6328 -79.883)
		(end 85.957918 -81.208118)
		(width 0.254)
		(layer "F.Cu")
		(net "P0V9_PG")
	)
	(segment
		(start 188.84392 -110.65256)
		(end 188.84392 -111.52632)
		(width 0.254)
		(layer "F.Cu")
		(net "P0V9_PG")
	)
	(segment
		(start 40.77208 -27.57932)
		(end 40.6527 -27.6987)
		(width 0.254)
		(layer "F.Cu")
		(net "P0V9_PG")
	)
	(segment
		(start 69.85 -76.6826)
		(end 69.85 -75.179682)
		(width 0.254)
		(layer "F.Cu")
		(net "P0V9_PG")
	)
	(segment
		(start 40.77208 -26.49474)
		(end 40.77208 -27.57932)
		(width 0.254)
		(layer "F.Cu")
		(net "P0V9_PG")
	)
	(segment
		(start 40.77208 -26.49474)
		(end 40.10406 -26.49474)
		(width 0.254)
		(layer "F.Cu")
		(net "P0V9_PG")
	)
	(segment
		(start 69.2277 -77.3049)
		(end 69.85 -76.6826)
		(width 0.254)
		(layer "F.Cu")
		(net "P0V9_PG")
	)
	(via
		(at 21.79193 -96.120204)
		(size 0.508)
		(drill 0.254)
		(layers "F.Cu" "B.Cu")
		(net "P0V9_PG")
	)
	(via
		(at 189.187582 -20.06473)
		(size 0.508)
		(drill 0.254)
		(layers "F.Cu" "B.Cu")
		(net "P0V9_PG")
	)
	(via
		(at 190.40348 -69.49948)
		(size 0.508)
		(drill 0.254)
		(layers "F.Cu" "B.Cu")
		(net "P0V9_PG")
	)
	(via
		(at 39.621714 -27.955494)
		(size 0.508)
		(drill 0.254)
		(layers "F.Cu" "B.Cu")
		(net "P0V9_PG")
	)
	(via
		(at 41.280588 -84.270596)
		(size 0.508)
		(drill 0.254)
		(layers "F.Cu" "B.Cu")
		(net "P0V9_PG")
	)
	(via
		(at 56.388 -78.8924)
		(size 0.508)
		(drill 0.254)
		(layers "F.Cu" "B.Cu")
		(net "P0V9_PG")
	)
	(via
		(at 32.667194 -84.270596)
		(size 0.6096)
		(drill 0.3048)
		(layers "F.Cu" "B.Cu")
		(net "P0V9_PG")
	)
	(via
		(at 16.637 -96.2152)
		(size 0.508)
		(drill 0.254)
		(layers "F.Cu" "B.Cu")
		(net "P0V9_PG")
	)
	(via
		(at 169.6974 -14.2494)
		(size 0.508)
		(drill 0.254)
		(layers "F.Cu" "B.Cu")
		(net "P0V9_PG")
	)
	(via
		(at 93.3323 -104.12857)
		(size 0.508)
		(drill 0.254)
		(layers "F.Cu" "B.Cu")
		(net "P0V9_PG")
	)
	(via
		(at 188.84392 -111.52632)
		(size 0.508)
		(drill 0.254)
		(layers "F.Cu" "B.Cu")
		(net "P0V9_PG")
	)
	(via
		(at 25.9842 -83.5914)
		(size 0.508)
		(drill 0.254)
		(layers "F.Cu" "B.Cu")
		(net "P0V9_PG")
	)
	(via
		(at 113.919 -107.696)
		(size 0.508)
		(drill 0.254)
		(layers "F.Cu" "B.Cu")
		(net "P0V9_PG")
	)
	(via
		(at 5.588 -96.101408)
		(size 0.508)
		(drill 0.254)
		(layers "F.Cu" "B.Cu")
		(net "P0V9_PG")
	)
	(via
		(at 10.922 -96.071182)
		(size 0.508)
		(drill 0.254)
		(layers "F.Cu" "B.Cu")
		(net "P0V9_PG")
	)
	(segment
		(start 41.280588 -84.270596)
		(end 49.949354 -84.270596)
		(width 0.254)
		(layer "B.Cu")
		(net "P0V9_PG")
	)
	(segment
		(start 6.285992 -96.7994)
		(end 9.093454 -96.7994)
		(width 0.254)
		(layer "B.Cu")
		(net "P0V9_PG")
	)
	(segment
		(start 113.919 -102.448106)
		(end 109.75213 -98.281236)
		(width 0.254)
		(layer "B.Cu")
		(net "P0V9_PG")
	)
	(segment
		(start 16.637 -96.2152)
		(end 15.4686 -96.2152)
		(width 0.254)
		(layer "B.Cu")
		(net "P0V9_PG")
	)
	(segment
		(start 32.667194 -84.270596)
		(end 26.663396 -84.270596)
		(width 0.254)
		(layer "B.Cu")
		(net "P0V9_PG")
	)
	(segment
		(start 109.71276 -98.281236)
		(end 109.68736 -98.255836)
		(width 0.254)
		(layer "B.Cu")
		(net "P0V9_PG")
	)
	(segment
		(start 99.205034 -98.255836)
		(end 93.3323 -104.12857)
		(width 0.254)
		(layer "B.Cu")
		(net "P0V9_PG")
	)
	(segment
		(start 113.919 -107.696)
		(end 113.919 -102.448106)
		(width 0.254)
		(layer "B.Cu")
		(net "P0V9_PG")
	)
	(segment
		(start 26.663396 -84.270596)
		(end 25.9842 -83.5914)
		(width 0.254)
		(layer "B.Cu")
		(net "P0V9_PG")
	)
	(segment
		(start 19.9136 -96.8756)
		(end 17.2974 -96.8756)
		(width 0.254)
		(layer "B.Cu")
		(net "P0V9_PG")
	)
	(segment
		(start 49.949354 -84.270596)
		(end 55.32755 -78.8924)
		(width 0.254)
		(layer "B.Cu")
		(net "P0V9_PG")
	)
	(segment
		(start 109.68736 -98.255836)
		(end 99.205034 -98.255836)
		(width 0.254)
		(layer "B.Cu")
		(net "P0V9_PG")
	)
	(segment
		(start 5.588 -96.101408)
		(end 6.285992 -96.7994)
		(width 0.254)
		(layer "B.Cu")
		(net "P0V9_PG")
	)
	(segment
		(start 9.093454 -96.7994)
		(end 9.821672 -96.071182)
		(width 0.254)
		(layer "B.Cu")
		(net "P0V9_PG")
	)
	(segment
		(start 14.986 -96.6978)
		(end 11.548618 -96.6978)
		(width 0.254)
		(layer "B.Cu")
		(net "P0V9_PG")
	)
	(segment
		(start 17.2974 -96.8756)
		(end 16.637 -96.2152)
		(width 0.254)
		(layer "B.Cu")
		(net "P0V9_PG")
	)
	(segment
		(start 15.4686 -96.2152)
		(end 14.986 -96.6978)
		(width 0.254)
		(layer "B.Cu")
		(net "P0V9_PG")
	)
	(segment
		(start 188.60516 -111.28756)
		(end 188.84392 -111.52632)
		(width 0.254)
		(layer "B.Cu")
		(net "P0V9_PG")
	)
	(segment
		(start 55.32755 -78.8924)
		(end 56.388 -78.8924)
		(width 0.254)
		(layer "B.Cu")
		(net "P0V9_PG")
	)
	(segment
		(start 21.79193 -96.120204)
		(end 20.668996 -96.120204)
		(width 0.254)
		(layer "B.Cu")
		(net "P0V9_PG")
	)
	(segment
		(start 20.668996 -96.120204)
		(end 19.9136 -96.8756)
		(width 0.254)
		(layer "B.Cu")
		(net "P0V9_PG")
	)
	(segment
		(start 11.548618 -96.6978)
		(end 10.922 -96.071182)
		(width 0.254)
		(layer "B.Cu")
		(net "P0V9_PG")
	)
	(segment
		(start 109.75213 -98.281236)
		(end 109.71276 -98.281236)
		(width 0.254)
		(layer "B.Cu")
		(net "P0V9_PG")
	)
	(segment
		(start 9.821672 -96.071182)
		(end 10.922 -96.071182)
		(width 0.254)
		(layer "B.Cu")
		(net "P0V9_PG")
	)
	(segment
		(start 187.87872 -111.28756)
		(end 188.60516 -111.28756)
		(width 0.254)
		(layer "B.Cu")
		(net "P0V9_PG")
	)
	(segment
		(start 41.280588 -84.270596)
		(end 32.667194 -84.270596)
		(width 0.254)
		(layer "B.Cu")
		(net "P0V9_PG")
	)
	(segment
		(start 69.594222 -102.436168)
		(end 59.44616 -102.436168)
		(width 0.254)
		(layer "In2.Cu")
		(net "P0V9_PG")
	)
	(segment
		(start 188.84392 -111.52632)
		(end 191.829182 -108.541058)
		(width 0.254)
		(layer "In2.Cu")
		(net "P0V9_PG")
	)
	(segment
		(start 39.621714 -27.955494)
		(end 39.621714 -30.035754)
		(width 0.254)
		(layer "In2.Cu")
		(net "P0V9_PG")
	)
	(segment
		(start 34.685224 -45.524674)
		(end 31.8262 -48.383698)
		(width 0.254)
		(layer "In2.Cu")
		(net "P0V9_PG")
	)
	(segment
		(start 189.187582 -20.06473)
		(end 185.3184 -20.06473)
		(width 0.254)
		(layer "In2.Cu")
		(net "P0V9_PG")
	)
	(segment
		(start 190.40348 -76.438252)
		(end 190.40348 -69.49948)
		(width 0.254)
		(layer "In2.Cu")
		(net "P0V9_PG")
	)
	(segment
		(start 183.89727 -18.6436)
		(end 174.0916 -18.6436)
		(width 0.254)
		(layer "In2.Cu")
		(net "P0V9_PG")
	)
	(segment
		(start 89.19337 -108.2675)
		(end 75.425554 -108.2675)
		(width 0.254)
		(layer "In2.Cu")
		(net "P0V9_PG")
	)
	(segment
		(start 39.621714 -30.035754)
		(end 34.685224 -34.972244)
		(width 0.254)
		(layer "In2.Cu")
		(net "P0V9_PG")
	)
	(segment
		(start 31.8262 -48.383698)
		(end 31.8262 -74.816208)
		(width 0.254)
		(layer "In2.Cu")
		(net "P0V9_PG")
	)
	(segment
		(start 191.829182 -77.863954)
		(end 190.40348 -76.438252)
		(width 0.254)
		(layer "In2.Cu")
		(net "P0V9_PG")
	)
	(segment
		(start 75.425554 -108.2675)
		(end 69.594222 -102.436168)
		(width 0.254)
		(layer "In2.Cu")
		(net "P0V9_PG")
	)
	(segment
		(start 191.829182 -108.541058)
		(end 191.829182 -77.863954)
		(width 0.254)
		(layer "In2.Cu")
		(net "P0V9_PG")
	)
	(segment
		(start 174.0916 -18.6436)
		(end 169.6974 -14.2494)
		(width 0.254)
		(layer "In2.Cu")
		(net "P0V9_PG")
	)
	(segment
		(start 34.685224 -34.972244)
		(end 34.685224 -45.524674)
		(width 0.254)
		(layer "In2.Cu")
		(net "P0V9_PG")
	)
	(segment
		(start 185.3184 -20.06473)
		(end 183.89727 -18.6436)
		(width 0.254)
		(layer "In2.Cu")
		(net "P0V9_PG")
	)
	(segment
		(start 59.44616 -102.436168)
		(end 41.280588 -84.270596)
		(width 0.254)
		(layer "In2.Cu")
		(net "P0V9_PG")
	)
	(segment
		(start 31.8262 -74.816208)
		(end 41.280588 -84.270596)
		(width 0.254)
		(layer "In2.Cu")
		(net "P0V9_PG")
	)
	(segment
		(start 93.3323 -104.12857)
		(end 89.19337 -108.2675)
		(width 0.254)
		(layer "In2.Cu")
		(net "P0V9_PG")
	)
	(segment
		(start 125.744224 -115.6335)
		(end 126.985014 -116.87429)
		(width 0.254)
		(layer "In5.Cu")
		(net "P0V9_PG")
	)
	(segment
		(start 24.8158 -84.2518)
		(end 24.8158 -90.551)
		(width 0.254)
		(layer "In5.Cu")
		(net "P0V9_PG")
	)
	(segment
		(start 126.985014 -116.87429)
		(end 139.371832 -116.87429)
		(width 0.254)
		(layer "In5.Cu")
		(net "P0V9_PG")
	)
	(segment
		(start 23.5966 -94.315534)
		(end 21.79193 -96.120204)
		(width 0.254)
		(layer "In5.Cu")
		(net "P0V9_PG")
	)
	(segment
		(start 143.703802 -121.20626)
		(end 163.40328 -121.20626)
		(width 0.254)
		(layer "In5.Cu")
		(net "P0V9_PG")
	)
	(segment
		(start 25.4762 -83.5914)
		(end 24.8158 -84.2518)
		(width 0.254)
		(layer "In5.Cu")
		(net "P0V9_PG")
	)
	(segment
		(start 113.919 -107.696)
		(end 114.427 -108.204)
		(width 0.254)
		(layer "In5.Cu")
		(net "P0V9_PG")
	)
	(segment
		(start 182.70093 -113.86693)
		(end 184.404 -115.57)
		(width 0.254)
		(layer "In5.Cu")
		(net "P0V9_PG")
	)
	(segment
		(start 23.5966 -91.7702)
		(end 23.5966 -94.315534)
		(width 0.254)
		(layer "In5.Cu")
		(net "P0V9_PG")
	)
	(segment
		(start 25.9842 -83.5914)
		(end 25.4762 -83.5914)
		(width 0.254)
		(layer "In5.Cu")
		(net "P0V9_PG")
	)
	(segment
		(start 170.74261 -113.86693)
		(end 182.70093 -113.86693)
		(width 0.254)
		(layer "In5.Cu")
		(net "P0V9_PG")
	)
	(segment
		(start 163.40328 -121.20626)
		(end 170.74261 -113.86693)
		(width 0.254)
		(layer "In5.Cu")
		(net "P0V9_PG")
	)
	(segment
		(start 139.371832 -116.87429)
		(end 143.703802 -121.20626)
		(width 0.254)
		(layer "In5.Cu")
		(net "P0V9_PG")
	)
	(segment
		(start 114.427 -108.204)
		(end 115.069874 -108.204)
		(width 0.254)
		(layer "In5.Cu")
		(net "P0V9_PG")
	)
	(segment
		(start 187.39612 -114.22888)
		(end 187.39612 -112.97412)
		(width 0.254)
		(layer "In5.Cu")
		(net "P0V9_PG")
	)
	(segment
		(start 187.39612 -112.97412)
		(end 188.84392 -111.52632)
		(width 0.254)
		(layer "In5.Cu")
		(net "P0V9_PG")
	)
	(segment
		(start 24.8158 -90.551)
		(end 23.5966 -91.7702)
		(width 0.254)
		(layer "In5.Cu")
		(net "P0V9_PG")
	)
	(segment
		(start 115.069874 -108.204)
		(end 122.499374 -115.6335)
		(width 0.254)
		(layer "In5.Cu")
		(net "P0V9_PG")
	)
	(segment
		(start 186.055 -115.57)
		(end 187.39612 -114.22888)
		(width 0.254)
		(layer "In5.Cu")
		(net "P0V9_PG")
	)
	(segment
		(start 122.499374 -115.6335)
		(end 125.744224 -115.6335)
		(width 0.254)
		(layer "In5.Cu")
		(net "P0V9_PG")
	)
	(segment
		(start 184.404 -115.57)
		(end 186.055 -115.57)
		(width 0.254)
		(layer "In5.Cu")
		(net "P0V9_PG")
	)
	(segment
		(start 43.133264 -33.151064)
		(end 42.418 -32.4358)
		(width 0.254)
		(layer "F.Cu")
		(net "P0V9_MODE")
	)
	(segment
		(start 40.6527 -30.988)
		(end 40.6527 -31.3309)
		(width 0.254)
		(layer "F.Cu")
		(net "P0V9_MODE")
	)
	(segment
		(start 43.610276 -33.151064)
		(end 43.133264 -33.151064)
		(width 0.254)
		(layer "F.Cu")
		(net "P0V9_MODE")
	)
	(segment
		(start 41.6306 -32.6644)
		(end 41.275 -32.6644)
		(width 0.254)
		(layer "F.Cu")
		(net "P0V9_MODE")
	)
	(segment
		(start 40.6527 -30.988)
		(end 40.6527 -29.8958)
		(width 0.254)
		(layer "F.Cu")
		(net "P0V9_MODE")
	)
	(segment
		(start 42.418 -32.4358)
		(end 41.8592 -32.4358)
		(width 0.254)
		(layer "F.Cu")
		(net "P0V9_MODE")
	)
	(segment
		(start 41.275 -31.9532)
		(end 41.275 -32.6644)
		(width 0.254)
		(layer "F.Cu")
		(net "P0V9_MODE")
	)
	(segment
		(start 41.8592 -32.4358)
		(end 41.6306 -32.6644)
		(width 0.254)
		(layer "F.Cu")
		(net "P0V9_MODE")
	)
	(segment
		(start 40.6527 -31.3309)
		(end 41.275 -31.9532)
		(width 0.254)
		(layer "F.Cu")
		(net "P0V9_MODE")
	)
	(via
		(at 41.275 -32.6644)
		(size 0.6604)
		(drill 0.3302)
		(layers "F.Cu" "B.Cu")
		(net "P0V9_MODE")
	)
	(segment
		(start 45.411136 -31.850076)
		(end 45.411136 -30.484064)
		(width 0.254)
		(layer "F.Cu")
		(net "P0V9_GSNS")
	)
	(segment
		(start 45.9867 -29.9085)
		(end 45.9867 -29.083)
		(width 0.254)
		(layer "F.Cu")
		(net "P0V9_GSNS")
	)
	(segment
		(start 46.2534 -26.797)
		(end 45.9994 -26.543)
		(width 0.254)
		(layer "F.Cu")
		(net "P0V9_GSNS")
	)
	(segment
		(start 46.6217 -28.2829)
		(end 45.9867 -28.9179)
		(width 0.254)
		(layer "F.Cu")
		(net "P0V9_GSNS")
	)
	(segment
		(start 45.6057 -27.94)
		(end 46.6217 -27.94)
		(width 0.254)
		(layer "F.Cu")
		(net "P0V9_GSNS")
	)
	(segment
		(start 44.7802 -26.543)
		(end 44.7802 -27.1145)
		(width 0.254)
		(layer "F.Cu")
		(net "P0V9_GSNS")
	)
	(segment
		(start 44.7802 -27.1145)
		(end 45.6057 -27.94)
		(width 0.254)
		(layer "F.Cu")
		(net "P0V9_GSNS")
	)
	(segment
		(start 45.9867 -28.9179)
		(end 45.9867 -29.083)
		(width 0.254)
		(layer "F.Cu")
		(net "P0V9_GSNS")
	)
	(segment
		(start 46.6217 -27.94)
		(end 46.6217 -28.2829)
		(width 0.254)
		(layer "F.Cu")
		(net "P0V9_GSNS")
	)
	(segment
		(start 45.9994 -26.543)
		(end 44.7802 -26.543)
		(width 0.254)
		(layer "F.Cu")
		(net "P0V9_GSNS")
	)
	(segment
		(start 45.411136 -30.484064)
		(end 45.9867 -29.9085)
		(width 0.254)
		(layer "F.Cu")
		(net "P0V9_GSNS")
	)
	(via
		(at 107.00004 -66.000122)
		(size 0.4572)
		(drill 0.2032)
		(layers "F.Cu" "B.Cu")
		(net "P0V9_GSNS")
	)
	(via
		(at 47.257716 -26.797762)
		(size 0.6096)
		(drill 0.3048)
		(layers "F.Cu" "B.Cu")
		(net "P0V9_GSNS")
	)
	(via
		(at 90.816684 -58.509916)
		(size 0.508)
		(drill 0.254)
		(layers "F.Cu" "B.Cu")
		(net "P0V9_GSNS")
	)
	(via
		(at 46.2534 -26.797)
		(size 0.508)
		(drill 0.254)
		(layers "F.Cu" "B.Cu")
		(net "P0V9_GSNS")
	)
	(segment
		(start 83.09356 -56.42864)
		(end 83.09356 -41.7957)
		(width 0.254)
		(layer "B.Cu")
		(net "P0V9_GSNS")
	)
	(segment
		(start 47.257716 -26.797762)
		(end 46.254162 -26.797762)
		(width 0.254)
		(layer "B.Cu")
		(net "P0V9_GSNS")
	)
	(segment
		(start 107.00004 -66.463164)
		(end 107.00004 -66.000122)
		(width 0.254)
		(layer "B.Cu")
		(net "P0V9_GSNS")
	)
	(segment
		(start 83.09356 -41.7957)
		(end 78.36154 -37.06368)
		(width 0.254)
		(layer "B.Cu")
		(net "P0V9_GSNS")
	)
	(segment
		(start 107.550966 -67.01409)
		(end 107.00004 -66.463164)
		(width 0.254)
		(layer "B.Cu")
		(net "P0V9_GSNS")
	)
	(segment
		(start 90.816684 -58.509916)
		(end 85.174836 -58.509916)
		(width 0.254)
		(layer "B.Cu")
		(net "P0V9_GSNS")
	)
	(segment
		(start 47.918878 -26.1366)
		(end 47.257716 -26.797762)
		(width 0.254)
		(layer "B.Cu")
		(net "P0V9_GSNS")
	)
	(segment
		(start 78.36154 -32.869124)
		(end 71.629016 -26.1366)
		(width 0.254)
		(layer "B.Cu")
		(net "P0V9_GSNS")
	)
	(segment
		(start 46.254162 -26.797762)
		(end 46.2534 -26.797)
		(width 0.254)
		(layer "B.Cu")
		(net "P0V9_GSNS")
	)
	(segment
		(start 71.629016 -26.1366)
		(end 47.918878 -26.1366)
		(width 0.254)
		(layer "B.Cu")
		(net "P0V9_GSNS")
	)
	(segment
		(start 78.36154 -37.06368)
		(end 78.36154 -32.869124)
		(width 0.254)
		(layer "B.Cu")
		(net "P0V9_GSNS")
	)
	(segment
		(start 85.174836 -58.509916)
		(end 83.09356 -56.42864)
		(width 0.254)
		(layer "B.Cu")
		(net "P0V9_GSNS")
	)
	(segment
		(start 90.816684 -58.852562)
		(end 91.517216 -59.553094)
		(width 0.254)
		(layer "In2.Cu")
		(net "P0V9_GSNS")
	)
	(segment
		(start 107.45724 -65.542922)
		(end 107.00004 -66.000122)
		(width 0.254)
		(layer "In2.Cu")
		(net "P0V9_GSNS")
	)
	(segment
		(start 95.847662 -57.542938)
		(end 104.18953 -57.542938)
		(width 0.254)
		(layer "In2.Cu")
		(net "P0V9_GSNS")
	)
	(segment
		(start 90.816684 -58.509916)
		(end 90.816684 -58.852562)
		(width 0.254)
		(layer "In2.Cu")
		(net "P0V9_GSNS")
	)
	(segment
		(start 93.837506 -59.553094)
		(end 95.847662 -57.542938)
		(width 0.254)
		(layer "In2.Cu")
		(net "P0V9_GSNS")
	)
	(segment
		(start 91.517216 -59.553094)
		(end 93.837506 -59.553094)
		(width 0.254)
		(layer "In2.Cu")
		(net "P0V9_GSNS")
	)
	(segment
		(start 107.45724 -60.810648)
		(end 107.45724 -65.542922)
		(width 0.254)
		(layer "In2.Cu")
		(net "P0V9_GSNS")
	)
	(segment
		(start 104.18953 -57.542938)
		(end 107.45724 -60.810648)
		(width 0.254)
		(layer "In2.Cu")
		(net "P0V9_GSNS")
	)
	(segment
		(start 39.8018 -34.6075)
		(end 40.4495 -34.6075)
		(width 0.254)
		(layer "F.Cu")
		(net "P0V9_EN")
	)
	(segment
		(start 43.610276 -33.650936)
		(end 42.643806 -33.650936)
		(width 0.254)
		(layer "F.Cu")
		(net "P0V9_EN")
	)
	(segment
		(start 39.8018 -34.6075)
		(end 39.247064 -34.6075)
		(width 0.254)
		(layer "F.Cu")
		(net "P0V9_EN")
	)
	(segment
		(start 39.183564 -34.671)
		(end 38.7858 -34.671)
		(width 0.254)
		(layer "F.Cu")
		(net "P0V9_EN")
	)
	(segment
		(start 39.247064 -34.6075)
		(end 39.183564 -34.671)
		(width 0.254)
		(layer "F.Cu")
		(net "P0V9_EN")
	)
	(segment
		(start 40.969946 -34.087054)
		(end 41.991026 -34.087054)
		(width 0.254)
		(layer "F.Cu")
		(net "P0V9_EN")
	)
	(segment
		(start 40.4495 -34.6075)
		(end 40.969946 -34.087054)
		(width 0.254)
		(layer "F.Cu")
		(net "P0V9_EN")
	)
	(segment
		(start 42.643806 -33.650936)
		(end 42.207688 -34.087054)
		(width 0.254)
		(layer "F.Cu")
		(net "P0V9_EN")
	)
	(segment
		(start 42.207688 -34.087054)
		(end 41.991026 -34.087054)
		(width 0.254)
		(layer "F.Cu")
		(net "P0V9_EN")
	)
	(via
		(at 41.991026 -34.087054)
		(size 0.6604)
		(drill 0.3302)
		(layers "F.Cu" "B.Cu")
		(net "P0V9_EN")
	)
	(segment
		(start 47.4218 -39.878)
		(end 52.6288 -39.878)
		(width 0.508)
		(layer "F.Cu")
		(net "P0V9_DL")
	)
	(segment
		(start 46.9138 -40.386)
		(end 45.4152 -38.8874)
		(width 0.508)
		(layer "F.Cu")
		(net "P0V9_DL")
	)
	(segment
		(start 45.411136 -36.698936)
		(end 45.411136 -34.951924)
		(width 0.254)
		(layer "F.Cu")
		(net "P0V9_DL")
	)
	(segment
		(start 46.9138 -40.386)
		(end 47.4218 -39.878)
		(width 0.508)
		(layer "F.Cu")
		(net "P0V9_DL")
	)
	(segment
		(start 45.4152 -38.8874)
		(end 45.4152 -36.703)
		(width 0.508)
		(layer "F.Cu")
		(net "P0V9_DL")
	)
	(segment
		(start 45.4152 -36.703)
		(end 45.411136 -36.698936)
		(width 0.254)
		(layer "F.Cu")
		(net "P0V9_DL")
	)
	(segment
		(start 52.6288 -39.878)
		(end 52.8574 -40.1066)
		(width 0.508)
		(layer "F.Cu")
		(net "P0V9_DL")
	)
	(segment
		(start 52.8574 -40.1066)
		(end 52.8574 -41.1226)
		(width 0.508)
		(layer "F.Cu")
		(net "P0V9_DL")
	)
	(via
		(at 46.9138 -40.386)
		(size 0.6604)
		(drill 0.3302)
		(layers "F.Cu" "B.Cu")
		(net "P0V9_DL")
	)
	(segment
		(start 44.5262 -36.2966)
		(end 44.911264 -35.911536)
		(width 0.254)
		(layer "F.Cu")
		(net "P0V9_DH")
	)
	(segment
		(start 44.5262 -39.5224)
		(end 44.5262 -36.703)
		(width 0.508)
		(layer "F.Cu")
		(net "P0V9_DH")
	)
	(segment
		(start 44.5262 -36.703)
		(end 44.5262 -36.2966)
		(width 0.254)
		(layer "F.Cu")
		(net "P0V9_DH")
	)
	(segment
		(start 44.831 -40.9448)
		(end 44.831 -39.8272)
		(width 0.508)
		(layer "F.Cu")
		(net "P0V9_DH")
	)
	(segment
		(start 44.831 -43.0784)
		(end 44.831 -40.9448)
		(width 0.508)
		(layer "F.Cu")
		(net "P0V9_DH")
	)
	(segment
		(start 44.831 -39.8272)
		(end 44.5262 -39.5224)
		(width 0.508)
		(layer "F.Cu")
		(net "P0V9_DH")
	)
	(segment
		(start 44.911264 -35.911536)
		(end 44.911264 -34.951924)
		(width 0.254)
		(layer "F.Cu")
		(net "P0V9_DH")
	)
	(via
		(at 44.831 -40.9448)
		(size 0.6604)
		(drill 0.3302)
		(layers "F.Cu" "B.Cu")
		(net "P0V9_DH")
	)
	(segment
		(start 48.101504 -31.899098)
		(end 48.367696 -31.632906)
		(width 0.254)
		(layer "F.Cu")
		(net "P0V9_COMP")
	)
	(segment
		(start 47.00397 -31.899098)
		(end 48.101504 -31.899098)
		(width 0.254)
		(layer "F.Cu")
		(net "P0V9_COMP")
	)
	(segment
		(start 48.110902 -29.995876)
		(end 48.367696 -30.25267)
		(width 0.254)
		(layer "F.Cu")
		(net "P0V9_COMP")
	)
	(segment
		(start 48.367696 -31.632906)
		(end 48.367696 -31.153354)
		(width 0.254)
		(layer "F.Cu")
		(net "P0V9_COMP")
	)
	(segment
		(start 46.712124 -32.190944)
		(end 47.00397 -31.899098)
		(width 0.254)
		(layer "F.Cu")
		(net "P0V9_COMP")
	)
	(segment
		(start 46.712124 -32.650938)
		(end 46.712124 -32.190944)
		(width 0.254)
		(layer "F.Cu")
		(net "P0V9_COMP")
	)
	(segment
		(start 48.367696 -30.25267)
		(end 48.367696 -31.153354)
		(width 0.254)
		(layer "F.Cu")
		(net "P0V9_COMP")
	)
	(via
		(at 48.367696 -31.153354)
		(size 0.6604)
		(drill 0.3302)
		(layers "F.Cu" "B.Cu")
		(net "P0V9_COMP")
	)
	(segment
		(start 42.799 -38.1)
		(end 42.418 -38.481)
		(width 0.508)
		(layer "F.Cu")
		(net "P0V9_BST_R")
	)
	(segment
		(start 43.1292 -38.1)
		(end 42.799 -38.1)
		(width 0.508)
		(layer "F.Cu")
		(net "P0V9_BST_R")
	)
	(segment
		(start 41.86174 -38.481)
		(end 41.86174 -37.383974)
		(width 0.508)
		(layer "F.Cu")
		(net "P0V9_BST_R")
	)
	(segment
		(start 42.418 -38.481)
		(end 41.86174 -38.481)
		(width 0.508)
		(layer "F.Cu")
		(net "P0V9_BST_R")
	)
	(via
		(at 41.86174 -38.481)
		(size 0.6604)
		(drill 0.3302)
		(layers "F.Cu" "B.Cu")
		(net "P0V9_BST_R")
	)
	(segment
		(start 41.86174 -35.517328)
		(end 41.934638 -35.44443)
		(width 0.508)
		(layer "F.Cu")
		(net "P0V9_BST")
	)
	(segment
		(start 43.610276 -34.151062)
		(end 42.994834 -34.151062)
		(width 0.3048)
		(layer "F.Cu")
		(net "P0V9_BST")
	)
	(segment
		(start 42.545508 -34.600388)
		(end 42.545508 -34.83356)
		(width 0.3048)
		(layer "F.Cu")
		(net "P0V9_BST")
	)
	(segment
		(start 42.994834 -34.151062)
		(end 42.545508 -34.600388)
		(width 0.3048)
		(layer "F.Cu")
		(net "P0V9_BST")
	)
	(segment
		(start 41.86174 -36.494974)
		(end 41.86174 -35.517328)
		(width 0.508)
		(layer "F.Cu")
		(net "P0V9_BST")
	)
	(segment
		(start 42.545508 -34.83356)
		(end 41.934638 -35.44443)
		(width 0.3048)
		(layer "F.Cu")
		(net "P0V9_BST")
	)
	(via
		(at 41.934638 -35.44443)
		(size 0.6604)
		(drill 0.3302)
		(layers "F.Cu" "B.Cu")
		(net "P0V9_BST")
	)
	(segment
		(start 53.721 -44.577)
		(end 54.2036 -44.0944)
		(width 0.508)
		(layer "F.Cu")
		(net "P0V9_BG")
	)
	(segment
		(start 54.2036 -43.053)
		(end 53.7972 -42.6466)
		(width 0.508)
		(layer "F.Cu")
		(net "P0V9_BG")
	)
	(segment
		(start 54.2036 -44.0944)
		(end 54.2036 -43.053)
		(width 0.508)
		(layer "F.Cu")
		(net "P0V9_BG")
	)
	(segment
		(start 52.834794 -44.577)
		(end 53.721 -44.577)
		(width 0.508)
		(layer "F.Cu")
		(net "P0V9_BG")
	)
	(segment
		(start 53.7972 -42.6466)
		(end 52.8574 -42.6466)
		(width 0.508)
		(layer "F.Cu")
		(net "P0V9_BG")
	)
	(segment
		(start 116.000022 -69.00037)
		(end 115.50015 -69.500242)
		(width 0.4064)
		(layer "F.Cu")
		(net "P0V9")
	)
	(segment
		(start 110.999778 -68.000372)
		(end 111.499904 -67.500246)
		(width 0.4064)
		(layer "F.Cu")
		(net "P0V9")
	)
	(segment
		(start 116.000022 -65.000124)
		(end 116.500148 -64.499998)
		(width 0.4064)
		(layer "F.Cu")
		(net "P0V9")
	)
	(segment
		(start 82.0928 -97.2058)
		(end 72.53478 -87.64778)
		(width 0.508)
		(layer "F.Cu")
		(net "P0V9")
	)
	(segment
		(start 114.499898 -66.499994)
		(end 113.999772 -67.00012)
		(width 0.4064)
		(layer "F.Cu")
		(net "P0V9")
	)
	(segment
		(start 160.4772 -81.0895)
		(end 160.4772 -80.298798)
		(width 0.508)
		(layer "F.Cu")
		(net "P0V9")
	)
	(segment
		(start 116.500148 -66.499994)
		(end 116.000022 -67.00012)
		(width 0.4064)
		(layer "F.Cu")
		(net "P0V9")
	)
	(segment
		(start 115.000024 -70.000368)
		(end 114.500152 -70.50024)
		(width 0.4064)
		(layer "F.Cu")
		(net "P0V9")
	)
	(segment
		(start 111.499904 -67.499992)
		(end 111.499904 -67.500246)
		(width 0.4064)
		(layer "F.Cu")
		(net "P0V9")
	)
	(segment
		(start 116.500148 -70.50024)
		(end 117.00002 -70.000368)
		(width 0.4064)
		(layer "F.Cu")
		(net "P0V9")
	)
	(segment
		(start 113.999772 -67.00012)
		(end 113.4999 -67.499992)
		(width 0.4064)
		(layer "F.Cu")
		(net "P0V9")
	)
	(segment
		(start 116.500148 -68.500244)
		(end 116.000022 -69.00037)
		(width 0.4064)
		(layer "F.Cu")
		(net "P0V9")
	)
	(segment
		(start 117.500146 -69.500242)
		(end 118.000018 -69.00037)
		(width 0.4064)
		(layer "F.Cu")
		(net "P0V9")
	)
	(segment
		(start 111.499904 -69.500242)
		(end 111.999776 -69.00037)
		(width 0.4064)
		(layer "F.Cu")
		(net "P0V9")
	)
	(segment
		(start 111.999776 -67.00012)
		(end 111.499904 -67.499992)
		(width 0.4064)
		(layer "F.Cu")
		(net "P0V9")
	)
	(segment
		(start 112.499902 -64.499998)
		(end 111.999776 -65.000124)
		(width 0.4064)
		(layer "F.Cu")
		(net "P0V9")
	)
	(segment
		(start 114.500152 -70.50024)
		(end 114.499898 -70.50024)
		(width 0.4064)
		(layer "F.Cu")
		(net "P0V9")
	)
	(segment
		(start 118.500144 -70.50024)
		(end 118.000272 -70.000368)
		(width 0.4064)
		(layer "F.Cu")
		(net "P0V9")
	)
	(segment
		(start 118.000018 -67.00012)
		(end 117.500146 -67.499992)
		(width 0.4064)
		(layer "F.Cu")
		(net "P0V9")
	)
	(segment
		(start 113.4999 -65.499996)
		(end 113.999772 -65.000124)
		(width 0.4064)
		(layer "F.Cu")
		(net "P0V9")
	)
	(segment
		(start 110.499906 -68.500244)
		(end 110.999778 -68.000372)
		(width 0.4064)
		(layer "F.Cu")
		(net "P0V9")
	)
	(segment
		(start 116.000022 -67.00012)
		(end 115.50015 -67.499992)
		(width 0.4064)
		(layer "F.Cu")
		(net "P0V9")
	)
	(segment
		(start 113.4999 -67.499992)
		(end 113.4999 -67.500246)
		(width 0.4064)
		(layer "F.Cu")
		(net "P0V9")
	)
	(segment
		(start 111.999776 -65.000124)
		(end 111.499904 -65.499996)
		(width 0.4064)
		(layer "F.Cu")
		(net "P0V9")
	)
	(segment
		(start 118.000018 -69.00037)
		(end 118.500144 -68.500244)
		(width 0.4064)
		(layer "F.Cu")
		(net "P0V9")
	)
	(segment
		(start 127.9652 -97.2058)
		(end 82.0928 -97.2058)
		(width 0.508)
		(layer "F.Cu")
		(net "P0V9")
	)
	(segment
		(start 51.089306 -30.00883)
		(end 51.089306 -30.89402)
		(width 0.508)
		(layer "F.Cu")
		(net "P0V9")
	)
	(segment
		(start 115.50015 -67.499992)
		(end 115.50015 -67.500246)
		(width 0.4064)
		(layer "F.Cu")
		(net "P0V9")
	)
	(segment
		(start 115.50015 -65.499996)
		(end 116.000022 -65.000124)
		(width 0.4064)
		(layer "F.Cu")
		(net "P0V9")
	)
	(segment
		(start 111.999776 -69.00037)
		(end 112.499902 -68.500244)
		(width 0.4064)
		(layer "F.Cu")
		(net "P0V9")
	)
	(segment
		(start 113.4999 -69.500242)
		(end 113.999772 -69.00037)
		(width 0.4064)
		(layer "F.Cu")
		(net "P0V9")
	)
	(segment
		(start 110.499906 -70.50024)
		(end 111.000032 -70.000114)
		(width 0.4064)
		(layer "F.Cu")
		(net "P0V9")
	)
	(segment
		(start 118.500144 -66.499994)
		(end 118.000018 -67.00012)
		(width 0.4064)
		(layer "F.Cu")
		(net "P0V9")
	)
	(segment
		(start 118.000018 -65.000124)
		(end 118.500144 -64.499998)
		(width 0.4064)
		(layer "F.Cu")
		(net "P0V9")
	)
	(segment
		(start 117.500146 -65.499996)
		(end 118.000018 -65.000124)
		(width 0.4064)
		(layer "F.Cu")
		(net "P0V9")
	)
	(segment
		(start 113.999772 -69.00037)
		(end 114.499898 -68.500244)
		(width 0.4064)
		(layer "F.Cu")
		(net "P0V9")
	)
	(segment
		(start 53.07838 -87.64778)
		(end 47.9298 -82.4992)
		(width 0.508)
		(layer "F.Cu")
		(net "P0V9")
	)
	(segment
		(start 110.999778 -64.99987)
		(end 110.499906 -64.499998)
		(width 0.4064)
		(layer "F.Cu")
		(net "P0V9")
	)
	(segment
		(start 112.499902 -70.50024)
		(end 113.000028 -70.000114)
		(width 0.4064)
		(layer "F.Cu")
		(net "P0V9")
	)
	(segment
		(start 112.499902 -66.499994)
		(end 111.999776 -67.00012)
		(width 0.4064)
		(layer "F.Cu")
		(net "P0V9")
	)
	(segment
		(start 110.999778 -66.000122)
		(end 110.499906 -66.499994)
		(width 0.4064)
		(layer "F.Cu")
		(net "P0V9")
	)
	(segment
		(start 72.53478 -87.64778)
		(end 53.07838 -87.64778)
		(width 0.508)
		(layer "F.Cu")
		(net "P0V9")
	)
	(segment
		(start 113.999772 -65.000124)
		(end 114.499898 -64.499998)
		(width 0.4064)
		(layer "F.Cu")
		(net "P0V9")
	)
	(segment
		(start 117.500146 -67.499992)
		(end 117.500146 -67.500246)
		(width 0.4064)
		(layer "F.Cu")
		(net "P0V9")
	)
	(segment
		(start 47.9298 -82.4992)
		(end 45.1739 -82.4992)
		(width 0.508)
		(layer "F.Cu")
		(net "P0V9")
	)
	(via
		(at 66.8528 -35.433)
		(size 0.7112)
		(drill 0.4064)
		(layers "F.Cu" "B.Cu")
		(net "P0V9")
	)
	(via
		(at 111.000032 -70.000114)
		(size 0.4572)
		(drill 0.2032)
		(layers "F.Cu" "B.Cu")
		(net "P0V9")
	)
	(via
		(at 69.3928 -55.8038)
		(size 0.6604)
		(drill 0.3302)
		(layers "F.Cu" "B.Cu")
		(net "P0V9")
	)
	(via
		(at 68.072 -40.3098)
		(size 0.7112)
		(drill 0.4064)
		(layers "F.Cu" "B.Cu")
		(net "P0V9")
	)
	(via
		(at 63.9572 -37.7952)
		(size 0.7112)
		(drill 0.4064)
		(layers "F.Cu" "B.Cu")
		(net "P0V9")
	)
	(via
		(at 118.000018 -69.00037)
		(size 0.4572)
		(drill 0.2032)
		(layers "F.Cu" "B.Cu")
		(net "P0V9")
	)
	(via
		(at 64.4144 -34.2138)
		(size 0.7112)
		(drill 0.4064)
		(layers "F.Cu" "B.Cu")
		(net "P0V9")
	)
	(via
		(at 110.999778 -66.000122)
		(size 0.4572)
		(drill 0.2032)
		(layers "F.Cu" "B.Cu")
		(net "P0V9")
	)
	(via
		(at 68.072 -62.2046)
		(size 0.7112)
		(drill 0.4064)
		(layers "F.Cu" "B.Cu")
		(net "P0V9")
	)
	(via
		(at 64.4144 -35.433)
		(size 0.7112)
		(drill 0.4064)
		(layers "F.Cu" "B.Cu")
		(net "P0V9")
	)
	(via
		(at 115.000024 -70.000368)
		(size 0.4572)
		(drill 0.2032)
		(layers "F.Cu" "B.Cu")
		(net "P0V9")
	)
	(via
		(at 88.0618 -75.268582)
		(size 0.7112)
		(drill 0.4064)
		(layers "F.Cu" "B.Cu")
		(net "P0V9")
	)
	(via
		(at 63.9572 -39.0144)
		(size 0.7112)
		(drill 0.4064)
		(layers "F.Cu" "B.Cu")
		(net "P0V9")
	)
	(via
		(at 160.4772 -80.298798)
		(size 0.508)
		(drill 0.254)
		(layers "F.Cu" "B.Cu")
		(net "P0V9")
	)
	(via
		(at 66.8528 -58.547)
		(size 0.7112)
		(drill 0.4064)
		(layers "F.Cu" "B.Cu")
		(net "P0V9")
	)
	(via
		(at 68.072 -34.2138)
		(size 0.7112)
		(drill 0.4064)
		(layers "F.Cu" "B.Cu")
		(net "P0V9")
	)
	(via
		(at 64.4144 -56.1086)
		(size 0.7112)
		(drill 0.4064)
		(layers "F.Cu" "B.Cu")
		(net "P0V9")
	)
	(via
		(at 111.057182 -67.03441)
		(size 0.6096)
		(drill 0.3048)
		(layers "F.Cu" "B.Cu")
		(net "P0V9")
	)
	(via
		(at 68.072 -36.6522)
		(size 0.7112)
		(drill 0.4064)
		(layers "F.Cu" "B.Cu")
		(net "P0V9")
	)
	(via
		(at 116.000022 -69.00037)
		(size 0.4572)
		(drill 0.2032)
		(layers "F.Cu" "B.Cu")
		(net "P0V9")
	)
	(via
		(at 51.089306 -30.89402)
		(size 0.508)
		(drill 0.254)
		(layers "F.Cu" "B.Cu")
		(net "P0V9")
	)
	(via
		(at 63.9572 -36.576)
		(size 0.7112)
		(drill 0.4064)
		(layers "F.Cu" "B.Cu")
		(net "P0V9")
	)
	(via
		(at 69.981826 -54.320186)
		(size 0.6096)
		(drill 0.3048)
		(layers "F.Cu" "B.Cu")
		(net "P0V9")
	)
	(via
		(at 116.000022 -65.000124)
		(size 0.4572)
		(drill 0.2032)
		(layers "F.Cu" "B.Cu")
		(net "P0V9")
	)
	(via
		(at 64.4144 -57.3278)
		(size 0.7112)
		(drill 0.4064)
		(layers "F.Cu" "B.Cu")
		(net "P0V9")
	)
	(via
		(at 88.0618 -74.049382)
		(size 0.7112)
		(drill 0.4064)
		(layers "F.Cu" "B.Cu")
		(net "P0V9")
	)
	(via
		(at 68.101972 -48.59147)
		(size 0.7112)
		(drill 0.4064)
		(layers "F.Cu" "B.Cu")
		(net "P0V9")
	)
	(via
		(at 127.9652 -97.2058)
		(size 0.508)
		(drill 0.254)
		(layers "F.Cu" "B.Cu")
		(net "P0V9")
	)
	(via
		(at 68.072 -49.9872)
		(size 0.7112)
		(drill 0.4064)
		(layers "F.Cu" "B.Cu")
		(net "P0V9")
	)
	(via
		(at 69.691504 -63.677546)
		(size 0.6604)
		(drill 0.3302)
		(layers "F.Cu" "B.Cu")
		(net "P0V9")
	)
	(via
		(at 45.1739 -82.4992)
		(size 0.7112)
		(drill 0.4064)
		(layers "F.Cu" "B.Cu")
		(net "P0V9")
	)
	(via
		(at 118.000018 -67.00012)
		(size 0.4572)
		(drill 0.2032)
		(layers "F.Cu" "B.Cu")
		(net "P0V9")
	)
	(via
		(at 68.088256 -46.751748)
		(size 0.7112)
		(drill 0.4064)
		(layers "F.Cu" "B.Cu")
		(net "P0V9")
	)
	(via
		(at 68.703444 -33.241234)
		(size 0.6096)
		(drill 0.3048)
		(layers "F.Cu" "B.Cu")
		(net "P0V9")
	)
	(via
		(at 113.999772 -69.00037)
		(size 0.4572)
		(drill 0.2032)
		(layers "F.Cu" "B.Cu")
		(net "P0V9")
	)
	(via
		(at 113.999772 -65.000124)
		(size 0.4572)
		(drill 0.2032)
		(layers "F.Cu" "B.Cu")
		(net "P0V9")
	)
	(via
		(at 110.999778 -68.000372)
		(size 0.4572)
		(drill 0.2032)
		(layers "F.Cu" "B.Cu")
		(net "P0V9")
	)
	(via
		(at 69.2912 -43.8912)
		(size 0.7112)
		(drill 0.4064)
		(layers "F.Cu" "B.Cu")
		(net "P0V9")
	)
	(via
		(at 65.6336 -56.1086)
		(size 0.7112)
		(drill 0.4064)
		(layers "F.Cu" "B.Cu")
		(net "P0V9")
	)
	(via
		(at 69.2912 -42.672)
		(size 0.7112)
		(drill 0.4064)
		(layers "F.Cu" "B.Cu")
		(net "P0V9")
	)
	(via
		(at 65.022222 -33.202372)
		(size 0.6604)
		(drill 0.3302)
		(layers "F.Cu" "B.Cu")
		(net "P0V9")
	)
	(via
		(at 110.999778 -64.99987)
		(size 0.4572)
		(drill 0.2032)
		(layers "F.Cu" "B.Cu")
		(net "P0V9")
	)
	(via
		(at 116.000022 -67.00012)
		(size 0.4572)
		(drill 0.2032)
		(layers "F.Cu" "B.Cu")
		(net "P0V9")
	)
	(via
		(at 63.181484 -35.74034)
		(size 0.6096)
		(drill 0.3048)
		(layers "F.Cu" "B.Cu")
		(net "P0V9")
	)
	(via
		(at 68.072 -56.1086)
		(size 0.7112)
		(drill 0.4064)
		(layers "F.Cu" "B.Cu")
		(net "P0V9")
	)
	(via
		(at 68.072 -51.2064)
		(size 0.7112)
		(drill 0.4064)
		(layers "F.Cu" "B.Cu")
		(net "P0V9")
	)
	(via
		(at 118.000018 -65.000124)
		(size 0.4572)
		(drill 0.2032)
		(layers "F.Cu" "B.Cu")
		(net "P0V9")
	)
	(via
		(at 67.666616 -63.425578)
		(size 0.7112)
		(drill 0.4064)
		(layers "F.Cu" "B.Cu")
		(net "P0V9")
	)
	(via
		(at 65.6336 -58.547)
		(size 0.7112)
		(drill 0.4064)
		(layers "F.Cu" "B.Cu")
		(net "P0V9")
	)
	(via
		(at 64.4144 -58.547)
		(size 0.7112)
		(drill 0.4064)
		(layers "F.Cu" "B.Cu")
		(net "P0V9")
	)
	(via
		(at 62.678056 -50.716434)
		(size 0.6096)
		(drill 0.3048)
		(layers "F.Cu" "B.Cu")
		(net "P0V9")
	)
	(via
		(at 111.999776 -65.000124)
		(size 0.4572)
		(drill 0.2032)
		(layers "F.Cu" "B.Cu")
		(net "P0V9")
	)
	(via
		(at 65.6336 -57.3278)
		(size 0.7112)
		(drill 0.4064)
		(layers "F.Cu" "B.Cu")
		(net "P0V9")
	)
	(via
		(at 68.072 -58.547)
		(size 0.7112)
		(drill 0.4064)
		(layers "F.Cu" "B.Cu")
		(net "P0V9")
	)
	(via
		(at 68.072 -37.8714)
		(size 0.7112)
		(drill 0.4064)
		(layers "F.Cu" "B.Cu")
		(net "P0V9")
	)
	(via
		(at 69.2912 -34.2138)
		(size 0.7112)
		(drill 0.4064)
		(layers "F.Cu" "B.Cu")
		(net "P0V9")
	)
	(via
		(at 68.072 -39.0906)
		(size 0.7112)
		(drill 0.4064)
		(layers "F.Cu" "B.Cu")
		(net "P0V9")
	)
	(via
		(at 113.999772 -67.00012)
		(size 0.4572)
		(drill 0.2032)
		(layers "F.Cu" "B.Cu")
		(net "P0V9")
	)
	(via
		(at 111.999776 -69.00037)
		(size 0.4572)
		(drill 0.2032)
		(layers "F.Cu" "B.Cu")
		(net "P0V9")
	)
	(via
		(at 68.072 -57.3278)
		(size 0.7112)
		(drill 0.4064)
		(layers "F.Cu" "B.Cu")
		(net "P0V9")
	)
	(via
		(at 111.999776 -67.00012)
		(size 0.4572)
		(drill 0.2032)
		(layers "F.Cu" "B.Cu")
		(net "P0V9")
	)
	(via
		(at 69.2912 -45.1104)
		(size 0.7112)
		(drill 0.4064)
		(layers "F.Cu" "B.Cu")
		(net "P0V9")
	)
	(via
		(at 117.00002 -70.000368)
		(size 0.4572)
		(drill 0.2032)
		(layers "F.Cu" "B.Cu")
		(net "P0V9")
	)
	(via
		(at 63.297816 -62.002162)
		(size 0.7112)
		(drill 0.4064)
		(layers "F.Cu" "B.Cu")
		(net "P0V9")
	)
	(via
		(at 65.6336 -34.2138)
		(size 0.7112)
		(drill 0.4064)
		(layers "F.Cu" "B.Cu")
		(net "P0V9")
	)
	(via
		(at 118.000272 -70.000368)
		(size 0.4572)
		(drill 0.2032)
		(layers "F.Cu" "B.Cu")
		(net "P0V9")
	)
	(via
		(at 68.072 -59.7662)
		(size 0.7112)
		(drill 0.4064)
		(layers "F.Cu" "B.Cu")
		(net "P0V9")
	)
	(via
		(at 113.000028 -70.000114)
		(size 0.4572)
		(drill 0.2032)
		(layers "F.Cu" "B.Cu")
		(net "P0V9")
	)
	(via
		(at 68.072 -42.154348)
		(size 0.7112)
		(drill 0.4064)
		(layers "F.Cu" "B.Cu")
		(net "P0V9")
	)
	(via
		(at 68.072 -35.433)
		(size 0.7112)
		(drill 0.4064)
		(layers "F.Cu" "B.Cu")
		(net "P0V9")
	)
	(via
		(at 68.072 -60.9854)
		(size 0.7112)
		(drill 0.4064)
		(layers "F.Cu" "B.Cu")
		(net "P0V9")
	)
	(via
		(at 68.072 -52.4256)
		(size 0.7112)
		(drill 0.4064)
		(layers "F.Cu" "B.Cu")
		(net "P0V9")
	)
	(via
		(at 66.8528 -56.1086)
		(size 0.7112)
		(drill 0.4064)
		(layers "F.Cu" "B.Cu")
		(net "P0V9")
	)
	(via
		(at 65.6336 -35.433)
		(size 0.7112)
		(drill 0.4064)
		(layers "F.Cu" "B.Cu")
		(net "P0V9")
	)
	(via
		(at 68.072 -45.227748)
		(size 0.7112)
		(drill 0.4064)
		(layers "F.Cu" "B.Cu")
		(net "P0V9")
	)
	(via
		(at 66.8528 -57.3278)
		(size 0.7112)
		(drill 0.4064)
		(layers "F.Cu" "B.Cu")
		(net "P0V9")
	)
	(via
		(at 66.8528 -34.2138)
		(size 0.7112)
		(drill 0.4064)
		(layers "F.Cu" "B.Cu")
		(net "P0V9")
	)
	(via
		(at 68.088256 -43.635168)
		(size 0.7112)
		(drill 0.4064)
		(layers "F.Cu" "B.Cu")
		(net "P0V9")
	)
	(via
		(at 68.072 -53.6448)
		(size 0.7112)
		(drill 0.4064)
		(layers "F.Cu" "B.Cu")
		(net "P0V9")
	)
	(via
		(at 68.072 -54.864)
		(size 0.7112)
		(drill 0.4064)
		(layers "F.Cu" "B.Cu")
		(net "P0V9")
	)
	(segment
		(start 64.402208 -33.241234)
		(end 62.054994 -30.89402)
		(width 0.508)
		(layer "B.Cu")
		(net "P0V9")
	)
	(segment
		(start 62.054994 -30.89402)
		(end 51.089306 -30.89402)
		(width 0.508)
		(layer "B.Cu")
		(net "P0V9")
	)
	(segment
		(start 149.250654 -95.268542)
		(end 151.977344 -92.541852)
		(width 0.508)
		(layer "In2.Cu")
		(net "P0V9")
	)
	(segment
		(start 142.30985 -97.945702)
		(end 144.98701 -95.268542)
		(width 0.508)
		(layer "In2.Cu")
		(net "P0V9")
	)
	(segment
		(start 151.977344 -92.541852)
		(end 151.977344 -84.623656)
		(width 0.508)
		(layer "In2.Cu")
		(net "P0V9")
	)
	(segment
		(start 45.1739 -82.4992)
		(end 45.1739 -69.8119)
		(width 1.016)
		(layer "In2.Cu")
		(net "P0V9")
	)
	(segment
		(start 62.511178 -62.7888)
		(end 63.297816 -62.002162)
		(width 1.016)
		(layer "In2.Cu")
		(net "P0V9")
	)
	(segment
		(start 151.977344 -84.623656)
		(end 155.194 -81.407)
		(width 0.508)
		(layer "In2.Cu")
		(net "P0V9")
	)
	(segment
		(start 127.9652 -97.2058)
		(end 128.705102 -97.945702)
		(width 0.508)
		(layer "In2.Cu")
		(net "P0V9")
	)
	(segment
		(start 144.98701 -95.268542)
		(end 149.250654 -95.268542)
		(width 0.508)
		(layer "In2.Cu")
		(net "P0V9")
	)
	(segment
		(start 159.368998 -81.407)
		(end 160.4772 -80.298798)
		(width 0.508)
		(layer "In2.Cu")
		(net "P0V9")
	)
	(segment
		(start 45.1739 -69.8119)
		(end 52.197 -62.7888)
		(width 1.016)
		(layer "In2.Cu")
		(net "P0V9")
	)
	(segment
		(start 52.197 -62.7888)
		(end 62.511178 -62.7888)
		(width 1.016)
		(layer "In2.Cu")
		(net "P0V9")
	)
	(segment
		(start 155.194 -81.407)
		(end 159.368998 -81.407)
		(width 0.508)
		(layer "In2.Cu")
		(net "P0V9")
	)
	(segment
		(start 128.705102 -97.945702)
		(end 142.30985 -97.945702)
		(width 0.508)
		(layer "In2.Cu")
		(net "P0V9")
	)
	(segment
		(start 165.399974 -39.19982)
		(end 165.800024 -39.59987)
		(width 0.127)
		(layer "F.Cu")
		(net "OSC_REF_CLK")
	)
	(via
		(at 165.399974 -39.19982)
		(size 0.508)
		(drill 0.254)
		(layers "F.Cu" "B.Cu")
		(net "OSC_REF_CLK")
	)
	(segment
		(start 165.399974 -39.19982)
		(end 164.60089 -39.19982)
		(width 0.127)
		(layer "B.Cu")
		(net "OSC_REF_CLK")
	)
	(segment
		(start 189.986666 -43.9674)
		(end 189.21857 -43.199304)
		(width 0.127)
		(layer "F.Cu")
		(net "MEM_CLK_SEL")
	)
	(segment
		(start 190.52413 -44.12361)
		(end 190.36792 -43.9674)
		(width 0.127)
		(layer "F.Cu")
		(net "MEM_CLK_SEL")
	)
	(segment
		(start 190.36792 -43.9674)
		(end 189.986666 -43.9674)
		(width 0.127)
		(layer "F.Cu")
		(net "MEM_CLK_SEL")
	)
	(segment
		(start 185.799984 -41.999916)
		(end 186.028076 -41.999916)
		(width 0.127)
		(layer "F.Cu")
		(net "MEM_CLK_SEL")
	)
	(segment
		(start 186.370976 -41.657016)
		(end 186.806586 -41.657016)
		(width 0.127)
		(layer "F.Cu")
		(net "MEM_CLK_SEL")
	)
	(segment
		(start 186.806586 -41.657016)
		(end 188.348874 -43.199304)
		(width 0.127)
		(layer "F.Cu")
		(net "MEM_CLK_SEL")
	)
	(segment
		(start 188.348874 -43.199304)
		(end 189.116208 -43.199304)
		(width 0.127)
		(layer "F.Cu")
		(net "MEM_CLK_SEL")
	)
	(segment
		(start 189.21857 -43.199304)
		(end 189.116208 -43.199304)
		(width 0.127)
		(layer "F.Cu")
		(net "MEM_CLK_SEL")
	)
	(segment
		(start 186.028076 -41.999916)
		(end 186.370976 -41.657016)
		(width 0.127)
		(layer "F.Cu")
		(net "MEM_CLK_SEL")
	)
	(segment
		(start 191.402208 -44.12361)
		(end 190.52413 -44.12361)
		(width 0.127)
		(layer "F.Cu")
		(net "MEM_CLK_SEL")
	)
	(via
		(at 189.116208 -43.199304)
		(size 0.6604)
		(drill 0.3302)
		(layers "F.Cu" "B.Cu")
		(net "MEM_CLK_SEL")
	)
	(segment
		(start 108.49991 -79.500222)
		(end 108.000038 -80.000094)
		(width 0.127)
		(layer "F.Cu")
		(net "LSI_TRST_N")
	)
	(via
		(at 108.000038 -80.000094)
		(size 0.4572)
		(drill 0.2032)
		(layers "F.Cu" "B.Cu")
		(net "LSI_TRST_N")
	)
	(segment
		(start 107.061 -83.754722)
		(end 107.500166 -83.315556)
		(width 0.127)
		(layer "B.Cu")
		(net "LSI_TRST_N")
	)
	(segment
		(start 107.500166 -83.315556)
		(end 107.500166 -81.500218)
		(width 0.127)
		(layer "B.Cu")
		(net "LSI_TRST_N")
	)
	(segment
		(start 108.000038 -80.000094)
		(end 107.500166 -80.499966)
		(width 0.127)
		(layer "B.Cu")
		(net "LSI_TRST_N")
	)
	(segment
		(start 107.061 -84.0105)
		(end 107.061 -83.754722)
		(width 0.127)
		(layer "B.Cu")
		(net "LSI_TRST_N")
	)
	(segment
		(start 107.500166 -80.499966)
		(end 107.500166 -81.500218)
		(width 0.127)
		(layer "B.Cu")
		(net "LSI_TRST_N")
	)
	(segment
		(start 174.30115 -53.427884)
		(end 174.30115 -54.685438)
		(width 0.127)
		(layer "F.Cu")
		(net "LSI_TN")
	)
	(segment
		(start 175.057054 -52.67198)
		(end 174.30115 -53.427884)
		(width 0.127)
		(layer "F.Cu")
		(net "LSI_TN")
	)
	(segment
		(start 175.399954 -49.9999)
		(end 175.057054 -50.3428)
		(width 0.127)
		(layer "F.Cu")
		(net "LSI_TN")
	)
	(segment
		(start 175.057054 -50.3428)
		(end 175.057054 -52.67198)
		(width 0.127)
		(layer "F.Cu")
		(net "LSI_TN")
	)
	(segment
		(start 172.339 -56.647588)
		(end 172.339 -57.785)
		(width 0.127)
		(layer "F.Cu")
		(net "LSI_TN")
	)
	(segment
		(start 172.339 -57.785)
		(end 172.339 -59.3725)
		(width 0.127)
		(layer "F.Cu")
		(net "LSI_TN")
	)
	(segment
		(start 174.30115 -54.685438)
		(end 172.339 -56.647588)
		(width 0.127)
		(layer "F.Cu")
		(net "LSI_TN")
	)
	(segment
		(start 97.1296 -74.422)
		(end 97.6122 -73.9394)
		(width 0.127)
		(layer "F.Cu")
		(net "LSI_T_N")
	)
	(segment
		(start 109.499908 -74.500232)
		(end 109.000036 -74.00036)
		(width 0.127)
		(layer "F.Cu")
		(net "LSI_T_N")
	)
	(segment
		(start 93.0275 -74.422)
		(end 94.344998 -74.422)
		(width 0.127)
		(layer "F.Cu")
		(net "LSI_T_N")
	)
	(segment
		(start 94.344998 -74.422)
		(end 97.1296 -74.422)
		(width 0.127)
		(layer "F.Cu")
		(net "LSI_T_N")
	)
	(via
		(at 97.6122 -73.9394)
		(size 0.508)
		(drill 0.254)
		(layers "F.Cu" "B.Cu")
		(net "LSI_T_N")
	)
	(via
		(at 94.344998 -74.422)
		(size 0.6604)
		(drill 0.3302)
		(layers "F.Cu" "B.Cu")
		(net "LSI_T_N")
	)
	(via
		(at 109.000036 -74.00036)
		(size 0.4572)
		(drill 0.2032)
		(layers "F.Cu" "B.Cu")
		(net "LSI_T_N")
	)
	(segment
		(start 109.000036 -74.00036)
		(end 108.67644 -74.00036)
		(width 0.127)
		(layer "In5.Cu")
		(net "LSI_T_N")
	)
	(segment
		(start 108.67644 -74.00036)
		(end 108.2294 -74.4474)
		(width 0.127)
		(layer "In5.Cu")
		(net "LSI_T_N")
	)
	(segment
		(start 108.2294 -74.4474)
		(end 98.1202 -74.4474)
		(width 0.127)
		(layer "In5.Cu")
		(net "LSI_T_N")
	)
	(segment
		(start 98.1202 -74.4474)
		(end 97.6122 -73.9394)
		(width 0.127)
		(layer "In5.Cu")
		(net "LSI_T_N")
	)
	(segment
		(start 96.266 -69.2404)
		(end 94.9325 -69.2404)
		(width 0.127)
		(layer "F.Cu")
		(net "LSI_SCAN_ENABLE")
	)
	(segment
		(start 110.499906 -72.500236)
		(end 110.999778 -73.000108)
		(width 0.127)
		(layer "F.Cu")
		(net "LSI_SCAN_ENABLE")
	)
	(segment
		(start 94.6658 -69.5071)
		(end 94.6658 -69.9643)
		(width 0.127)
		(layer "F.Cu")
		(net "LSI_SCAN_ENABLE")
	)
	(segment
		(start 94.6785 -70.993)
		(end 95.631 -70.993)
		(width 0.127)
		(layer "F.Cu")
		(net "LSI_SCAN_ENABLE")
	)
	(segment
		(start 94.6785 -69.977)
		(end 95.631 -69.977)
		(width 0.127)
		(layer "F.Cu")
		(net "LSI_SCAN_ENABLE")
	)
	(segment
		(start 95.631 -69.977)
		(end 95.885 -70.231)
		(width 0.127)
		(layer "F.Cu")
		(net "LSI_SCAN_ENABLE")
	)
	(segment
		(start 94.6658 -69.9643)
		(end 94.6785 -69.977)
		(width 0.127)
		(layer "F.Cu")
		(net "LSI_SCAN_ENABLE")
	)
	(segment
		(start 94.9325 -69.2404)
		(end 94.6658 -69.5071)
		(width 0.127)
		(layer "F.Cu")
		(net "LSI_SCAN_ENABLE")
	)
	(segment
		(start 95.885 -70.739)
		(end 95.885 -70.485)
		(width 0.127)
		(layer "F.Cu")
		(net "LSI_SCAN_ENABLE")
	)
	(segment
		(start 95.631 -70.993)
		(end 95.885 -70.739)
		(width 0.127)
		(layer "F.Cu")
		(net "LSI_SCAN_ENABLE")
	)
	(segment
		(start 95.885 -70.231)
		(end 95.885 -70.485)
		(width 0.127)
		(layer "F.Cu")
		(net "LSI_SCAN_ENABLE")
	)
	(via
		(at 95.885 -70.485)
		(size 0.6604)
		(drill 0.3302)
		(layers "F.Cu" "B.Cu")
		(net "LSI_SCAN_ENABLE")
	)
	(via
		(at 110.999778 -73.000108)
		(size 0.4572)
		(drill 0.2032)
		(layers "F.Cu" "B.Cu")
		(net "LSI_SCAN_ENABLE")
	)
	(via
		(at 96.266 -69.2404)
		(size 0.508)
		(drill 0.254)
		(layers "F.Cu" "B.Cu")
		(net "LSI_SCAN_ENABLE")
	)
	(segment
		(start 96.266 -69.2404)
		(end 96.7359 -69.2404)
		(width 0.127)
		(layer "In5.Cu")
		(net "LSI_SCAN_ENABLE")
	)
	(segment
		(start 109.9058 -72.517)
		(end 110.51667 -72.517)
		(width 0.127)
		(layer "In5.Cu")
		(net "LSI_SCAN_ENABLE")
	)
	(segment
		(start 109.49432 -69.735446)
		(end 109.49432 -72.10552)
		(width 0.127)
		(layer "In5.Cu")
		(net "LSI_SCAN_ENABLE")
	)
	(segment
		(start 110.51667 -72.517)
		(end 110.999778 -73.000108)
		(width 0.127)
		(layer "In5.Cu")
		(net "LSI_SCAN_ENABLE")
	)
	(segment
		(start 96.7359 -69.2404)
		(end 97.056448 -69.560948)
		(width 0.127)
		(layer "In5.Cu")
		(net "LSI_SCAN_ENABLE")
	)
	(segment
		(start 109.319822 -69.560948)
		(end 109.49432 -69.735446)
		(width 0.127)
		(layer "In5.Cu")
		(net "LSI_SCAN_ENABLE")
	)
	(segment
		(start 109.49432 -72.10552)
		(end 109.9058 -72.517)
		(width 0.127)
		(layer "In5.Cu")
		(net "LSI_SCAN_ENABLE")
	)
	(segment
		(start 97.056448 -69.560948)
		(end 109.319822 -69.560948)
		(width 0.127)
		(layer "In5.Cu")
		(net "LSI_SCAN_ENABLE")
	)
	(segment
		(start 176.6824 -59.3725)
		(end 176.6824 -57.785)
		(width 0.127)
		(layer "F.Cu")
		(net "LSI_SCAN_EN")
	)
	(segment
		(start 176.579276 -51.179476)
		(end 176.1998 -50.8)
		(width 0.127)
		(layer "F.Cu")
		(net "LSI_SCAN_EN")
	)
	(segment
		(start 176.6824 -57.785)
		(end 176.6824 -56.677306)
		(width 0.127)
		(layer "F.Cu")
		(net "LSI_SCAN_EN")
	)
	(segment
		(start 176.579276 -56.574182)
		(end 176.579276 -51.179476)
		(width 0.127)
		(layer "F.Cu")
		(net "LSI_SCAN_EN")
	)
	(segment
		(start 176.6824 -59.3725)
		(end 175.5394 -59.3725)
		(width 0.127)
		(layer "F.Cu")
		(net "LSI_SCAN_EN")
	)
	(segment
		(start 176.6824 -56.677306)
		(end 176.579276 -56.574182)
		(width 0.127)
		(layer "F.Cu")
		(net "LSI_SCAN_EN")
	)
	(segment
		(start 109.499908 -77.500226)
		(end 109.000036 -77.000354)
		(width 0.127)
		(layer "F.Cu")
		(net "LSI_PROCMON")
	)
	(via
		(at 109.000036 -77.000354)
		(size 0.4572)
		(drill 0.2032)
		(layers "F.Cu" "B.Cu")
		(net "LSI_PROCMON")
	)
	(segment
		(start 109.000036 -77.987906)
		(end 109.50067 -78.48854)
		(width 0.127)
		(layer "B.Cu")
		(net "LSI_PROCMON")
	)
	(segment
		(start 109.000036 -77.000354)
		(end 109.000036 -77.987906)
		(width 0.127)
		(layer "B.Cu")
		(net "LSI_PROCMON")
	)
	(segment
		(start 174.4726 -59.3725)
		(end 174.4726 -57.785)
		(width 0.127)
		(layer "F.Cu")
		(net "LSI_JTAG_EN_N")
	)
	(segment
		(start 175.32858 -53.497226)
		(end 175.32858 -55.09514)
		(width 0.127)
		(layer "F.Cu")
		(net "LSI_JTAG_EN_N")
	)
	(segment
		(start 175.8569 -52.968906)
		(end 175.32858 -53.497226)
		(width 0.127)
		(layer "F.Cu")
		(net "LSI_JTAG_EN_N")
	)
	(segment
		(start 175.399954 -50.8)
		(end 175.399954 -50.939954)
		(width 0.127)
		(layer "F.Cu")
		(net "LSI_JTAG_EN_N")
	)
	(segment
		(start 174.4726 -55.95112)
		(end 174.4726 -57.785)
		(width 0.127)
		(layer "F.Cu")
		(net "LSI_JTAG_EN_N")
	)
	(segment
		(start 175.399954 -50.939954)
		(end 175.8569 -51.3969)
		(width 0.127)
		(layer "F.Cu")
		(net "LSI_JTAG_EN_N")
	)
	(segment
		(start 175.32858 -55.09514)
		(end 174.4726 -55.95112)
		(width 0.127)
		(layer "F.Cu")
		(net "LSI_JTAG_EN_N")
	)
	(segment
		(start 175.8569 -51.3969)
		(end 175.8569 -52.968906)
		(width 0.127)
		(layer "F.Cu")
		(net "LSI_JTAG_EN_N")
	)
	(segment
		(start 176.9999 -51.780186)
		(end 176.9999 -51.599846)
		(width 0.127)
		(layer "F.Cu")
		(net "LSI_IDDT")
	)
	(segment
		(start 178.181 -56.761634)
		(end 177.6349 -56.215534)
		(width 0.127)
		(layer "F.Cu")
		(net "LSI_IDDT")
	)
	(segment
		(start 178.181 -58.07837)
		(end 178.181 -57.277)
		(width 0.127)
		(layer "F.Cu")
		(net "LSI_IDDT")
	)
	(segment
		(start 177.6349 -56.215534)
		(end 177.6349 -52.415186)
		(width 0.127)
		(layer "F.Cu")
		(net "LSI_IDDT")
	)
	(segment
		(start 177.6984 -59.3725)
		(end 177.6984 -58.56097)
		(width 0.127)
		(layer "F.Cu")
		(net "LSI_IDDT")
	)
	(segment
		(start 177.6349 -52.415186)
		(end 176.9999 -51.780186)
		(width 0.127)
		(layer "F.Cu")
		(net "LSI_IDDT")
	)
	(segment
		(start 178.181 -57.277)
		(end 178.181 -56.761634)
		(width 0.127)
		(layer "F.Cu")
		(net "LSI_IDDT")
	)
	(segment
		(start 177.6984 -58.56097)
		(end 178.181 -58.07837)
		(width 0.127)
		(layer "F.Cu")
		(net "LSI_IDDT")
	)
	(segment
		(start 118.500144 -72.500236)
		(end 118.000272 -73.000108)
		(width 0.127)
		(layer "F.Cu")
		(net "LSI_EFUSE")
	)
	(via
		(at 118.000272 -73.000108)
		(size 0.4572)
		(drill 0.2032)
		(layers "F.Cu" "B.Cu")
		(net "LSI_EFUSE")
	)
	(via
		(at 127.311658 -90.001344)
		(size 0.6096)
		(drill 0.3048)
		(layers "F.Cu" "B.Cu")
		(net "LSI_EFUSE")
	)
	(via
		(at 127.543052 -88.519)
		(size 0.508)
		(drill 0.254)
		(layers "F.Cu" "B.Cu")
		(net "LSI_EFUSE")
	)
	(segment
		(start 127.543052 -88.519)
		(end 127.311658 -88.750394)
		(width 0.127)
		(layer "B.Cu")
		(net "LSI_EFUSE")
	)
	(segment
		(start 127.5588 -90.983816)
		(end 127.311658 -90.736674)
		(width 0.127)
		(layer "B.Cu")
		(net "LSI_EFUSE")
	)
	(segment
		(start 127.5588 -91.581986)
		(end 127.5588 -90.983816)
		(width 0.127)
		(layer "B.Cu")
		(net "LSI_EFUSE")
	)
	(segment
		(start 127.311658 -88.750394)
		(end 127.311658 -90.001344)
		(width 0.127)
		(layer "B.Cu")
		(net "LSI_EFUSE")
	)
	(segment
		(start 127.311658 -90.736674)
		(end 127.311658 -90.001344)
		(width 0.127)
		(layer "B.Cu")
		(net "LSI_EFUSE")
	)
	(segment
		(start 123.16333 -78.606396)
		(end 123.393708 -78.836774)
		(width 0.127)
		(layer "In2.Cu")
		(net "LSI_EFUSE")
	)
	(segment
		(start 123.393708 -79.197708)
		(end 123.825 -79.629)
		(width 0.127)
		(layer "In2.Cu")
		(net "LSI_EFUSE")
	)
	(segment
		(start 118.431564 -73.4314)
		(end 120.142 -73.4314)
		(width 0.127)
		(layer "In2.Cu")
		(net "LSI_EFUSE")
	)
	(segment
		(start 122.513344 -78.070456)
		(end 123.049284 -78.606396)
		(width 0.127)
		(layer "In2.Cu")
		(net "LSI_EFUSE")
	)
	(segment
		(start 123.825 -79.629)
		(end 123.825 -81.0133)
		(width 0.127)
		(layer "In2.Cu")
		(net "LSI_EFUSE")
	)
	(segment
		(start 127.543052 -87.284052)
		(end 127.543052 -88.519)
		(width 0.127)
		(layer "In2.Cu")
		(net "LSI_EFUSE")
	)
	(segment
		(start 121.70664 -76.5302)
		(end 122.1486 -76.5302)
		(width 0.127)
		(layer "In2.Cu")
		(net "LSI_EFUSE")
	)
	(segment
		(start 120.142 -73.4314)
		(end 120.606312 -73.895712)
		(width 0.127)
		(layer "In2.Cu")
		(net "LSI_EFUSE")
	)
	(segment
		(start 124.5108 -82.2071)
		(end 124.7775 -82.4738)
		(width 0.127)
		(layer "In2.Cu")
		(net "LSI_EFUSE")
	)
	(segment
		(start 122.1486 -76.5302)
		(end 122.513344 -76.894944)
		(width 0.127)
		(layer "In2.Cu")
		(net "LSI_EFUSE")
	)
	(segment
		(start 127.228854 -85.514688)
		(end 127.228854 -86.969854)
		(width 0.127)
		(layer "In2.Cu")
		(net "LSI_EFUSE")
	)
	(segment
		(start 122.513344 -76.894944)
		(end 122.513344 -78.070456)
		(width 0.127)
		(layer "In2.Cu")
		(net "LSI_EFUSE")
	)
	(segment
		(start 121.04624 -74.734928)
		(end 121.04624 -75.8698)
		(width 0.127)
		(layer "In2.Cu")
		(net "LSI_EFUSE")
	)
	(segment
		(start 123.825 -81.0133)
		(end 124.5108 -81.6991)
		(width 0.127)
		(layer "In2.Cu")
		(net "LSI_EFUSE")
	)
	(segment
		(start 125.1712 -82.4738)
		(end 126.238 -83.5406)
		(width 0.127)
		(layer "In2.Cu")
		(net "LSI_EFUSE")
	)
	(segment
		(start 118.000272 -73.000108)
		(end 118.431564 -73.4314)
		(width 0.127)
		(layer "In2.Cu")
		(net "LSI_EFUSE")
	)
	(segment
		(start 123.393708 -78.836774)
		(end 123.393708 -79.197708)
		(width 0.127)
		(layer "In2.Cu")
		(net "LSI_EFUSE")
	)
	(segment
		(start 123.049284 -78.606396)
		(end 123.16333 -78.606396)
		(width 0.127)
		(layer "In2.Cu")
		(net "LSI_EFUSE")
	)
	(segment
		(start 126.238 -83.5406)
		(end 126.238 -84.523834)
		(width 0.127)
		(layer "In2.Cu")
		(net "LSI_EFUSE")
	)
	(segment
		(start 127.228854 -86.969854)
		(end 127.543052 -87.284052)
		(width 0.127)
		(layer "In2.Cu")
		(net "LSI_EFUSE")
	)
	(segment
		(start 120.606312 -73.895712)
		(end 120.606312 -74.295)
		(width 0.127)
		(layer "In2.Cu")
		(net "LSI_EFUSE")
	)
	(segment
		(start 120.606312 -74.295)
		(end 121.04624 -74.734928)
		(width 0.127)
		(layer "In2.Cu")
		(net "LSI_EFUSE")
	)
	(segment
		(start 124.5108 -81.6991)
		(end 124.5108 -82.2071)
		(width 0.127)
		(layer "In2.Cu")
		(net "LSI_EFUSE")
	)
	(segment
		(start 126.238 -84.523834)
		(end 127.228854 -85.514688)
		(width 0.127)
		(layer "In2.Cu")
		(net "LSI_EFUSE")
	)
	(segment
		(start 124.7775 -82.4738)
		(end 125.1712 -82.4738)
		(width 0.127)
		(layer "In2.Cu")
		(net "LSI_EFUSE")
	)
	(segment
		(start 121.04624 -75.8698)
		(end 121.70664 -76.5302)
		(width 0.127)
		(layer "In2.Cu")
		(net "LSI_EFUSE")
	)
	(segment
		(start 178.181 -55.626)
		(end 178.181 -52.503832)
		(width 0.127)
		(layer "F.Cu")
		(net "JTAG_IOC_TMS")
	)
	(segment
		(start 177.406808 -51.72964)
		(end 177.406808 -51.206908)
		(width 0.127)
		(layer "F.Cu")
		(net "JTAG_IOC_TMS")
	)
	(segment
		(start 177.406808 -51.206908)
		(end 176.9999 -50.8)
		(width 0.127)
		(layer "F.Cu")
		(net "JTAG_IOC_TMS")
	)
	(segment
		(start 178.181 -52.503832)
		(end 177.406808 -51.72964)
		(width 0.127)
		(layer "F.Cu")
		(net "JTAG_IOC_TMS")
	)
	(segment
		(start 175.485298 -55.656988)
		(end 175.485298 -56.506364)
		(width 0.127)
		(layer "F.Cu")
		(net "JTAG_IOC_TDI")
	)
	(segment
		(start 175.485298 -56.506364)
		(end 175.697134 -56.7182)
		(width 0.127)
		(layer "F.Cu")
		(net "JTAG_IOC_TDI")
	)
	(segment
		(start 175.864774 -55.277512)
		(end 175.485298 -55.656988)
		(width 0.127)
		(layer "F.Cu")
		(net "JTAG_IOC_TDI")
	)
	(segment
		(start 176.1998 -53.197506)
		(end 175.864774 -53.532532)
		(width 0.127)
		(layer "F.Cu")
		(net "JTAG_IOC_TDI")
	)
	(segment
		(start 176.1998 -51.599846)
		(end 176.1998 -53.197506)
		(width 0.127)
		(layer "F.Cu")
		(net "JTAG_IOC_TDI")
	)
	(segment
		(start 175.864774 -53.532532)
		(end 175.864774 -55.277512)
		(width 0.127)
		(layer "F.Cu")
		(net "JTAG_IOC_TDI")
	)
	(segment
		(start 176.1998 -49.999646)
		(end 176.1998 -49.9999)
		(width 0.127)
		(layer "F.Cu")
		(net "JTAG_IOC_TCK")
	)
	(segment
		(start 175.79975 -50.399442)
		(end 176.199546 -49.999646)
		(width 0.127)
		(layer "F.Cu")
		(net "JTAG_IOC_TCK")
	)
	(segment
		(start 176.199546 -49.999646)
		(end 176.1998 -49.999646)
		(width 0.127)
		(layer "F.Cu")
		(net "JTAG_IOC_TCK")
	)
	(via
		(at 175.79975 -50.399442)
		(size 0.508)
		(drill 0.254)
		(layers "F.Cu" "B.Cu")
		(net "JTAG_IOC_TCK")
	)
	(segment
		(start 175.79975 -50.937414)
		(end 175.79975 -50.399442)
		(width 0.127)
		(layer "B.Cu")
		(net "JTAG_IOC_TCK")
	)
	(segment
		(start 175.312578 -52.221638)
		(end 175.312578 -51.424586)
		(width 0.127)
		(layer "B.Cu")
		(net "JTAG_IOC_TCK")
	)
	(segment
		(start 175.312578 -51.424586)
		(end 175.79975 -50.937414)
		(width 0.127)
		(layer "B.Cu")
		(net "JTAG_IOC_TCK")
	)
	(segment
		(start 108.077 -85.161374)
		(end 108.914184 -84.32419)
		(width 0.127)
		(layer "F.Cu")
		(net "JTAG_EXP_TMS")
	)
	(segment
		(start 107.02925 -88.024208)
		(end 107.725718 -87.32774)
		(width 0.127)
		(layer "F.Cu")
		(net "JTAG_EXP_TMS")
	)
	(segment
		(start 107.725718 -87.32774)
		(end 107.725718 -86.68258)
		(width 0.127)
		(layer "F.Cu")
		(net "JTAG_EXP_TMS")
	)
	(segment
		(start 108.49991 -81.848452)
		(end 108.49991 -81.500218)
		(width 0.127)
		(layer "F.Cu")
		(net "JTAG_EXP_TMS")
	)
	(segment
		(start 108.914184 -84.32419)
		(end 108.914184 -82.262726)
		(width 0.127)
		(layer "F.Cu")
		(net "JTAG_EXP_TMS")
	)
	(segment
		(start 107.725718 -86.68258)
		(end 108.077 -86.331298)
		(width 0.127)
		(layer "F.Cu")
		(net "JTAG_EXP_TMS")
	)
	(segment
		(start 108.077 -86.331298)
		(end 108.077 -85.161374)
		(width 0.127)
		(layer "F.Cu")
		(net "JTAG_EXP_TMS")
	)
	(segment
		(start 108.914184 -82.262726)
		(end 108.49991 -81.848452)
		(width 0.127)
		(layer "F.Cu")
		(net "JTAG_EXP_TMS")
	)
	(segment
		(start 108.49991 -82.500216)
		(end 108.49991 -83.709002)
		(width 0.127)
		(layer "F.Cu")
		(net "JTAG_EXP_TDO")
	)
	(segment
		(start 107.569 -84.639912)
		(end 107.569 -86.120732)
		(width 0.127)
		(layer "F.Cu")
		(net "JTAG_EXP_TDO")
	)
	(segment
		(start 107.569 -86.120732)
		(end 107.024678 -86.665054)
		(width 0.127)
		(layer "F.Cu")
		(net "JTAG_EXP_TDO")
	)
	(segment
		(start 108.49991 -83.709002)
		(end 107.569 -84.639912)
		(width 0.127)
		(layer "F.Cu")
		(net "JTAG_EXP_TDO")
	)
	(segment
		(start 109.499908 -76.500228)
		(end 109.000036 -76.000356)
		(width 0.127)
		(layer "F.Cu")
		(net "JTAG_EXP_TDI")
	)
	(via
		(at 109.000036 -76.000356)
		(size 0.4572)
		(drill 0.2032)
		(layers "F.Cu" "B.Cu")
		(net "JTAG_EXP_TDI")
	)
	(segment
		(start 109.499654 -76.499974)
		(end 109.000036 -76.000356)
		(width 0.127)
		(layer "B.Cu")
		(net "JTAG_EXP_TDI")
	)
	(segment
		(start 109.499908 -76.499974)
		(end 109.499654 -76.499974)
		(width 0.127)
		(layer "B.Cu")
		(net "JTAG_EXP_TDI")
	)
	(segment
		(start 109.499908 -75.50023)
		(end 109.000036 -75.000358)
		(width 0.127)
		(layer "F.Cu")
		(net "JTAG_EXP_TCK")
	)
	(via
		(at 109.000036 -75.000358)
		(size 0.4572)
		(drill 0.2032)
		(layers "F.Cu" "B.Cu")
		(net "JTAG_EXP_TCK")
	)
	(segment
		(start 109.000036 -74.99985)
		(end 109.499908 -74.499978)
		(width 0.127)
		(layer "B.Cu")
		(net "JTAG_EXP_TCK")
	)
	(segment
		(start 109.000036 -75.000358)
		(end 109.000036 -74.99985)
		(width 0.127)
		(layer "B.Cu")
		(net "JTAG_EXP_TCK")
	)
	(via
		(at 181.888384 -69.188584)
		(size 0.6096)
		(drill 0.3048)
		(layers "F.Cu" "B.Cu")
		(net "IOC_WP_N")
	)
	(segment
		(start 181.888384 -68.46697)
		(end 182.32755 -68.027804)
		(width 0.127)
		(layer "B.Cu")
		(net "IOC_WP_N")
	)
	(segment
		(start 181.888384 -69.188584)
		(end 181.888384 -68.46697)
		(width 0.127)
		(layer "B.Cu")
		(net "IOC_WP_N")
	)
	(segment
		(start 182.32755 -68.027804)
		(end 183.99252 -68.027804)
		(width 0.127)
		(layer "B.Cu")
		(net "IOC_WP_N")
	)
	(segment
		(start 181.888384 -70.245732)
		(end 181.888384 -69.188584)
		(width 0.127)
		(layer "B.Cu")
		(net "IOC_WP_N")
	)
	(segment
		(start 170.21429 -57.27827)
		(end 170.015662 -57.079642)
		(width 0.127)
		(layer "F.Cu")
		(net "IOC_VREF_SET")
	)
	(segment
		(start 170.21429 -61.368178)
		(end 170.21429 -57.27827)
		(width 0.127)
		(layer "F.Cu")
		(net "IOC_VREF_SET")
	)
	(segment
		(start 170.21429 -51.214274)
		(end 169.800016 -50.8)
		(width 0.127)
		(layer "F.Cu")
		(net "IOC_VREF_SET")
	)
	(segment
		(start 170.21429 -54.264814)
		(end 170.21429 -51.214274)
		(width 0.127)
		(layer "F.Cu")
		(net "IOC_VREF_SET")
	)
	(segment
		(start 170.015662 -57.079642)
		(end 170.015662 -54.463442)
		(width 0.127)
		(layer "F.Cu")
		(net "IOC_VREF_SET")
	)
	(segment
		(start 170.015662 -54.463442)
		(end 170.21429 -54.264814)
		(width 0.127)
		(layer "F.Cu")
		(net "IOC_VREF_SET")
	)
	(segment
		(start 175.17872 -66.332608)
		(end 170.21429 -61.368178)
		(width 0.127)
		(layer "F.Cu")
		(net "IOC_VREF_SET")
	)
	(segment
		(start 176.627282 -67.78117)
		(end 175.17872 -66.332608)
		(width 0.127)
		(layer "F.Cu")
		(net "IOC_VREF_SET")
	)
	(via
		(at 176.627282 -67.78117)
		(size 0.508)
		(drill 0.254)
		(layers "F.Cu" "B.Cu")
		(net "IOC_VREF_SET")
	)
	(via
		(at 175.17872 -66.332608)
		(size 0.6604)
		(drill 0.3302)
		(layers "F.Cu" "B.Cu")
		(net "IOC_VREF_SET")
	)
	(segment
		(start 173.728126 -70.737984)
		(end 172.776642 -69.7865)
		(width 0.127)
		(layer "B.Cu")
		(net "IOC_VREF_SET")
	)
	(segment
		(start 172.776642 -69.7865)
		(end 171.92625 -69.7865)
		(width 0.127)
		(layer "B.Cu")
		(net "IOC_VREF_SET")
	)
	(segment
		(start 176.627282 -69.585586)
		(end 175.474884 -70.737984)
		(width 0.127)
		(layer "B.Cu")
		(net "IOC_VREF_SET")
	)
	(segment
		(start 175.474884 -70.737984)
		(end 173.728126 -70.737984)
		(width 0.127)
		(layer "B.Cu")
		(net "IOC_VREF_SET")
	)
	(segment
		(start 176.627282 -67.78117)
		(end 176.627282 -69.585586)
		(width 0.127)
		(layer "B.Cu")
		(net "IOC_VREF_SET")
	)
	(segment
		(start 192.363598 -70.185026)
		(end 192.363598 -69.065902)
		(width 0.127)
		(layer "F.Cu")
		(net "IOC_UART_R_TX")
	)
	(segment
		(start 192.839848 -70.661276)
		(end 192.363598 -70.185026)
		(width 0.127)
		(layer "F.Cu")
		(net "IOC_UART_R_TX")
	)
	(segment
		(start 192.363598 -68.369434)
		(end 192.363598 -69.065902)
		(width 0.127)
		(layer "F.Cu")
		(net "IOC_UART_R_TX")
	)
	(segment
		(start 193.633598 -70.661276)
		(end 192.839848 -70.661276)
		(width 0.127)
		(layer "F.Cu")
		(net "IOC_UART_R_TX")
	)
	(segment
		(start 192.951354 -67.781678)
		(end 192.363598 -68.369434)
		(width 0.127)
		(layer "F.Cu")
		(net "IOC_UART_R_TX")
	)
	(via
		(at 192.363598 -69.065902)
		(size 0.6604)
		(drill 0.3302)
		(layers "F.Cu" "B.Cu")
		(net "IOC_UART_R_TX")
	)
	(segment
		(start 194.01536 -69.772022)
		(end 194.01536 -68.94322)
		(width 0.127)
		(layer "F.Cu")
		(net "IOC_UART_R_RX")
	)
	(segment
		(start 194.904614 -70.661276)
		(end 194.01536 -69.772022)
		(width 0.127)
		(layer "F.Cu")
		(net "IOC_UART_R_RX")
	)
	(segment
		(start 194.01536 -68.94322)
		(end 194.01536 -67.75704)
		(width 0.127)
		(layer "F.Cu")
		(net "IOC_UART_R_RX")
	)
	(segment
		(start 195.970398 -70.661276)
		(end 194.904614 -70.661276)
		(width 0.127)
		(layer "F.Cu")
		(net "IOC_UART_R_RX")
	)
	(via
		(at 194.01536 -68.94322)
		(size 0.6604)
		(drill 0.3302)
		(layers "F.Cu" "B.Cu")
		(net "IOC_UART_R_RX")
	)
	(segment
		(start 179.399946 -29.99994)
		(end 179.00015 -29.600144)
		(width 0.127)
		(layer "F.Cu")
		(net "IOC_UART_1_TX")
	)
	(via
		(at 179.00015 -29.600144)
		(size 0.508)
		(drill 0.254)
		(layers "F.Cu" "B.Cu")
		(net "IOC_UART_1_TX")
	)
	(segment
		(start 178.7144 -29.314394)
		(end 179.00015 -29.600144)
		(width 0.127)
		(layer "B.Cu")
		(net "IOC_UART_1_TX")
	)
	(segment
		(start 178.7144 -28.0924)
		(end 178.7144 -29.314394)
		(width 0.127)
		(layer "B.Cu")
		(net "IOC_UART_1_TX")
	)
	(segment
		(start 183.399938 -29.99994)
		(end 183.000142 -29.600144)
		(width 0.127)
		(layer "F.Cu")
		(net "IOC_UART_1_RX")
	)
	(via
		(at 183.000142 -29.600144)
		(size 0.508)
		(drill 0.254)
		(layers "F.Cu" "B.Cu")
		(net "IOC_UART_1_RX")
	)
	(segment
		(start 186.7027 -25.3111)
		(end 186.7027 -24.8666)
		(width 0.127)
		(layer "B.Cu")
		(net "IOC_UART_1_RX")
	)
	(segment
		(start 183.642 -29.1592)
		(end 183.201056 -29.600144)
		(width 0.127)
		(layer "B.Cu")
		(net "IOC_UART_1_RX")
	)
	(segment
		(start 185.2676 -28.3972)
		(end 185.2676 -28.9052)
		(width 0.127)
		(layer "B.Cu")
		(net "IOC_UART_1_RX")
	)
	(segment
		(start 185.2676 -28.3972)
		(end 185.1914 -28.321)
		(width 0.127)
		(layer "B.Cu")
		(net "IOC_UART_1_RX")
	)
	(segment
		(start 183.201056 -29.600144)
		(end 183.000142 -29.600144)
		(width 0.127)
		(layer "B.Cu")
		(net "IOC_UART_1_RX")
	)
	(segment
		(start 185.1914 -28.321)
		(end 185.1914 -26.8224)
		(width 0.127)
		(layer "B.Cu")
		(net "IOC_UART_1_RX")
	)
	(segment
		(start 185.0136 -29.1592)
		(end 183.642 -29.1592)
		(width 0.127)
		(layer "B.Cu")
		(net "IOC_UART_1_RX")
	)
	(segment
		(start 185.2676 -28.9052)
		(end 185.0136 -29.1592)
		(width 0.127)
		(layer "B.Cu")
		(net "IOC_UART_1_RX")
	)
	(segment
		(start 185.1914 -26.8224)
		(end 186.7027 -25.3111)
		(width 0.127)
		(layer "B.Cu")
		(net "IOC_UART_1_RX")
	)
	(segment
		(start 194.953128 -72.430386)
		(end 194.953128 -73.595484)
		(width 0.127)
		(layer "F.Cu")
		(net "IOC_UART_0_TX_R")
	)
	(segment
		(start 194.685158 -72.162416)
		(end 194.953128 -72.430386)
		(width 0.127)
		(layer "F.Cu")
		(net "IOC_UART_0_TX_R")
	)
	(segment
		(start 194.953128 -73.595484)
		(end 194.953128 -74.266044)
		(width 0.127)
		(layer "F.Cu")
		(net "IOC_UART_0_TX_R")
	)
	(segment
		(start 194.953128 -74.266044)
		(end 195.154804 -74.46772)
		(width 0.127)
		(layer "F.Cu")
		(net "IOC_UART_0_TX_R")
	)
	(segment
		(start 195.154804 -74.46772)
		(end 196.084444 -74.46772)
		(width 0.127)
		(layer "F.Cu")
		(net "IOC_UART_0_TX_R")
	)
	(segment
		(start 193.633598 -72.162416)
		(end 194.685158 -72.162416)
		(width 0.127)
		(layer "F.Cu")
		(net "IOC_UART_0_TX_R")
	)
	(via
		(at 194.953128 -73.595484)
		(size 0.6604)
		(drill 0.3302)
		(layers "F.Cu" "B.Cu")
		(net "IOC_UART_0_TX_R")
	)
	(segment
		(start 192.1383 -26.7335)
		(end 193.594482 -25.277318)
		(width 0.127)
		(layer "F.Cu")
		(net "IOC_UART_0_TX")
	)
	(segment
		(start 190.646558 -26.7335)
		(end 192.1383 -26.7335)
		(width 0.127)
		(layer "F.Cu")
		(net "IOC_UART_0_TX")
	)
	(segment
		(start 193.594482 -25.277318)
		(end 193.594482 -25.277064)
		(width 0.127)
		(layer "F.Cu")
		(net "IOC_UART_0_TX")
	)
	(segment
		(start 195.239386 -23.63216)
		(end 195.98894 -23.63216)
		(width 0.127)
		(layer "F.Cu")
		(net "IOC_UART_0_TX")
	)
	(segment
		(start 190.608458 -26.6954)
		(end 190.646558 -26.7335)
		(width 0.127)
		(layer "F.Cu")
		(net "IOC_UART_0_TX")
	)
	(segment
		(start 189.220602 -26.6954)
		(end 190.608458 -26.6954)
		(width 0.127)
		(layer "F.Cu")
		(net "IOC_UART_0_TX")
	)
	(segment
		(start 184.199784 -28.31973)
		(end 184.912 -27.607514)
		(width 0.127)
		(layer "F.Cu")
		(net "IOC_UART_0_TX")
	)
	(segment
		(start 185.42889 -26.58491)
		(end 189.110112 -26.58491)
		(width 0.127)
		(layer "F.Cu")
		(net "IOC_UART_0_TX")
	)
	(segment
		(start 184.912 -27.1018)
		(end 185.42889 -26.58491)
		(width 0.127)
		(layer "F.Cu")
		(net "IOC_UART_0_TX")
	)
	(segment
		(start 189.110112 -26.58491)
		(end 189.220602 -26.6954)
		(width 0.127)
		(layer "F.Cu")
		(net "IOC_UART_0_TX")
	)
	(segment
		(start 193.594482 -25.277064)
		(end 195.239386 -23.63216)
		(width 0.127)
		(layer "F.Cu")
		(net "IOC_UART_0_TX")
	)
	(segment
		(start 184.912 -27.607514)
		(end 184.912 -27.1018)
		(width 0.127)
		(layer "F.Cu")
		(net "IOC_UART_0_TX")
	)
	(segment
		(start 196.973444 -74.46772)
		(end 196.973444 -72.978264)
		(width 0.127)
		(layer "F.Cu")
		(net "IOC_UART_0_TX")
	)
	(segment
		(start 184.199784 -28.399994)
		(end 184.199784 -28.31973)
		(width 0.127)
		(layer "F.Cu")
		(net "IOC_UART_0_TX")
	)
	(via
		(at 196.973444 -72.978264)
		(size 0.508)
		(drill 0.254)
		(layers "F.Cu" "B.Cu")
		(net "IOC_UART_0_TX")
	)
	(via
		(at 195.98894 -23.63216)
		(size 0.508)
		(drill 0.254)
		(layers "F.Cu" "B.Cu")
		(net "IOC_UART_0_TX")
	)
	(segment
		(start 199.01027 -72.00773)
		(end 199.01027 -71.716392)
		(width 0.127)
		(layer "In5.Cu")
		(net "IOC_UART_0_TX")
	)
	(segment
		(start 200.445878 -62.404498)
		(end 200.81748 -62.032896)
		(width 0.127)
		(layer "In5.Cu")
		(net "IOC_UART_0_TX")
	)
	(segment
		(start 202.2729 -34.3027)
		(end 202.2729 -29.344112)
		(width 0.127)
		(layer "In5.Cu")
		(net "IOC_UART_0_TX")
	)
	(segment
		(start 199.01027 -71.716392)
		(end 200.445878 -70.280784)
		(width 0.127)
		(layer "In5.Cu")
		(net "IOC_UART_0_TX")
	)
	(segment
		(start 200.81748 -62.032896)
		(end 200.817734 -62.032896)
		(width 0.127)
		(layer "In5.Cu")
		(net "IOC_UART_0_TX")
	)
	(segment
		(start 196.973444 -72.978264)
		(end 198.039736 -72.978264)
		(width 0.127)
		(layer "In5.Cu")
		(net "IOC_UART_0_TX")
	)
	(segment
		(start 198.039736 -72.978264)
		(end 199.01027 -72.00773)
		(width 0.127)
		(layer "In5.Cu")
		(net "IOC_UART_0_TX")
	)
	(segment
		(start 200.817734 -62.032896)
		(end 201.311256 -61.539374)
		(width 0.127)
		(layer "In5.Cu")
		(net "IOC_UART_0_TX")
	)
	(segment
		(start 201.311256 -53.095144)
		(end 201.611992 -52.794408)
		(width 0.127)
		(layer "In5.Cu")
		(net "IOC_UART_0_TX")
	)
	(segment
		(start 201.311256 -61.539374)
		(end 201.311256 -53.095144)
		(width 0.127)
		(layer "In5.Cu")
		(net "IOC_UART_0_TX")
	)
	(segment
		(start 202.2729 -29.344112)
		(end 196.560948 -23.63216)
		(width 0.127)
		(layer "In5.Cu")
		(net "IOC_UART_0_TX")
	)
	(segment
		(start 196.560948 -23.63216)
		(end 195.98894 -23.63216)
		(width 0.127)
		(layer "In5.Cu")
		(net "IOC_UART_0_TX")
	)
	(segment
		(start 200.445878 -70.280784)
		(end 200.445878 -62.404498)
		(width 0.127)
		(layer "In5.Cu")
		(net "IOC_UART_0_TX")
	)
	(segment
		(start 201.611992 -34.963608)
		(end 202.2729 -34.3027)
		(width 0.127)
		(layer "In5.Cu")
		(net "IOC_UART_0_TX")
	)
	(segment
		(start 201.611992 -52.794408)
		(end 201.611992 -34.963608)
		(width 0.127)
		(layer "In5.Cu")
		(net "IOC_UART_0_TX")
	)
	(segment
		(start 198.09206 -72.87006)
		(end 198.09206 -73.406)
		(width 0.127)
		(layer "F.Cu")
		(net "IOC_UART_0_RX_R")
	)
	(segment
		(start 197.06336 -72.517)
		(end 197.739 -72.517)
		(width 0.127)
		(layer "F.Cu")
		(net "IOC_UART_0_RX_R")
	)
	(segment
		(start 197.739 -72.517)
		(end 198.09206 -72.87006)
		(width 0.127)
		(layer "F.Cu")
		(net "IOC_UART_0_RX_R")
	)
	(segment
		(start 196.708776 -72.162416)
		(end 197.06336 -72.517)
		(width 0.127)
		(layer "F.Cu")
		(net "IOC_UART_0_RX_R")
	)
	(segment
		(start 195.970398 -72.162416)
		(end 196.708776 -72.162416)
		(width 0.127)
		(layer "F.Cu")
		(net "IOC_UART_0_RX_R")
	)
	(segment
		(start 198.09206 -73.406)
		(end 198.09206 -74.46772)
		(width 0.127)
		(layer "F.Cu")
		(net "IOC_UART_0_RX_R")
	)
	(via
		(at 198.09206 -73.406)
		(size 0.6604)
		(drill 0.3302)
		(layers "F.Cu" "B.Cu")
		(net "IOC_UART_0_RX_R")
	)
	(segment
		(start 183.739282 -26.087578)
		(end 183.160924 -26.087578)
		(width 0.127)
		(layer "F.Cu")
		(net "IOC_UART_0_RX")
	)
	(segment
		(start 181.3433 -27.582368)
		(end 181.3433 -28.743148)
		(width 0.127)
		(layer "F.Cu")
		(net "IOC_UART_0_RX")
	)
	(segment
		(start 184.389522 -25.437338)
		(end 183.739282 -26.087578)
		(width 0.127)
		(layer "F.Cu")
		(net "IOC_UART_0_RX")
	)
	(segment
		(start 185.034174 -24.966422)
		(end 184.860438 -24.966422)
		(width 0.127)
		(layer "F.Cu")
		(net "IOC_UART_0_RX")
	)
	(segment
		(start 184.860438 -24.966422)
		(end 184.389522 -25.437338)
		(width 0.127)
		(layer "F.Cu")
		(net "IOC_UART_0_RX")
	)
	(segment
		(start 182.484776 -26.440892)
		(end 181.3433 -27.582368)
		(width 0.127)
		(layer "F.Cu")
		(net "IOC_UART_0_RX")
	)
	(segment
		(start 183.160924 -26.087578)
		(end 182.80761 -26.440892)
		(width 0.127)
		(layer "F.Cu")
		(net "IOC_UART_0_RX")
	)
	(segment
		(start 198.98106 -72.644)
		(end 198.98106 -74.46772)
		(width 0.127)
		(layer "F.Cu")
		(net "IOC_UART_0_RX")
	)
	(segment
		(start 181.3433 -28.743148)
		(end 181.799992 -29.19984)
		(width 0.127)
		(layer "F.Cu")
		(net "IOC_UART_0_RX")
	)
	(segment
		(start 182.80761 -26.440892)
		(end 182.484776 -26.440892)
		(width 0.127)
		(layer "F.Cu")
		(net "IOC_UART_0_RX")
	)
	(segment
		(start 198.98106 -72.643746)
		(end 199.645524 -71.979282)
		(width 0.127)
		(layer "F.Cu")
		(net "IOC_UART_0_RX")
	)
	(segment
		(start 198.98106 -72.644)
		(end 198.98106 -72.643746)
		(width 0.127)
		(layer "F.Cu")
		(net "IOC_UART_0_RX")
	)
	(via
		(at 193.4591 -22.843998)
		(size 0.508)
		(drill 0.254)
		(layers "F.Cu" "B.Cu")
		(net "IOC_UART_0_RX")
	)
	(via
		(at 199.645524 -71.979282)
		(size 0.508)
		(drill 0.254)
		(layers "F.Cu" "B.Cu")
		(net "IOC_UART_0_RX")
	)
	(via
		(at 184.389522 -25.437338)
		(size 0.508)
		(drill 0.254)
		(layers "F.Cu" "B.Cu")
		(net "IOC_UART_0_RX")
	)
	(via
		(at 198.98106 -72.644)
		(size 0.6604)
		(drill 0.3302)
		(layers "F.Cu" "B.Cu")
		(net "IOC_UART_0_RX")
	)
	(segment
		(start 193.4591 -22.843998)
		(end 193.22161 -22.606508)
		(width 0.127)
		(layer "B.Cu")
		(net "IOC_UART_0_RX")
	)
	(segment
		(start 191.617854 -22.606508)
		(end 190.068962 -24.1554)
		(width 0.127)
		(layer "B.Cu")
		(net "IOC_UART_0_RX")
	)
	(segment
		(start 184.683654 -24.539448)
		(end 184.683654 -25.143206)
		(width 0.127)
		(layer "B.Cu")
		(net "IOC_UART_0_RX")
	)
	(segment
		(start 185.067702 -24.1554)
		(end 184.683654 -24.539448)
		(width 0.127)
		(layer "B.Cu")
		(net "IOC_UART_0_RX")
	)
	(segment
		(start 190.068962 -24.1554)
		(end 185.067702 -24.1554)
		(width 0.127)
		(layer "B.Cu")
		(net "IOC_UART_0_RX")
	)
	(segment
		(start 184.683654 -25.143206)
		(end 184.389522 -25.437338)
		(width 0.127)
		(layer "B.Cu")
		(net "IOC_UART_0_RX")
	)
	(segment
		(start 193.22161 -22.606508)
		(end 191.617854 -22.606508)
		(width 0.127)
		(layer "B.Cu")
		(net "IOC_UART_0_RX")
	)
	(segment
		(start 202.246992 -53.073808)
		(end 201.946256 -53.374544)
		(width 0.127)
		(layer "In5.Cu")
		(net "IOC_UART_0_RX")
	)
	(segment
		(start 196.783198 -22.955758)
		(end 202.9079 -29.08046)
		(width 0.127)
		(layer "In5.Cu")
		(net "IOC_UART_0_RX")
	)
	(segment
		(start 193.4591 -22.843998)
		(end 193.57086 -22.955758)
		(width 0.127)
		(layer "In5.Cu")
		(net "IOC_UART_0_RX")
	)
	(segment
		(start 201.946256 -53.374544)
		(end 201.946256 -61.802518)
		(width 0.127)
		(layer "In5.Cu")
		(net "IOC_UART_0_RX")
	)
	(segment
		(start 202.9079 -29.08046)
		(end 202.9079 -34.565844)
		(width 0.127)
		(layer "In5.Cu")
		(net "IOC_UART_0_RX")
	)
	(segment
		(start 201.946256 -61.802518)
		(end 201.080878 -62.667896)
		(width 0.127)
		(layer "In5.Cu")
		(net "IOC_UART_0_RX")
	)
	(segment
		(start 202.246992 -35.226752)
		(end 202.246992 -53.073808)
		(width 0.127)
		(layer "In5.Cu")
		(net "IOC_UART_0_RX")
	)
	(segment
		(start 201.080878 -70.543928)
		(end 199.645524 -71.979282)
		(width 0.127)
		(layer "In5.Cu")
		(net "IOC_UART_0_RX")
	)
	(segment
		(start 193.57086 -22.955758)
		(end 196.783198 -22.955758)
		(width 0.127)
		(layer "In5.Cu")
		(net "IOC_UART_0_RX")
	)
	(segment
		(start 201.080878 -62.667896)
		(end 201.080878 -70.543928)
		(width 0.127)
		(layer "In5.Cu")
		(net "IOC_UART_0_RX")
	)
	(segment
		(start 202.9079 -34.565844)
		(end 202.246992 -35.226752)
		(width 0.127)
		(layer "In5.Cu")
		(net "IOC_UART_0_RX")
	)
	(segment
		(start 174.80915 -54.896004)
		(end 174.80915 -53.480716)
		(width 0.127)
		(layer "F.Cu")
		(net "IOC_TRST_N")
	)
	(segment
		(start 173.4058 -59.3725)
		(end 173.4058 -56.7182)
		(width 0.127)
		(layer "F.Cu")
		(net "IOC_TRST_N")
	)
	(segment
		(start 173.4058 -56.299354)
		(end 174.80915 -54.896004)
		(width 0.127)
		(layer "F.Cu")
		(net "IOC_TRST_N")
	)
	(segment
		(start 175.399954 -52.889912)
		(end 175.399954 -51.599846)
		(width 0.127)
		(layer "F.Cu")
		(net "IOC_TRST_N")
	)
	(segment
		(start 174.80915 -53.480716)
		(end 175.399954 -52.889912)
		(width 0.127)
		(layer "F.Cu")
		(net "IOC_TRST_N")
	)
	(segment
		(start 173.4058 -56.7182)
		(end 173.4058 -56.299354)
		(width 0.127)
		(layer "F.Cu")
		(net "IOC_TRST_N")
	)
	(segment
		(start 176.9999 -49.9999)
		(end 176.59985 -50.39995)
		(width 0.127)
		(layer "F.Cu")
		(net "IOC_TDO")
	)
	(via
		(at 176.59985 -50.39995)
		(size 0.508)
		(drill 0.254)
		(layers "F.Cu" "B.Cu")
		(net "IOC_TDO")
	)
	(segment
		(start 176.298098 -50.701702)
		(end 176.59985 -50.39995)
		(width 0.127)
		(layer "B.Cu")
		(net "IOC_TDO")
	)
	(segment
		(start 176.298098 -51.237896)
		(end 176.298098 -50.701702)
		(width 0.127)
		(layer "B.Cu")
		(net "IOC_TDO")
	)
	(segment
		(start 166.59987 -40.39997)
		(end 166.19982 -39.99992)
		(width 0.127)
		(layer "F.Cu")
		(net "IOC_SIO_BLINK")
	)
	(via
		(at 166.19982 -39.99992)
		(size 0.508)
		(drill 0.254)
		(layers "F.Cu" "B.Cu")
		(net "IOC_SIO_BLINK")
	)
	(segment
		(start 165.337744 -41.454832)
		(end 164.628576 -42.164)
		(width 0.127)
		(layer "B.Cu")
		(net "IOC_SIO_BLINK")
	)
	(segment
		(start 166.19982 -39.99992)
		(end 165.337744 -40.861996)
		(width 0.127)
		(layer "B.Cu")
		(net "IOC_SIO_BLINK")
	)
	(segment
		(start 165.337744 -40.861996)
		(end 165.337744 -41.454832)
		(width 0.127)
		(layer "B.Cu")
		(net "IOC_SIO_BLINK")
	)
	(segment
		(start 164.628576 -42.164)
		(end 163.8935 -42.164)
		(width 0.127)
		(layer "B.Cu")
		(net "IOC_SIO_BLINK")
	)
	(segment
		(start 159.0675 -42.291)
		(end 159.0675 -42.706036)
		(width 0.127)
		(layer "F.Cu")
		(net "IOC_REF_CLK_P")
	)
	(segment
		(start 159.375856 -43.014392)
		(end 159.375856 -44.054522)
		(width 0.127)
		(layer "F.Cu")
		(net "IOC_REF_CLK_P")
	)
	(segment
		(start 159.83585 -41.364916)
		(end 159.0675 -42.133266)
		(width 0.127)
		(layer "F.Cu")
		(net "IOC_REF_CLK_P")
	)
	(segment
		(start 163.234878 -41.364916)
		(end 159.83585 -41.364916)
		(width 0.127)
		(layer "F.Cu")
		(net "IOC_REF_CLK_P")
	)
	(segment
		(start 159.0675 -42.133266)
		(end 159.0675 -42.291)
		(width 0.127)
		(layer "F.Cu")
		(net "IOC_REF_CLK_P")
	)
	(segment
		(start 159.0675 -42.706036)
		(end 159.375856 -43.014392)
		(width 0.127)
		(layer "F.Cu")
		(net "IOC_REF_CLK_P")
	)
	(segment
		(start 163.399978 -41.199816)
		(end 163.234878 -41.364916)
		(width 0.127)
		(layer "F.Cu")
		(net "IOC_REF_CLK_P")
	)
	(segment
		(start 159.2072 -41.275)
		(end 159.625284 -40.856916)
		(width 0.127)
		(layer "F.Cu")
		(net "IOC_REF_CLK_N")
	)
	(segment
		(start 159.625284 -40.856916)
		(end 163.8681 -40.856916)
		(width 0.127)
		(layer "F.Cu")
		(net "IOC_REF_CLK_N")
	)
	(segment
		(start 163.8681 -40.856916)
		(end 164.199824 -41.18864)
		(width 0.127)
		(layer "F.Cu")
		(net "IOC_REF_CLK_N")
	)
	(segment
		(start 164.199824 -41.18864)
		(end 164.199824 -41.199816)
		(width 0.127)
		(layer "F.Cu")
		(net "IOC_REF_CLK_N")
	)
	(segment
		(start 158.9405 -41.275)
		(end 159.2072 -41.275)
		(width 0.127)
		(layer "F.Cu")
		(net "IOC_REF_CLK_N")
	)
	(segment
		(start 185.799984 -28.399994)
		(end 186.028584 -28.399994)
		(width 0.127)
		(layer "F.Cu")
		(net "IOC_GPIO_9")
	)
	(segment
		(start 186.028584 -28.399994)
		(end 186.489848 -27.93873)
		(width 0.127)
		(layer "F.Cu")
		(net "IOC_GPIO_9")
	)
	(via
		(at 186.489848 -27.93873)
		(size 0.508)
		(drill 0.254)
		(layers "F.Cu" "B.Cu")
		(net "IOC_GPIO_9")
	)
	(segment
		(start 186.952128 -27.47645)
		(end 188.32449 -27.47645)
		(width 0.127)
		(layer "B.Cu")
		(net "IOC_GPIO_9")
	)
	(segment
		(start 188.32449 -27.47645)
		(end 188.45784 -27.6098)
		(width 0.127)
		(layer "B.Cu")
		(net "IOC_GPIO_9")
	)
	(segment
		(start 188.45784 -27.6098)
		(end 189.4078 -27.6098)
		(width 0.127)
		(layer "B.Cu")
		(net "IOC_GPIO_9")
	)
	(segment
		(start 186.489848 -27.93873)
		(end 186.952128 -27.47645)
		(width 0.127)
		(layer "B.Cu")
		(net "IOC_GPIO_9")
	)
	(segment
		(start 190.9445 -31.496)
		(end 189.723268 -31.496)
		(width 0.127)
		(layer "F.Cu")
		(net "IOC_GPIO_8")
	)
	(segment
		(start 191.516 -32.0675)
		(end 190.9445 -31.496)
		(width 0.127)
		(layer "F.Cu")
		(net "IOC_GPIO_8")
	)
	(segment
		(start 187.455302 -33.999932)
		(end 186.59983 -33.999932)
		(width 0.127)
		(layer "F.Cu")
		(net "IOC_GPIO_8")
	)
	(segment
		(start 189.723268 -31.496)
		(end 188.975746 -32.243522)
		(width 0.127)
		(layer "F.Cu")
		(net "IOC_GPIO_8")
	)
	(segment
		(start 188.975746 -32.479488)
		(end 187.455302 -33.999932)
		(width 0.127)
		(layer "F.Cu")
		(net "IOC_GPIO_8")
	)
	(segment
		(start 188.975746 -32.243522)
		(end 188.975746 -32.479488)
		(width 0.127)
		(layer "F.Cu")
		(net "IOC_GPIO_8")
	)
	(segment
		(start 179.399946 -32.399986)
		(end 179.799742 -32.799782)
		(width 0.127)
		(layer "F.Cu")
		(net "IOC_GPIO_7")
	)
	(via
		(at 179.799742 -32.799782)
		(size 0.508)
		(drill 0.254)
		(layers "F.Cu" "B.Cu")
		(net "IOC_GPIO_7")
	)
	(segment
		(start 179.799742 -32.799782)
		(end 179.126642 -32.126682)
		(width 0.127)
		(layer "B.Cu")
		(net "IOC_GPIO_7")
	)
	(segment
		(start 179.126642 -32.126682)
		(end 176.993296 -32.126682)
		(width 0.127)
		(layer "B.Cu")
		(net "IOC_GPIO_7")
	)
	(segment
		(start 176.993296 -32.126682)
		(end 176.72558 -31.858966)
		(width 0.127)
		(layer "B.Cu")
		(net "IOC_GPIO_7")
	)
	(segment
		(start 182.599838 -29.99994)
		(end 182.199788 -29.59989)
		(width 0.127)
		(layer "F.Cu")
		(net "IOC_GPIO_6")
	)
	(via
		(at 182.199788 -29.59989)
		(size 0.508)
		(drill 0.254)
		(layers "F.Cu" "B.Cu")
		(net "IOC_GPIO_6")
	)
	(segment
		(start 182.40756 -29.59989)
		(end 182.199788 -29.59989)
		(width 0.127)
		(layer "B.Cu")
		(net "IOC_GPIO_6")
	)
	(segment
		(start 182.826406 -29.181044)
		(end 182.40756 -29.59989)
		(width 0.127)
		(layer "B.Cu")
		(net "IOC_GPIO_6")
	)
	(segment
		(start 183.112156 -29.181044)
		(end 182.826406 -29.181044)
		(width 0.127)
		(layer "B.Cu")
		(net "IOC_GPIO_6")
	)
	(segment
		(start 183.9468 -28.3464)
		(end 183.112156 -29.181044)
		(width 0.127)
		(layer "B.Cu")
		(net "IOC_GPIO_6")
	)
	(segment
		(start 183.9468 -28.1178)
		(end 183.9468 -28.3464)
		(width 0.127)
		(layer "B.Cu")
		(net "IOC_GPIO_6")
	)
	(segment
		(start 181.799992 -29.99994)
		(end 181.399942 -29.59989)
		(width 0.127)
		(layer "F.Cu")
		(net "IOC_GPIO_5")
	)
	(via
		(at 181.399942 -29.59989)
		(size 0.508)
		(drill 0.254)
		(layers "F.Cu" "B.Cu")
		(net "IOC_GPIO_5")
	)
	(segment
		(start 182.0926 -29.1592)
		(end 181.840632 -29.1592)
		(width 0.127)
		(layer "B.Cu")
		(net "IOC_GPIO_5")
	)
	(segment
		(start 182.626 -28.6258)
		(end 182.0926 -29.1592)
		(width 0.127)
		(layer "B.Cu")
		(net "IOC_GPIO_5")
	)
	(segment
		(start 181.840632 -29.1592)
		(end 181.399942 -29.59989)
		(width 0.127)
		(layer "B.Cu")
		(net "IOC_GPIO_5")
	)
	(segment
		(start 188.46927 -27.3304)
		(end 186.59983 -29.19984)
		(width 0.127)
		(layer "F.Cu")
		(net "IOC_GPIO_4")
	)
	(segment
		(start 190.345314 -27.3304)
		(end 188.46927 -27.3304)
		(width 0.127)
		(layer "F.Cu")
		(net "IOC_GPIO_4")
	)
	(segment
		(start 191.516 -27.8384)
		(end 190.853314 -27.8384)
		(width 0.127)
		(layer "F.Cu")
		(net "IOC_GPIO_4")
	)
	(segment
		(start 190.853314 -27.8384)
		(end 190.345314 -27.3304)
		(width 0.127)
		(layer "F.Cu")
		(net "IOC_GPIO_4")
	)
	(segment
		(start 187.20308 -31.98241)
		(end 189.21349 -29.972)
		(width 0.127)
		(layer "F.Cu")
		(net "IOC_GPIO_39")
	)
	(segment
		(start 186.21756 -31.98241)
		(end 187.20308 -31.98241)
		(width 0.127)
		(layer "F.Cu")
		(net "IOC_GPIO_39")
	)
	(segment
		(start 193.918332 -31.9532)
		(end 194.5132 -31.9532)
		(width 0.127)
		(layer "F.Cu")
		(net "IOC_GPIO_39")
	)
	(segment
		(start 191.937132 -29.972)
		(end 193.918332 -31.9532)
		(width 0.127)
		(layer "F.Cu")
		(net "IOC_GPIO_39")
	)
	(segment
		(start 189.21349 -29.972)
		(end 191.937132 -29.972)
		(width 0.127)
		(layer "F.Cu")
		(net "IOC_GPIO_39")
	)
	(segment
		(start 185.799984 -32.399986)
		(end 186.21756 -31.98241)
		(width 0.127)
		(layer "F.Cu")
		(net "IOC_GPIO_39")
	)
	(segment
		(start 185.000138 -37.199824)
		(end 184.999884 -37.199824)
		(width 0.127)
		(layer "F.Cu")
		(net "IOC_GPIO_38")
	)
	(segment
		(start 185.399934 -36.800028)
		(end 185.000138 -37.199824)
		(width 0.127)
		(layer "F.Cu")
		(net "IOC_GPIO_38")
	)
	(via
		(at 185.399934 -36.800028)
		(size 0.508)
		(drill 0.254)
		(layers "F.Cu" "B.Cu")
		(net "IOC_GPIO_38")
	)
	(segment
		(start 185.399934 -36.800028)
		(end 186.025028 -36.800028)
		(width 0.127)
		(layer "B.Cu")
		(net "IOC_GPIO_38")
	)
	(segment
		(start 186.025028 -36.800028)
		(end 186.309 -37.084)
		(width 0.127)
		(layer "B.Cu")
		(net "IOC_GPIO_38")
	)
	(segment
		(start 188.9887 -34.2265)
		(end 188.9887 -33.867598)
		(width 0.127)
		(layer "F.Cu")
		(net "IOC_GPIO_37")
	)
	(segment
		(start 188.5442 -34.671)
		(end 188.9887 -34.2265)
		(width 0.127)
		(layer "F.Cu")
		(net "IOC_GPIO_37")
	)
	(segment
		(start 188.107066 -35.5092)
		(end 188.5442 -35.072066)
		(width 0.127)
		(layer "F.Cu")
		(net "IOC_GPIO_37")
	)
	(segment
		(start 192.913 -33.0962)
		(end 193.0654 -33.2486)
		(width 0.127)
		(layer "F.Cu")
		(net "IOC_GPIO_37")
	)
	(segment
		(start 192.5828 -33.0962)
		(end 192.913 -33.0962)
		(width 0.127)
		(layer "F.Cu")
		(net "IOC_GPIO_37")
	)
	(segment
		(start 189.4205 -33.435798)
		(end 189.4205 -33.2359)
		(width 0.127)
		(layer "F.Cu")
		(net "IOC_GPIO_37")
	)
	(segment
		(start 188.9887 -33.867598)
		(end 189.4205 -33.435798)
		(width 0.127)
		(layer "F.Cu")
		(net "IOC_GPIO_37")
	)
	(segment
		(start 188.5442 -35.072066)
		(end 188.5442 -34.671)
		(width 0.127)
		(layer "F.Cu")
		(net "IOC_GPIO_37")
	)
	(segment
		(start 188.080142 -35.5092)
		(end 188.107066 -35.5092)
		(width 0.127)
		(layer "F.Cu")
		(net "IOC_GPIO_37")
	)
	(segment
		(start 189.4205 -33.2359)
		(end 189.9158 -32.7406)
		(width 0.127)
		(layer "F.Cu")
		(net "IOC_GPIO_37")
	)
	(segment
		(start 189.9158 -32.7406)
		(end 192.2272 -32.7406)
		(width 0.127)
		(layer "F.Cu")
		(net "IOC_GPIO_37")
	)
	(segment
		(start 187.989464 -35.599878)
		(end 188.080142 -35.5092)
		(width 0.127)
		(layer "F.Cu")
		(net "IOC_GPIO_37")
	)
	(segment
		(start 186.59983 -35.599878)
		(end 187.989464 -35.599878)
		(width 0.127)
		(layer "F.Cu")
		(net "IOC_GPIO_37")
	)
	(segment
		(start 192.2272 -32.7406)
		(end 192.5828 -33.0962)
		(width 0.127)
		(layer "F.Cu")
		(net "IOC_GPIO_37")
	)
	(segment
		(start 184.999884 -35.599878)
		(end 185.399934 -35.199828)
		(width 0.127)
		(layer "F.Cu")
		(net "IOC_GPIO_36")
	)
	(via
		(at 185.399934 -35.199828)
		(size 0.508)
		(drill 0.254)
		(layers "F.Cu" "B.Cu")
		(net "IOC_GPIO_36")
	)
	(segment
		(start 185.399934 -35.199828)
		(end 186.406028 -35.199828)
		(width 0.127)
		(layer "B.Cu")
		(net "IOC_GPIO_36")
	)
	(segment
		(start 186.406028 -35.199828)
		(end 186.563 -35.3568)
		(width 0.127)
		(layer "B.Cu")
		(net "IOC_GPIO_36")
	)
	(segment
		(start 187.863988 -34.800032)
		(end 186.59983 -34.800032)
		(width 0.127)
		(layer "F.Cu")
		(net "IOC_GPIO_35")
	)
	(via
		(at 187.863988 -34.800032)
		(size 0.508)
		(drill 0.254)
		(layers "F.Cu" "B.Cu")
		(net "IOC_GPIO_35")
	)
	(segment
		(start 187.863988 -34.800032)
		(end 188.292232 -34.800032)
		(width 0.127)
		(layer "B.Cu")
		(net "IOC_GPIO_35")
	)
	(segment
		(start 188.292232 -34.800032)
		(end 188.8236 -35.3314)
		(width 0.127)
		(layer "B.Cu")
		(net "IOC_GPIO_35")
	)
	(segment
		(start 184.999884 -34.800032)
		(end 185.399934 -34.399982)
		(width 0.127)
		(layer "F.Cu")
		(net "IOC_GPIO_34")
	)
	(via
		(at 185.399934 -34.399982)
		(size 0.508)
		(drill 0.254)
		(layers "F.Cu" "B.Cu")
		(net "IOC_GPIO_34")
	)
	(segment
		(start 187.062618 -34.399982)
		(end 187.452 -34.0106)
		(width 0.127)
		(layer "B.Cu")
		(net "IOC_GPIO_34")
	)
	(segment
		(start 185.399934 -34.399982)
		(end 187.062618 -34.399982)
		(width 0.127)
		(layer "B.Cu")
		(net "IOC_GPIO_34")
	)
	(segment
		(start 186.11469 -35.599878)
		(end 185.799984 -35.599878)
		(width 0.127)
		(layer "F.Cu")
		(net "IOC_GPIO_33")
	)
	(segment
		(start 188.283088 -34.973768)
		(end 188.001656 -35.2552)
		(width 0.127)
		(layer "F.Cu")
		(net "IOC_GPIO_33")
	)
	(segment
		(start 188.283088 -34.315146)
		(end 188.283088 -34.973768)
		(width 0.127)
		(layer "F.Cu")
		(net "IOC_GPIO_33")
	)
	(segment
		(start 186.459368 -35.2552)
		(end 186.11469 -35.599878)
		(width 0.127)
		(layer "F.Cu")
		(net "IOC_GPIO_33")
	)
	(segment
		(start 188.405516 -34.192718)
		(end 188.283088 -34.315146)
		(width 0.127)
		(layer "F.Cu")
		(net "IOC_GPIO_33")
	)
	(segment
		(start 188.001656 -35.2552)
		(end 186.459368 -35.2552)
		(width 0.127)
		(layer "F.Cu")
		(net "IOC_GPIO_33")
	)
	(via
		(at 188.405516 -34.192718)
		(size 0.508)
		(drill 0.254)
		(layers "F.Cu" "B.Cu")
		(net "IOC_GPIO_33")
	)
	(segment
		(start 189.581282 -34.192718)
		(end 189.5856 -34.1884)
		(width 0.127)
		(layer "B.Cu")
		(net "IOC_GPIO_33")
	)
	(segment
		(start 188.405516 -34.192718)
		(end 189.581282 -34.192718)
		(width 0.127)
		(layer "B.Cu")
		(net "IOC_GPIO_33")
	)
	(segment
		(start 184.999884 -41.999916)
		(end 184.599834 -41.599866)
		(width 0.127)
		(layer "F.Cu")
		(net "IOC_GPIO_32")
	)
	(via
		(at 184.599834 -41.599866)
		(size 0.508)
		(drill 0.254)
		(layers "F.Cu" "B.Cu")
		(net "IOC_GPIO_32")
	)
	(segment
		(start 185.90768 -42.09923)
		(end 186.02579 -41.98112)
		(width 0.127)
		(layer "B.Cu")
		(net "IOC_GPIO_32")
	)
	(segment
		(start 186.02579 -41.98112)
		(end 186.813952 -41.98112)
		(width 0.127)
		(layer "B.Cu")
		(net "IOC_GPIO_32")
	)
	(segment
		(start 186.813952 -41.98112)
		(end 187.12942 -42.296588)
		(width 0.127)
		(layer "B.Cu")
		(net "IOC_GPIO_32")
	)
	(segment
		(start 184.599834 -41.599866)
		(end 185.099198 -42.09923)
		(width 0.127)
		(layer "B.Cu")
		(net "IOC_GPIO_32")
	)
	(segment
		(start 185.099198 -42.09923)
		(end 185.90768 -42.09923)
		(width 0.127)
		(layer "B.Cu")
		(net "IOC_GPIO_32")
	)
	(segment
		(start 187.551822 -32.23641)
		(end 186.763406 -32.23641)
		(width 0.127)
		(layer "F.Cu")
		(net "IOC_GPIO_31")
	)
	(segment
		(start 191.643 -30.48)
		(end 189.308232 -30.48)
		(width 0.127)
		(layer "F.Cu")
		(net "IOC_GPIO_31")
	)
	(segment
		(start 193.167 -32.004)
		(end 191.643 -30.48)
		(width 0.127)
		(layer "F.Cu")
		(net "IOC_GPIO_31")
	)
	(segment
		(start 189.308232 -30.48)
		(end 187.551822 -32.23641)
		(width 0.127)
		(layer "F.Cu")
		(net "IOC_GPIO_31")
	)
	(segment
		(start 186.763406 -32.23641)
		(end 186.59983 -32.399986)
		(width 0.127)
		(layer "F.Cu")
		(net "IOC_GPIO_31")
	)
	(segment
		(start 187.403232 -33.602422)
		(end 186.479942 -33.602422)
		(width 0.127)
		(layer "F.Cu")
		(net "IOC_GPIO_30")
	)
	(segment
		(start 192.872614 -32.5882)
		(end 191.272414 -30.988)
		(width 0.127)
		(layer "F.Cu")
		(net "IOC_GPIO_30")
	)
	(segment
		(start 191.272414 -30.988)
		(end 189.512702 -30.988)
		(width 0.127)
		(layer "F.Cu")
		(net "IOC_GPIO_30")
	)
	(segment
		(start 194.2846 -33.2232)
		(end 193.6496 -32.5882)
		(width 0.127)
		(layer "F.Cu")
		(net "IOC_GPIO_30")
	)
	(segment
		(start 186.479942 -33.602422)
		(end 186.082432 -33.999932)
		(width 0.127)
		(layer "F.Cu")
		(net "IOC_GPIO_30")
	)
	(segment
		(start 186.082432 -33.999932)
		(end 185.799984 -33.999932)
		(width 0.127)
		(layer "F.Cu")
		(net "IOC_GPIO_30")
	)
	(segment
		(start 193.6496 -32.5882)
		(end 192.872614 -32.5882)
		(width 0.127)
		(layer "F.Cu")
		(net "IOC_GPIO_30")
	)
	(segment
		(start 188.721492 -32.284162)
		(end 187.403232 -33.602422)
		(width 0.127)
		(layer "F.Cu")
		(net "IOC_GPIO_30")
	)
	(segment
		(start 188.721492 -31.77921)
		(end 188.721492 -32.284162)
		(width 0.127)
		(layer "F.Cu")
		(net "IOC_GPIO_30")
	)
	(segment
		(start 189.512702 -30.988)
		(end 188.721492 -31.77921)
		(width 0.127)
		(layer "F.Cu")
		(net "IOC_GPIO_30")
	)
	(segment
		(start 180.999892 -29.99994)
		(end 180.599842 -29.59989)
		(width 0.127)
		(layer "F.Cu")
		(net "IOC_GPIO_3")
	)
	(via
		(at 180.599842 -29.59989)
		(size 0.508)
		(drill 0.254)
		(layers "F.Cu" "B.Cu")
		(net "IOC_GPIO_3")
	)
	(segment
		(start 181.9148 -28.2194)
		(end 181.9148 -28.725622)
		(width 0.127)
		(layer "B.Cu")
		(net "IOC_GPIO_3")
	)
	(segment
		(start 181.018942 -29.18079)
		(end 180.599842 -29.59989)
		(width 0.127)
		(layer "B.Cu")
		(net "IOC_GPIO_3")
	)
	(segment
		(start 181.459632 -29.18079)
		(end 181.018942 -29.18079)
		(width 0.127)
		(layer "B.Cu")
		(net "IOC_GPIO_3")
	)
	(segment
		(start 181.9148 -28.725622)
		(end 181.459632 -29.18079)
		(width 0.127)
		(layer "B.Cu")
		(net "IOC_GPIO_3")
	)
	(segment
		(start 181.6354 -27.2542)
		(end 181.6354 -27.94)
		(width 0.127)
		(layer "B.Cu")
		(net "IOC_GPIO_3")
	)
	(segment
		(start 181.6354 -27.94)
		(end 181.9148 -28.2194)
		(width 0.127)
		(layer "B.Cu")
		(net "IOC_GPIO_3")
	)
	(segment
		(start 185.399934 -32.800036)
		(end 185.000138 -33.199832)
		(width 0.127)
		(layer "F.Cu")
		(net "IOC_GPIO_29")
	)
	(segment
		(start 185.000138 -33.199832)
		(end 184.999884 -33.199832)
		(width 0.127)
		(layer "F.Cu")
		(net "IOC_GPIO_29")
	)
	(via
		(at 185.399934 -32.800036)
		(size 0.508)
		(drill 0.254)
		(layers "F.Cu" "B.Cu")
		(net "IOC_GPIO_29")
	)
	(segment
		(start 185.399934 -32.800036)
		(end 185.679588 -33.07969)
		(width 0.127)
		(layer "B.Cu")
		(net "IOC_GPIO_29")
	)
	(segment
		(start 185.679588 -33.07969)
		(end 186.276488 -33.07969)
		(width 0.127)
		(layer "B.Cu")
		(net "IOC_GPIO_29")
	)
	(segment
		(start 184.999884 -33.999932)
		(end 185.399934 -33.599882)
		(width 0.127)
		(layer "F.Cu")
		(net "IOC_GPIO_28")
	)
	(via
		(at 185.399934 -33.599882)
		(size 0.508)
		(drill 0.254)
		(layers "F.Cu" "B.Cu")
		(net "IOC_GPIO_28")
	)
	(segment
		(start 188.6458 -33.1724)
		(end 187.275978 -33.1724)
		(width 0.127)
		(layer "B.Cu")
		(net "IOC_GPIO_28")
	)
	(segment
		(start 185.47969 -33.679638)
		(end 185.399934 -33.599882)
		(width 0.127)
		(layer "B.Cu")
		(net "IOC_GPIO_28")
	)
	(segment
		(start 187.275978 -33.1724)
		(end 186.76874 -33.679638)
		(width 0.127)
		(layer "B.Cu")
		(net "IOC_GPIO_28")
	)
	(segment
		(start 186.76874 -33.679638)
		(end 185.47969 -33.679638)
		(width 0.127)
		(layer "B.Cu")
		(net "IOC_GPIO_28")
	)
	(segment
		(start 187.189618 -32.8422)
		(end 186.157616 -32.8422)
		(width 0.127)
		(layer "F.Cu")
		(net "IOC_GPIO_27")
	)
	(segment
		(start 186.157616 -32.8422)
		(end 185.799984 -33.199832)
		(width 0.127)
		(layer "F.Cu")
		(net "IOC_GPIO_27")
	)
	(segment
		(start 187.376308 -32.65551)
		(end 187.189618 -32.8422)
		(width 0.127)
		(layer "F.Cu")
		(net "IOC_GPIO_27")
	)
	(via
		(at 187.376308 -32.65551)
		(size 0.508)
		(drill 0.254)
		(layers "F.Cu" "B.Cu")
		(net "IOC_GPIO_27")
	)
	(segment
		(start 187.376308 -32.029908)
		(end 187.1472 -31.8008)
		(width 0.127)
		(layer "B.Cu")
		(net "IOC_GPIO_27")
	)
	(segment
		(start 187.376308 -32.65551)
		(end 187.376308 -32.029908)
		(width 0.127)
		(layer "B.Cu")
		(net "IOC_GPIO_27")
	)
	(segment
		(start 184.999884 -31.599886)
		(end 185.399934 -31.199836)
		(width 0.127)
		(layer "F.Cu")
		(net "IOC_GPIO_26")
	)
	(via
		(at 185.399934 -31.199836)
		(size 0.508)
		(drill 0.254)
		(layers "F.Cu" "B.Cu")
		(net "IOC_GPIO_26")
	)
	(segment
		(start 185.99277 -30.607)
		(end 185.399934 -31.199836)
		(width 0.127)
		(layer "B.Cu")
		(net "IOC_GPIO_26")
	)
	(segment
		(start 186.3344 -30.607)
		(end 185.99277 -30.607)
		(width 0.127)
		(layer "B.Cu")
		(net "IOC_GPIO_26")
	)
	(segment
		(start 184.999884 -30.80004)
		(end 184.599834 -31.20009)
		(width 0.127)
		(layer "F.Cu")
		(net "IOC_GPIO_25")
	)
	(via
		(at 184.599834 -31.20009)
		(size 0.508)
		(drill 0.254)
		(layers "F.Cu" "B.Cu")
		(net "IOC_GPIO_25")
	)
	(segment
		(start 185.929524 -29.8704)
		(end 184.599834 -31.20009)
		(width 0.127)
		(layer "B.Cu")
		(net "IOC_GPIO_25")
	)
	(segment
		(start 187.5028 -29.8704)
		(end 185.929524 -29.8704)
		(width 0.127)
		(layer "B.Cu")
		(net "IOC_GPIO_25")
	)
	(segment
		(start 187.142374 -37.199824)
		(end 186.59983 -37.199824)
		(width 0.127)
		(layer "F.Cu")
		(net "IOC_GPIO_24")
	)
	(segment
		(start 187.287408 -37.05479)
		(end 187.142374 -37.199824)
		(width 0.127)
		(layer "F.Cu")
		(net "IOC_GPIO_24")
	)
	(via
		(at 187.287408 -37.05479)
		(size 0.508)
		(drill 0.254)
		(layers "F.Cu" "B.Cu")
		(net "IOC_GPIO_24")
	)
	(segment
		(start 188.18479 -37.05479)
		(end 188.341 -37.211)
		(width 0.127)
		(layer "B.Cu")
		(net "IOC_GPIO_24")
	)
	(segment
		(start 187.287408 -37.05479)
		(end 188.18479 -37.05479)
		(width 0.127)
		(layer "B.Cu")
		(net "IOC_GPIO_24")
	)
	(segment
		(start 190.2968 -32.0675)
		(end 189.870334 -32.0675)
		(width 0.127)
		(layer "F.Cu")
		(net "IOC_GPIO_23")
	)
	(segment
		(start 188.975746 -32.962088)
		(end 188.975746 -33.221168)
		(width 0.127)
		(layer "F.Cu")
		(net "IOC_GPIO_23")
	)
	(segment
		(start 188.975746 -33.221168)
		(end 188.490606 -33.706308)
		(width 0.127)
		(layer "F.Cu")
		(net "IOC_GPIO_23")
	)
	(segment
		(start 187.49264 -34.380932)
		(end 186.219084 -34.380932)
		(width 0.127)
		(layer "F.Cu")
		(net "IOC_GPIO_23")
	)
	(segment
		(start 189.870334 -32.0675)
		(end 188.975746 -32.962088)
		(width 0.127)
		(layer "F.Cu")
		(net "IOC_GPIO_23")
	)
	(segment
		(start 188.490606 -33.706308)
		(end 188.167264 -33.706308)
		(width 0.127)
		(layer "F.Cu")
		(net "IOC_GPIO_23")
	)
	(segment
		(start 186.219084 -34.380932)
		(end 185.799984 -34.800032)
		(width 0.127)
		(layer "F.Cu")
		(net "IOC_GPIO_23")
	)
	(segment
		(start 188.167264 -33.706308)
		(end 187.49264 -34.380932)
		(width 0.127)
		(layer "F.Cu")
		(net "IOC_GPIO_23")
	)
	(segment
		(start 186.71794 -29.63164)
		(end 186.353958 -29.63164)
		(width 0.127)
		(layer "F.Cu")
		(net "IOC_GPIO_22")
	)
	(segment
		(start 190.119 -27.8765)
		(end 189.484 -27.8765)
		(width 0.127)
		(layer "F.Cu")
		(net "IOC_GPIO_22")
	)
	(segment
		(start 189.4332 -27.8257)
		(end 188.52388 -27.8257)
		(width 0.127)
		(layer "F.Cu")
		(net "IOC_GPIO_22")
	)
	(segment
		(start 186.353958 -29.63164)
		(end 185.985658 -29.99994)
		(width 0.127)
		(layer "F.Cu")
		(net "IOC_GPIO_22")
	)
	(segment
		(start 188.52388 -27.8257)
		(end 186.71794 -29.63164)
		(width 0.127)
		(layer "F.Cu")
		(net "IOC_GPIO_22")
	)
	(segment
		(start 185.985658 -29.99994)
		(end 185.799984 -29.99994)
		(width 0.127)
		(layer "F.Cu")
		(net "IOC_GPIO_22")
	)
	(segment
		(start 189.484 -27.8765)
		(end 189.4332 -27.8257)
		(width 0.127)
		(layer "F.Cu")
		(net "IOC_GPIO_22")
	)
	(segment
		(start 186.71794 -30.80004)
		(end 186.59983 -30.80004)
		(width 0.127)
		(layer "F.Cu")
		(net "IOC_GPIO_21")
	)
	(segment
		(start 188.38418 -29.1338)
		(end 186.71794 -30.80004)
		(width 0.127)
		(layer "F.Cu")
		(net "IOC_GPIO_21")
	)
	(segment
		(start 188.7474 -29.1338)
		(end 188.38418 -29.1338)
		(width 0.127)
		(layer "F.Cu")
		(net "IOC_GPIO_21")
	)
	(via
		(at 188.7474 -29.1338)
		(size 0.508)
		(drill 0.254)
		(layers "F.Cu" "B.Cu")
		(net "IOC_GPIO_21")
	)
	(segment
		(start 188.7474 -29.1338)
		(end 189.8904 -29.1338)
		(width 0.127)
		(layer "B.Cu")
		(net "IOC_GPIO_21")
	)
	(segment
		(start 189.8904 -29.1338)
		(end 189.9158 -29.1592)
		(width 0.127)
		(layer "B.Cu")
		(net "IOC_GPIO_21")
	)
	(segment
		(start 184.8358 -28.756864)
		(end 184.8358 -29.035756)
		(width 0.127)
		(layer "F.Cu")
		(net "IOC_GPIO_20")
	)
	(segment
		(start 184.631584 -28.552648)
		(end 184.8358 -28.756864)
		(width 0.127)
		(layer "F.Cu")
		(net "IOC_GPIO_20")
	)
	(segment
		(start 184.631584 -28.24734)
		(end 184.631584 -28.552648)
		(width 0.127)
		(layer "F.Cu")
		(net "IOC_GPIO_20")
	)
	(segment
		(start 185.674 -27.204924)
		(end 184.631584 -28.24734)
		(width 0.127)
		(layer "F.Cu")
		(net "IOC_GPIO_20")
	)
	(segment
		(start 185.674 -27.00401)
		(end 185.674 -27.204924)
		(width 0.127)
		(layer "F.Cu")
		(net "IOC_GPIO_20")
	)
	(segment
		(start 184.8358 -29.035756)
		(end 184.999884 -29.19984)
		(width 0.127)
		(layer "F.Cu")
		(net "IOC_GPIO_20")
	)
	(via
		(at 185.674 -27.00401)
		(size 0.508)
		(drill 0.254)
		(layers "F.Cu" "B.Cu")
		(net "IOC_GPIO_20")
	)
	(segment
		(start 185.674 -27.9146)
		(end 186.563 -28.8036)
		(width 0.127)
		(layer "B.Cu")
		(net "IOC_GPIO_20")
	)
	(segment
		(start 185.674 -27.00401)
		(end 185.674 -27.9146)
		(width 0.127)
		(layer "B.Cu")
		(net "IOC_GPIO_20")
	)
	(segment
		(start 179.799996 -29.59989)
		(end 180.199792 -29.999686)
		(width 0.127)
		(layer "F.Cu")
		(net "IOC_GPIO_2")
	)
	(segment
		(start 180.199792 -29.999686)
		(end 180.199792 -29.99994)
		(width 0.127)
		(layer "F.Cu")
		(net "IOC_GPIO_2")
	)
	(via
		(at 179.799996 -29.59989)
		(size 0.508)
		(drill 0.254)
		(layers "F.Cu" "B.Cu")
		(net "IOC_GPIO_2")
	)
	(segment
		(start 179.9082 -29.083)
		(end 179.9082 -28.7782)
		(width 0.127)
		(layer "B.Cu")
		(net "IOC_GPIO_2")
	)
	(segment
		(start 179.799996 -29.59989)
		(end 179.799996 -29.191204)
		(width 0.127)
		(layer "B.Cu")
		(net "IOC_GPIO_2")
	)
	(segment
		(start 179.799996 -29.191204)
		(end 179.9082 -29.083)
		(width 0.127)
		(layer "B.Cu")
		(net "IOC_GPIO_2")
	)
	(segment
		(start 186.616086 -27.07513)
		(end 186.462416 -27.2288)
		(width 0.127)
		(layer "F.Cu")
		(net "IOC_GPIO_19")
	)
	(segment
		(start 186.055 -27.2288)
		(end 184.999884 -28.283916)
		(width 0.127)
		(layer "F.Cu")
		(net "IOC_GPIO_19")
	)
	(segment
		(start 184.999884 -28.283916)
		(end 184.999884 -28.399994)
		(width 0.127)
		(layer "F.Cu")
		(net "IOC_GPIO_19")
	)
	(segment
		(start 186.462416 -27.2288)
		(end 186.055 -27.2288)
		(width 0.127)
		(layer "F.Cu")
		(net "IOC_GPIO_19")
	)
	(via
		(at 186.616086 -27.07513)
		(size 0.508)
		(drill 0.254)
		(layers "F.Cu" "B.Cu")
		(net "IOC_GPIO_19")
	)
	(segment
		(start 186.616086 -26.769314)
		(end 187.2234 -26.162)
		(width 0.127)
		(layer "B.Cu")
		(net "IOC_GPIO_19")
	)
	(segment
		(start 186.616086 -27.07513)
		(end 186.616086 -26.769314)
		(width 0.127)
		(layer "B.Cu")
		(net "IOC_GPIO_19")
	)
	(segment
		(start 192.517014 -28.956)
		(end 193.914014 -30.353)
		(width 0.127)
		(layer "F.Cu")
		(net "IOC_GPIO_18")
	)
	(segment
		(start 186.71159 -30.43301)
		(end 188.5315 -28.6131)
		(width 0.127)
		(layer "F.Cu")
		(net "IOC_GPIO_18")
	)
	(segment
		(start 188.5315 -28.6131)
		(end 188.9887 -28.6131)
		(width 0.127)
		(layer "F.Cu")
		(net "IOC_GPIO_18")
	)
	(segment
		(start 189.3316 -28.956)
		(end 192.517014 -28.956)
		(width 0.127)
		(layer "F.Cu")
		(net "IOC_GPIO_18")
	)
	(segment
		(start 186.167014 -30.43301)
		(end 186.71159 -30.43301)
		(width 0.127)
		(layer "F.Cu")
		(net "IOC_GPIO_18")
	)
	(segment
		(start 185.799984 -30.80004)
		(end 186.167014 -30.43301)
		(width 0.127)
		(layer "F.Cu")
		(net "IOC_GPIO_18")
	)
	(segment
		(start 193.914014 -30.353)
		(end 194.437 -30.353)
		(width 0.127)
		(layer "F.Cu")
		(net "IOC_GPIO_18")
	)
	(segment
		(start 188.9887 -28.6131)
		(end 189.3316 -28.956)
		(width 0.127)
		(layer "F.Cu")
		(net "IOC_GPIO_18")
	)
	(segment
		(start 187.446412 -33.199832)
		(end 186.59983 -33.199832)
		(width 0.127)
		(layer "F.Cu")
		(net "IOC_GPIO_17")
	)
	(segment
		(start 188.0108 -32.635444)
		(end 187.446412 -33.199832)
		(width 0.127)
		(layer "F.Cu")
		(net "IOC_GPIO_17")
	)
	(segment
		(start 188.0108 -32.402018)
		(end 188.0108 -32.635444)
		(width 0.127)
		(layer "F.Cu")
		(net "IOC_GPIO_17")
	)
	(segment
		(start 188.201808 -32.21101)
		(end 188.0108 -32.402018)
		(width 0.127)
		(layer "F.Cu")
		(net "IOC_GPIO_17")
	)
	(via
		(at 188.201808 -32.21101)
		(size 0.508)
		(drill 0.254)
		(layers "F.Cu" "B.Cu")
		(net "IOC_GPIO_17")
	)
	(segment
		(start 189.64021 -32.21101)
		(end 189.7888 -32.3596)
		(width 0.127)
		(layer "B.Cu")
		(net "IOC_GPIO_17")
	)
	(segment
		(start 188.201808 -32.21101)
		(end 189.64021 -32.21101)
		(width 0.127)
		(layer "B.Cu")
		(net "IOC_GPIO_17")
	)
	(segment
		(start 186.992768 -31.599886)
		(end 186.59983 -31.599886)
		(width 0.127)
		(layer "F.Cu")
		(net "IOC_GPIO_16")
	)
	(segment
		(start 187.947808 -30.644846)
		(end 186.992768 -31.599886)
		(width 0.127)
		(layer "F.Cu")
		(net "IOC_GPIO_16")
	)
	(via
		(at 187.947808 -30.644846)
		(size 0.508)
		(drill 0.254)
		(layers "F.Cu" "B.Cu")
		(net "IOC_GPIO_16")
	)
	(segment
		(start 187.978796 -30.613858)
		(end 187.947808 -30.644846)
		(width 0.127)
		(layer "B.Cu")
		(net "IOC_GPIO_16")
	)
	(segment
		(start 189.032388 -30.613858)
		(end 187.978796 -30.613858)
		(width 0.127)
		(layer "B.Cu")
		(net "IOC_GPIO_16")
	)
	(segment
		(start 189.53988 -34.62782)
		(end 189.357254 -34.62782)
		(width 0.127)
		(layer "F.Cu")
		(net "IOC_GPIO_15")
	)
	(segment
		(start 191.3001 -33.8582)
		(end 190.3095 -33.8582)
		(width 0.127)
		(layer "F.Cu")
		(net "IOC_GPIO_15")
	)
	(segment
		(start 189.0522 -35.282886)
		(end 188.060076 -36.27501)
		(width 0.127)
		(layer "F.Cu")
		(net "IOC_GPIO_15")
	)
	(segment
		(start 191.8462 -33.3121)
		(end 191.3001 -33.8582)
		(width 0.127)
		(layer "F.Cu")
		(net "IOC_GPIO_15")
	)
	(segment
		(start 190.3095 -33.8582)
		(end 189.53988 -34.62782)
		(width 0.127)
		(layer "F.Cu")
		(net "IOC_GPIO_15")
	)
	(segment
		(start 189.357254 -34.62782)
		(end 189.0522 -34.932874)
		(width 0.127)
		(layer "F.Cu")
		(net "IOC_GPIO_15")
	)
	(segment
		(start 188.060076 -36.27501)
		(end 186.724798 -36.27501)
		(width 0.127)
		(layer "F.Cu")
		(net "IOC_GPIO_15")
	)
	(segment
		(start 186.724798 -36.27501)
		(end 186.59983 -36.399978)
		(width 0.127)
		(layer "F.Cu")
		(net "IOC_GPIO_15")
	)
	(segment
		(start 189.0522 -34.932874)
		(end 189.0522 -35.282886)
		(width 0.127)
		(layer "F.Cu")
		(net "IOC_GPIO_15")
	)
	(segment
		(start 183.76519 -28.27401)
		(end 183.76519 -28.765246)
		(width 0.127)
		(layer "F.Cu")
		(net "IOC_GPIO_14")
	)
	(segment
		(start 183.76519 -28.765246)
		(end 184.199784 -29.19984)
		(width 0.127)
		(layer "F.Cu")
		(net "IOC_GPIO_14")
	)
	(segment
		(start 184.4294 -27.6098)
		(end 183.76519 -28.27401)
		(width 0.127)
		(layer "F.Cu")
		(net "IOC_GPIO_14")
	)
	(segment
		(start 184.4294 -27.2288)
		(end 184.4294 -27.6098)
		(width 0.127)
		(layer "F.Cu")
		(net "IOC_GPIO_14")
	)
	(via
		(at 184.4294 -27.2288)
		(size 0.508)
		(drill 0.254)
		(layers "F.Cu" "B.Cu")
		(net "IOC_GPIO_14")
	)
	(segment
		(start 184.4294 -27.2288)
		(end 184.4294 -27.188414)
		(width 0.127)
		(layer "B.Cu")
		(net "IOC_GPIO_14")
	)
	(segment
		(start 185.4708 -26.147014)
		(end 185.4708 -24.9428)
		(width 0.127)
		(layer "B.Cu")
		(net "IOC_GPIO_14")
	)
	(segment
		(start 184.4294 -27.188414)
		(end 185.4708 -26.147014)
		(width 0.127)
		(layer "B.Cu")
		(net "IOC_GPIO_14")
	)
	(segment
		(start 182.168038 -28.76804)
		(end 182.599838 -29.19984)
		(width 0.127)
		(layer "F.Cu")
		(net "IOC_GPIO_13")
	)
	(segment
		(start 182.168038 -27.850084)
		(end 182.168038 -28.76804)
		(width 0.127)
		(layer "F.Cu")
		(net "IOC_GPIO_13")
	)
	(via
		(at 182.168038 -27.850084)
		(size 0.508)
		(drill 0.254)
		(layers "F.Cu" "B.Cu")
		(net "IOC_GPIO_13")
	)
	(segment
		(start 182.753 -26.1366)
		(end 182.1942 -26.6954)
		(width 0.127)
		(layer "B.Cu")
		(net "IOC_GPIO_13")
	)
	(segment
		(start 182.1942 -27.823922)
		(end 182.168038 -27.850084)
		(width 0.127)
		(layer "B.Cu")
		(net "IOC_GPIO_13")
	)
	(segment
		(start 182.1942 -26.6954)
		(end 182.1942 -27.823922)
		(width 0.127)
		(layer "B.Cu")
		(net "IOC_GPIO_13")
	)
	(segment
		(start 187.4012 -27.05735)
		(end 186.96432 -27.49423)
		(width 0.127)
		(layer "F.Cu")
		(net "IOC_GPIO_12")
	)
	(segment
		(start 185.431684 -28.83154)
		(end 185.799984 -29.19984)
		(width 0.127)
		(layer "F.Cu")
		(net "IOC_GPIO_12")
	)
	(segment
		(start 186.96432 -27.49423)
		(end 186.17057 -27.49423)
		(width 0.127)
		(layer "F.Cu")
		(net "IOC_GPIO_12")
	)
	(segment
		(start 185.431684 -28.233116)
		(end 185.431684 -28.83154)
		(width 0.127)
		(layer "F.Cu")
		(net "IOC_GPIO_12")
	)
	(segment
		(start 186.17057 -27.49423)
		(end 185.431684 -28.233116)
		(width 0.127)
		(layer "F.Cu")
		(net "IOC_GPIO_12")
	)
	(via
		(at 187.4012 -27.05735)
		(size 0.508)
		(drill 0.254)
		(layers "F.Cu" "B.Cu")
		(net "IOC_GPIO_12")
	)
	(segment
		(start 187.4012 -27.05735)
		(end 187.77585 -27.05735)
		(width 0.127)
		(layer "B.Cu")
		(net "IOC_GPIO_12")
	)
	(segment
		(start 187.77585 -27.05735)
		(end 188.6458 -26.1874)
		(width 0.127)
		(layer "B.Cu")
		(net "IOC_GPIO_12")
	)
	(segment
		(start 186.73826 -29.99994)
		(end 188.6204 -28.1178)
		(width 0.127)
		(layer "F.Cu")
		(net "IOC_GPIO_11")
	)
	(segment
		(start 189.1538 -28.1178)
		(end 189.484 -28.448)
		(width 0.127)
		(layer "F.Cu")
		(net "IOC_GPIO_11")
	)
	(segment
		(start 192.72758 -28.448)
		(end 193.48958 -29.21)
		(width 0.127)
		(layer "F.Cu")
		(net "IOC_GPIO_11")
	)
	(segment
		(start 188.6204 -28.1178)
		(end 189.1538 -28.1178)
		(width 0.127)
		(layer "F.Cu")
		(net "IOC_GPIO_11")
	)
	(segment
		(start 189.484 -28.448)
		(end 192.72758 -28.448)
		(width 0.127)
		(layer "F.Cu")
		(net "IOC_GPIO_11")
	)
	(segment
		(start 186.59983 -29.99994)
		(end 186.73826 -29.99994)
		(width 0.127)
		(layer "F.Cu")
		(net "IOC_GPIO_11")
	)
	(segment
		(start 193.48958 -29.21)
		(end 193.929 -29.21)
		(width 0.127)
		(layer "F.Cu")
		(net "IOC_GPIO_11")
	)
	(segment
		(start 185.67146 -29.602684)
		(end 185.274204 -29.99994)
		(width 0.127)
		(layer "F.Cu")
		(net "IOC_GPIO_10")
	)
	(segment
		(start 186.193684 -28.936696)
		(end 186.193684 -29.327094)
		(width 0.127)
		(layer "F.Cu")
		(net "IOC_GPIO_10")
	)
	(segment
		(start 186.193684 -29.327094)
		(end 185.918094 -29.602684)
		(width 0.127)
		(layer "F.Cu")
		(net "IOC_GPIO_10")
	)
	(segment
		(start 185.918094 -29.602684)
		(end 185.67146 -29.602684)
		(width 0.127)
		(layer "F.Cu")
		(net "IOC_GPIO_10")
	)
	(segment
		(start 187.14339 -27.98699)
		(end 186.193684 -28.936696)
		(width 0.127)
		(layer "F.Cu")
		(net "IOC_GPIO_10")
	)
	(segment
		(start 185.274204 -29.99994)
		(end 184.999884 -29.99994)
		(width 0.127)
		(layer "F.Cu")
		(net "IOC_GPIO_10")
	)
	(via
		(at 187.14339 -27.98699)
		(size 0.508)
		(drill 0.254)
		(layers "F.Cu" "B.Cu")
		(net "IOC_GPIO_10")
	)
	(segment
		(start 187.9346 -28.575)
		(end 187.7314 -28.575)
		(width 0.127)
		(layer "B.Cu")
		(net "IOC_GPIO_10")
	)
	(segment
		(start 187.7314 -28.575)
		(end 187.14339 -27.98699)
		(width 0.127)
		(layer "B.Cu")
		(net "IOC_GPIO_10")
	)
	(segment
		(start 183.558942 -26.782776)
		(end 183.057038 -27.28468)
		(width 0.127)
		(layer "F.Cu")
		(net "IOC_GPIO_1")
	)
	(segment
		(start 183.057038 -28.85694)
		(end 183.399938 -29.19984)
		(width 0.127)
		(layer "F.Cu")
		(net "IOC_GPIO_1")
	)
	(segment
		(start 183.057038 -27.28468)
		(end 183.057038 -28.85694)
		(width 0.127)
		(layer "F.Cu")
		(net "IOC_GPIO_1")
	)
	(via
		(at 183.558942 -26.782776)
		(size 0.508)
		(drill 0.254)
		(layers "F.Cu" "B.Cu")
		(net "IOC_GPIO_1")
	)
	(segment
		(start 184.027318 -26.3144)
		(end 183.558942 -26.782776)
		(width 0.127)
		(layer "B.Cu")
		(net "IOC_GPIO_1")
	)
	(segment
		(start 184.3024 -26.3144)
		(end 184.027318 -26.3144)
		(width 0.127)
		(layer "B.Cu")
		(net "IOC_GPIO_1")
	)
	(segment
		(start 188.269118 -29.7307)
		(end 188.955934 -29.7307)
		(width 0.127)
		(layer "F.Cu")
		(net "IOC_GPIO_0")
	)
	(segment
		(start 188.955934 -29.7307)
		(end 189.222634 -29.464)
		(width 0.127)
		(layer "F.Cu")
		(net "IOC_GPIO_0")
	)
	(segment
		(start 186.814714 -31.185104)
		(end 188.269118 -29.7307)
		(width 0.127)
		(layer "F.Cu")
		(net "IOC_GPIO_0")
	)
	(segment
		(start 192.2526 -29.464)
		(end 193.1543 -30.3657)
		(width 0.127)
		(layer "F.Cu")
		(net "IOC_GPIO_0")
	)
	(segment
		(start 186.337956 -31.185104)
		(end 186.814714 -31.185104)
		(width 0.127)
		(layer "F.Cu")
		(net "IOC_GPIO_0")
	)
	(segment
		(start 185.923174 -31.599886)
		(end 186.337956 -31.185104)
		(width 0.127)
		(layer "F.Cu")
		(net "IOC_GPIO_0")
	)
	(segment
		(start 189.222634 -29.464)
		(end 192.2526 -29.464)
		(width 0.127)
		(layer "F.Cu")
		(net "IOC_GPIO_0")
	)
	(segment
		(start 185.799984 -31.599886)
		(end 185.923174 -31.599886)
		(width 0.127)
		(layer "F.Cu")
		(net "IOC_GPIO_0")
	)
	(via
		(at 202.0443 -45.3517)
		(size 0.6096)
		(drill 0.3048)
		(layers "F.Cu" "B.Cu")
		(net "IOC_EEPROM_WP")
	)
	(segment
		(start 202.21194 -45.51934)
		(end 202.0443 -45.3517)
		(width 0.127)
		(layer "B.Cu")
		(net "IOC_EEPROM_WP")
	)
	(segment
		(start 201.93 -45.2374)
		(end 202.0443 -45.3517)
		(width 0.127)
		(layer "B.Cu")
		(net "IOC_EEPROM_WP")
	)
	(segment
		(start 202.21194 -46.4439)
		(end 202.21194 -45.51934)
		(width 0.127)
		(layer "B.Cu")
		(net "IOC_EEPROM_WP")
	)
	(segment
		(start 201.93 -43.688)
		(end 201.93 -45.2374)
		(width 0.127)
		(layer "B.Cu")
		(net "IOC_EEPROM_WP")
	)
	(via
		(at 198.8439 -45.3009)
		(size 0.6096)
		(drill 0.3048)
		(layers "F.Cu" "B.Cu")
		(net "IOC_EEPROM_SDA")
	)
	(segment
		(start 199.39 -44.6405)
		(end 198.8439 -45.1866)
		(width 0.127)
		(layer "B.Cu")
		(net "IOC_EEPROM_SDA")
	)
	(segment
		(start 198.955914 -46.439074)
		(end 198.8439 -46.32706)
		(width 0.127)
		(layer "B.Cu")
		(net "IOC_EEPROM_SDA")
	)
	(segment
		(start 199.39 -43.688)
		(end 199.39 -44.6405)
		(width 0.127)
		(layer "B.Cu")
		(net "IOC_EEPROM_SDA")
	)
	(segment
		(start 198.8439 -45.1866)
		(end 198.8439 -45.3009)
		(width 0.127)
		(layer "B.Cu")
		(net "IOC_EEPROM_SDA")
	)
	(segment
		(start 198.8439 -46.32706)
		(end 198.8439 -45.3009)
		(width 0.127)
		(layer "B.Cu")
		(net "IOC_EEPROM_SDA")
	)
	(via
		(at 200.6727 -45.3009)
		(size 0.6096)
		(drill 0.3048)
		(layers "F.Cu" "B.Cu")
		(net "IOC_EEPROM_SCL")
	)
	(segment
		(start 200.66 -45.2882)
		(end 200.6727 -45.3009)
		(width 0.127)
		(layer "B.Cu")
		(net "IOC_EEPROM_SCL")
	)
	(segment
		(start 200.9648 -45.593)
		(end 200.6727 -45.3009)
		(width 0.127)
		(layer "B.Cu")
		(net "IOC_EEPROM_SCL")
	)
	(segment
		(start 200.66 -43.688)
		(end 200.66 -45.2882)
		(width 0.127)
		(layer "B.Cu")
		(net "IOC_EEPROM_SCL")
	)
	(segment
		(start 200.9648 -46.4439)
		(end 200.9648 -45.593)
		(width 0.127)
		(layer "B.Cu")
		(net "IOC_EEPROM_SCL")
	)
	(via
		(at 199.582024 -36.919662)
		(size 0.6096)
		(drill 0.3048)
		(layers "F.Cu" "B.Cu")
		(net "IOC_EEPROM_A2")
	)
	(segment
		(start 198.755 -36.092638)
		(end 198.755 -35.7759)
		(width 0.127)
		(layer "B.Cu")
		(net "IOC_EEPROM_A2")
	)
	(segment
		(start 199.582024 -36.919662)
		(end 198.755 -36.092638)
		(width 0.127)
		(layer "B.Cu")
		(net "IOC_EEPROM_A2")
	)
	(segment
		(start 200.66 -38.608)
		(end 200.66 -37.997638)
		(width 0.127)
		(layer "B.Cu")
		(net "IOC_EEPROM_A2")
	)
	(segment
		(start 198.755 -35.7759)
		(end 199.771 -35.7759)
		(width 0.127)
		(layer "B.Cu")
		(net "IOC_EEPROM_A2")
	)
	(segment
		(start 200.66 -37.997638)
		(end 199.582024 -36.919662)
		(width 0.127)
		(layer "B.Cu")
		(net "IOC_EEPROM_A2")
	)
	(via
		(at 201.518012 -36.908486)
		(size 0.6096)
		(drill 0.3048)
		(layers "F.Cu" "B.Cu")
		(net "IOC_EEPROM_A1")
	)
	(segment
		(start 201.93 -37.693854)
		(end 201.518012 -37.281866)
		(width 0.127)
		(layer "B.Cu")
		(net "IOC_EEPROM_A1")
	)
	(segment
		(start 201.803 -35.7759)
		(end 200.787 -35.7759)
		(width 0.127)
		(layer "B.Cu")
		(net "IOC_EEPROM_A1")
	)
	(segment
		(start 201.93 -38.608)
		(end 201.93 -37.693854)
		(width 0.127)
		(layer "B.Cu")
		(net "IOC_EEPROM_A1")
	)
	(segment
		(start 201.518012 -36.908486)
		(end 201.518012 -36.32835)
		(width 0.127)
		(layer "B.Cu")
		(net "IOC_EEPROM_A1")
	)
	(segment
		(start 201.518012 -36.32835)
		(end 201.803 -36.043362)
		(width 0.127)
		(layer "B.Cu")
		(net "IOC_EEPROM_A1")
	)
	(segment
		(start 201.803 -36.043362)
		(end 201.803 -35.7759)
		(width 0.127)
		(layer "B.Cu")
		(net "IOC_EEPROM_A1")
	)
	(segment
		(start 201.518012 -37.281866)
		(end 201.518012 -36.908486)
		(width 0.127)
		(layer "B.Cu")
		(net "IOC_EEPROM_A1")
	)
	(via
		(at 203.2 -36.89096)
		(size 0.6096)
		(drill 0.3048)
		(layers "F.Cu" "B.Cu")
		(net "IOC_EEPROM_A0")
	)
	(segment
		(start 203.2 -36.89096)
		(end 203.2 -38.608)
		(width 0.127)
		(layer "B.Cu")
		(net "IOC_EEPROM_A0")
	)
	(segment
		(start 203.2 -36.577016)
		(end 203.2 -36.89096)
		(width 0.127)
		(layer "B.Cu")
		(net "IOC_EEPROM_A0")
	)
	(segment
		(start 202.819 -35.7759)
		(end 202.819 -36.196016)
		(width 0.127)
		(layer "B.Cu")
		(net "IOC_EEPROM_A0")
	)
	(segment
		(start 202.819 -36.196016)
		(end 203.2 -36.577016)
		(width 0.127)
		(layer "B.Cu")
		(net "IOC_EEPROM_A0")
	)
	(segment
		(start 203.884784 -35.7759)
		(end 202.819 -35.7759)
		(width 0.127)
		(layer "B.Cu")
		(net "IOC_EEPROM_A0")
	)
	(segment
		(start 184.999884 -39.59987)
		(end 185.399934 -39.99992)
		(width 0.127)
		(layer "F.Cu")
		(net "IOC_CLK_SEL1")
	)
	(via
		(at 185.399934 -39.99992)
		(size 0.508)
		(drill 0.254)
		(layers "F.Cu" "B.Cu")
		(net "IOC_CLK_SEL1")
	)
	(via
		(at 186.075066 -38.764464)
		(size 0.6096)
		(drill 0.3048)
		(layers "F.Cu" "B.Cu")
		(net "IOC_CLK_SEL1")
	)
	(segment
		(start 185.399934 -39.99992)
		(end 185.968894 -39.43096)
		(width 0.127)
		(layer "B.Cu")
		(net "IOC_CLK_SEL1")
	)
	(segment
		(start 187.154566 -38.582346)
		(end 187.154566 -39.598346)
		(width 0.127)
		(layer "B.Cu")
		(net "IOC_CLK_SEL1")
	)
	(segment
		(start 186.075066 -38.764464)
		(end 186.257184 -38.582346)
		(width 0.127)
		(layer "B.Cu")
		(net "IOC_CLK_SEL1")
	)
	(segment
		(start 185.968894 -39.43096)
		(end 185.968894 -38.870636)
		(width 0.127)
		(layer "B.Cu")
		(net "IOC_CLK_SEL1")
	)
	(segment
		(start 186.257184 -38.582346)
		(end 187.154566 -38.582346)
		(width 0.127)
		(layer "B.Cu")
		(net "IOC_CLK_SEL1")
	)
	(segment
		(start 185.968894 -38.870636)
		(end 186.075066 -38.764464)
		(width 0.127)
		(layer "B.Cu")
		(net "IOC_CLK_SEL1")
	)
	(segment
		(start 190.073026 -41.676574)
		(end 190.809372 -41.676574)
		(width 0.127)
		(layer "F.Cu")
		(net "IOC_CLK_SEL0")
	)
	(segment
		(start 186.157108 -40.842692)
		(end 187.018422 -40.842692)
		(width 0.127)
		(layer "F.Cu")
		(net "IOC_CLK_SEL0")
	)
	(segment
		(start 191.993266 -42.375074)
		(end 192.00114 -42.3672)
		(width 0.127)
		(layer "F.Cu")
		(net "IOC_CLK_SEL0")
	)
	(segment
		(start 192.00114 -42.3672)
		(end 193.04 -42.3672)
		(width 0.127)
		(layer "F.Cu")
		(net "IOC_CLK_SEL0")
	)
	(segment
		(start 187.018422 -40.842692)
		(end 188.16193 -41.9862)
		(width 0.127)
		(layer "F.Cu")
		(net "IOC_CLK_SEL0")
	)
	(segment
		(start 191.050672 -42.375074)
		(end 191.993266 -42.375074)
		(width 0.127)
		(layer "F.Cu")
		(net "IOC_CLK_SEL0")
	)
	(segment
		(start 188.16193 -41.9862)
		(end 189.7634 -41.9862)
		(width 0.127)
		(layer "F.Cu")
		(net "IOC_CLK_SEL0")
	)
	(segment
		(start 190.809372 -42.133774)
		(end 191.050672 -42.375074)
		(width 0.127)
		(layer "F.Cu")
		(net "IOC_CLK_SEL0")
	)
	(segment
		(start 189.8269 -41.9227)
		(end 190.073026 -41.676574)
		(width 0.127)
		(layer "F.Cu")
		(net "IOC_CLK_SEL0")
	)
	(segment
		(start 189.7634 -41.9862)
		(end 189.8269 -41.9227)
		(width 0.127)
		(layer "F.Cu")
		(net "IOC_CLK_SEL0")
	)
	(segment
		(start 193.04 -42.3672)
		(end 193.6877 -41.7195)
		(width 0.127)
		(layer "F.Cu")
		(net "IOC_CLK_SEL0")
	)
	(segment
		(start 190.809372 -41.676574)
		(end 190.809372 -42.133774)
		(width 0.127)
		(layer "F.Cu")
		(net "IOC_CLK_SEL0")
	)
	(segment
		(start 193.6877 -41.7195)
		(end 193.6877 -41.7068)
		(width 0.127)
		(layer "F.Cu")
		(net "IOC_CLK_SEL0")
	)
	(segment
		(start 185.799984 -41.199816)
		(end 186.157108 -40.842692)
		(width 0.127)
		(layer "F.Cu")
		(net "IOC_CLK_SEL0")
	)
	(via
		(at 189.8269 -41.9227)
		(size 0.6604)
		(drill 0.3302)
		(layers "F.Cu" "B.Cu")
		(net "IOC_CLK_SEL0")
	)
	(segment
		(start 164.164772 -55.315612)
		(end 164.164772 -56.6293)
		(width 0.127)
		(layer "F.Cu")
		(net "ICE1_TRST#")
	)
	(segment
		(start 167.39997 -50.230024)
		(end 167.39997 -49.9999)
		(width 0.127)
		(layer "F.Cu")
		(net "ICE1_TRST#")
	)
	(segment
		(start 164.164772 -56.6293)
		(end 164.075872 -56.7182)
		(width 0.127)
		(layer "F.Cu")
		(net "ICE1_TRST#")
	)
	(segment
		(start 167.037766 -52.336192)
		(end 167.037766 -50.592228)
		(width 0.127)
		(layer "F.Cu")
		(net "ICE1_TRST#")
	)
	(segment
		(start 167.037766 -50.592228)
		(end 167.39997 -50.230024)
		(width 0.127)
		(layer "F.Cu")
		(net "ICE1_TRST#")
	)
	(segment
		(start 164.164772 -55.209186)
		(end 167.037766 -52.336192)
		(width 0.127)
		(layer "F.Cu")
		(net "ICE1_TRST#")
	)
	(segment
		(start 164.075872 -56.7182)
		(end 164.075872 -57.669938)
		(width 0.127)
		(layer "F.Cu")
		(net "ICE1_TRST#")
	)
	(segment
		(start 164.164772 -55.315612)
		(end 164.164772 -55.209186)
		(width 0.127)
		(layer "F.Cu")
		(net "ICE1_TRST#")
	)
	(segment
		(start 165.172898 -57.664096)
		(end 165.172898 -56.394858)
		(width 0.127)
		(layer "F.Cu")
		(net "ICE1_TMS")
	)
	(segment
		(start 167.39997 -52.692554)
		(end 167.39997 -51.599846)
		(width 0.127)
		(layer "F.Cu")
		(net "ICE1_TMS")
	)
	(segment
		(start 165.273736 -56.29402)
		(end 165.273736 -54.818788)
		(width 0.127)
		(layer "F.Cu")
		(net "ICE1_TMS")
	)
	(segment
		(start 165.273736 -54.818788)
		(end 167.39997 -52.692554)
		(width 0.127)
		(layer "F.Cu")
		(net "ICE1_TMS")
	)
	(segment
		(start 165.172898 -56.394858)
		(end 165.273736 -56.29402)
		(width 0.127)
		(layer "F.Cu")
		(net "ICE1_TMS")
	)
	(segment
		(start 170.563032 -56.089296)
		(end 170.599862 -56.052466)
		(width 0.127)
		(layer "F.Cu")
		(net "ICE1_TDO")
	)
	(segment
		(start 170.599862 -56.052466)
		(end 170.599862 -51.599846)
		(width 0.127)
		(layer "F.Cu")
		(net "ICE1_TDO")
	)
	(segment
		(start 167.39997 -43.599862)
		(end 167.799766 -43.999658)
		(width 0.127)
		(layer "F.Cu")
		(net "ICE1_TDI")
	)
	(via
		(at 167.799766 -43.999658)
		(size 0.508)
		(drill 0.254)
		(layers "F.Cu" "B.Cu")
		(net "ICE1_TDI")
	)
	(segment
		(start 167.799766 -47.312834)
		(end 167.799766 -43.999658)
		(width 0.127)
		(layer "B.Cu")
		(net "ICE1_TDI")
	)
	(segment
		(start 166.5478 -50.038508)
		(end 166.5478 -48.5648)
		(width 0.127)
		(layer "B.Cu")
		(net "ICE1_TDI")
	)
	(segment
		(start 166.906702 -50.39741)
		(end 166.5478 -50.038508)
		(width 0.127)
		(layer "B.Cu")
		(net "ICE1_TDI")
	)
	(segment
		(start 167.64 -51.130708)
		(end 166.906702 -50.39741)
		(width 0.127)
		(layer "B.Cu")
		(net "ICE1_TDI")
	)
	(segment
		(start 167.64 -51.6255)
		(end 167.64 -51.130708)
		(width 0.127)
		(layer "B.Cu")
		(net "ICE1_TDI")
	)
	(segment
		(start 166.5478 -48.5648)
		(end 167.799766 -47.312834)
		(width 0.127)
		(layer "B.Cu")
		(net "ICE1_TDI")
	)
	(segment
		(start 168.199816 -51.072796)
		(end 168.199816 -50.8)
		(width 0.127)
		(layer "F.Cu")
		(net "ICE1_TCK")
	)
	(segment
		(start 166.233856 -55.208932)
		(end 166.233856 -54.577234)
		(width 0.127)
		(layer "F.Cu")
		(net "ICE1_TCK")
	)
	(segment
		(start 166.233856 -57.67451)
		(end 166.233856 -55.208932)
		(width 0.127)
		(layer "F.Cu")
		(net "ICE1_TCK")
	)
	(segment
		(start 167.754808 -53.056282)
		(end 167.754808 -51.517804)
		(width 0.127)
		(layer "F.Cu")
		(net "ICE1_TCK")
	)
	(segment
		(start 166.233856 -54.577234)
		(end 167.754808 -53.056282)
		(width 0.127)
		(layer "F.Cu")
		(net "ICE1_TCK")
	)
	(segment
		(start 167.754808 -51.517804)
		(end 168.199816 -51.072796)
		(width 0.127)
		(layer "F.Cu")
		(net "ICE1_TCK")
	)
	(segment
		(start 168.008808 -54.5084)
		(end 168.008808 -55.179214)
		(width 0.127)
		(layer "F.Cu")
		(net "ICE0_TRST#")
	)
	(segment
		(start 168.999916 -53.517292)
		(end 168.008808 -54.5084)
		(width 0.127)
		(layer "F.Cu")
		(net "ICE0_TRST#")
	)
	(segment
		(start 168.999916 -51.599846)
		(end 168.999916 -53.517292)
		(width 0.127)
		(layer "F.Cu")
		(net "ICE0_TRST#")
	)
	(segment
		(start 168.008808 -56.883808)
		(end 168.008808 -55.179214)
		(width 0.127)
		(layer "F.Cu")
		(net "ICE0_TRST#")
	)
	(segment
		(start 168.42994 -57.30494)
		(end 168.008808 -56.883808)
		(width 0.127)
		(layer "F.Cu")
		(net "ICE0_TRST#")
	)
	(segment
		(start 168.42994 -57.63895)
		(end 168.42994 -57.30494)
		(width 0.127)
		(layer "F.Cu")
		(net "ICE0_TRST#")
	)
	(segment
		(start 167.002206 -50.203354)
		(end 166.79291 -50.41265)
		(width 0.127)
		(layer "F.Cu")
		(net "ICE0_TMS")
	)
	(segment
		(start 162.961066 -57.69356)
		(end 162.961066 -56.32958)
		(width 0.127)
		(layer "F.Cu")
		(net "ICE0_TMS")
	)
	(segment
		(start 166.25697 -50.600356)
		(end 166.25697 -52.398422)
		(width 0.127)
		(layer "F.Cu")
		(net "ICE0_TMS")
	)
	(segment
		(start 162.961066 -55.694326)
		(end 162.961066 -56.32958)
		(width 0.127)
		(layer "F.Cu")
		(net "ICE0_TMS")
	)
	(segment
		(start 168.199816 -49.9999)
		(end 167.78732 -49.587404)
		(width 0.127)
		(layer "F.Cu")
		(net "ICE0_TMS")
	)
	(segment
		(start 166.444676 -50.41265)
		(end 166.25697 -50.600356)
		(width 0.127)
		(layer "F.Cu")
		(net "ICE0_TMS")
	)
	(segment
		(start 167.002206 -49.866042)
		(end 167.002206 -50.203354)
		(width 0.127)
		(layer "F.Cu")
		(net "ICE0_TMS")
	)
	(segment
		(start 166.79291 -50.41265)
		(end 166.444676 -50.41265)
		(width 0.127)
		(layer "F.Cu")
		(net "ICE0_TMS")
	)
	(segment
		(start 166.25697 -52.398422)
		(end 162.961066 -55.694326)
		(width 0.127)
		(layer "F.Cu")
		(net "ICE0_TMS")
	)
	(segment
		(start 167.78732 -49.587404)
		(end 167.280844 -49.587404)
		(width 0.127)
		(layer "F.Cu")
		(net "ICE0_TMS")
	)
	(segment
		(start 167.280844 -49.587404)
		(end 167.002206 -49.866042)
		(width 0.127)
		(layer "F.Cu")
		(net "ICE0_TMS")
	)
	(segment
		(start 169.382186 -50.38217)
		(end 168.999916 -49.9999)
		(width 0.127)
		(layer "F.Cu")
		(net "ICE0_TDO")
	)
	(segment
		(start 169.382186 -53.853842)
		(end 169.382186 -50.38217)
		(width 0.127)
		(layer "F.Cu")
		(net "ICE0_TDO")
	)
	(segment
		(start 168.770808 -54.46522)
		(end 169.382186 -53.853842)
		(width 0.127)
		(layer "F.Cu")
		(net "ICE0_TDO")
	)
	(segment
		(start 168.770808 -56.46801)
		(end 168.770808 -54.46522)
		(width 0.127)
		(layer "F.Cu")
		(net "ICE0_TDO")
	)
	(segment
		(start 167.11168 -54.79542)
		(end 168.643808 -53.263292)
		(width 0.127)
		(layer "F.Cu")
		(net "ICE0_TDI")
	)
	(segment
		(start 168.643808 -53.263292)
		(end 168.643808 -51.446176)
		(width 0.127)
		(layer "F.Cu")
		(net "ICE0_TDI")
	)
	(segment
		(start 168.999916 -51.090068)
		(end 168.999916 -50.8)
		(width 0.127)
		(layer "F.Cu")
		(net "ICE0_TDI")
	)
	(segment
		(start 167.28694 -57.63895)
		(end 167.28694 -56.4515)
		(width 0.127)
		(layer "F.Cu")
		(net "ICE0_TDI")
	)
	(segment
		(start 168.643808 -51.446176)
		(end 168.999916 -51.090068)
		(width 0.127)
		(layer "F.Cu")
		(net "ICE0_TDI")
	)
	(segment
		(start 167.28694 -56.4515)
		(end 167.11168 -56.27624)
		(width 0.127)
		(layer "F.Cu")
		(net "ICE0_TDI")
	)
	(segment
		(start 167.11168 -56.27624)
		(end 167.11168 -54.79542)
		(width 0.127)
		(layer "F.Cu")
		(net "ICE0_TDI")
	)
	(segment
		(start 169.507662 -57.628028)
		(end 169.507662 -56.08701)
		(width 0.127)
		(layer "F.Cu")
		(net "ICE0_TCK")
	)
	(segment
		(start 169.460164 -56.039512)
		(end 169.460164 -55.167276)
		(width 0.127)
		(layer "F.Cu")
		(net "ICE0_TCK")
	)
	(segment
		(start 169.800016 -51.599846)
		(end 169.800016 -54.178454)
		(width 0.127)
		(layer "F.Cu")
		(net "ICE0_TCK")
	)
	(segment
		(start 169.507662 -56.08701)
		(end 169.460164 -56.039512)
		(width 0.127)
		(layer "F.Cu")
		(net "ICE0_TCK")
	)
	(segment
		(start 169.460164 -54.518306)
		(end 169.460164 -55.167276)
		(width 0.127)
		(layer "F.Cu")
		(net "ICE0_TCK")
	)
	(segment
		(start 169.800016 -54.178454)
		(end 169.460164 -54.518306)
		(width 0.127)
		(layer "F.Cu")
		(net "ICE0_TCK")
	)
	(segment
		(start 122.500136 -77.500226)
		(end 123.000008 -78.000098)
		(width 0.127)
		(layer "F.Cu")
		(net "ICE_TRST_N")
	)
	(via
		(at 123.000008 -78.000098)
		(size 0.4572)
		(drill 0.2032)
		(layers "F.Cu" "B.Cu")
		(net "ICE_TRST_N")
	)
	(segment
		(start 122.352308 -79.450692)
		(end 122.606308 -79.196692)
		(width 0.127)
		(layer "B.Cu")
		(net "ICE_TRST_N")
	)
	(segment
		(start 125.984 -85.344)
		(end 123.0249 -82.3849)
		(width 0.127)
		(layer "B.Cu")
		(net "ICE_TRST_N")
	)
	(segment
		(start 127.325374 -86.807294)
		(end 127.325374 -86.685374)
		(width 0.127)
		(layer "B.Cu")
		(net "ICE_TRST_N")
	)
	(segment
		(start 122.606308 -78.836774)
		(end 123.000008 -78.443074)
		(width 0.127)
		(layer "B.Cu")
		(net "ICE_TRST_N")
	)
	(segment
		(start 122.352308 -81.356708)
		(end 122.352308 -79.450692)
		(width 0.127)
		(layer "B.Cu")
		(net "ICE_TRST_N")
	)
	(segment
		(start 123.0249 -82.3849)
		(end 123.0249 -82.0293)
		(width 0.127)
		(layer "B.Cu")
		(net "ICE_TRST_N")
	)
	(segment
		(start 123.000008 -78.443074)
		(end 123.000008 -78.000098)
		(width 0.127)
		(layer "B.Cu")
		(net "ICE_TRST_N")
	)
	(segment
		(start 127.325374 -86.685374)
		(end 125.984 -85.344)
		(width 0.127)
		(layer "B.Cu")
		(net "ICE_TRST_N")
	)
	(segment
		(start 123.0249 -82.0293)
		(end 122.352308 -81.356708)
		(width 0.127)
		(layer "B.Cu")
		(net "ICE_TRST_N")
	)
	(segment
		(start 122.606308 -79.196692)
		(end 122.606308 -78.836774)
		(width 0.127)
		(layer "B.Cu")
		(net "ICE_TRST_N")
	)
	(segment
		(start 123.500134 -78.500224)
		(end 124.000006 -79.000096)
		(width 0.127)
		(layer "F.Cu")
		(net "ICE_TMS")
	)
	(via
		(at 124.000006 -79.000096)
		(size 0.4572)
		(drill 0.2032)
		(layers "F.Cu" "B.Cu")
		(net "ICE_TMS")
	)
	(segment
		(start 127.4699 -84.1629)
		(end 128.7018 -85.3948)
		(width 0.127)
		(layer "B.Cu")
		(net "ICE_TMS")
	)
	(segment
		(start 125.605794 -84.1629)
		(end 127.4699 -84.1629)
		(width 0.127)
		(layer "B.Cu")
		(net "ICE_TMS")
	)
	(segment
		(start 124.496068 -83.053174)
		(end 125.605794 -84.1629)
		(width 0.127)
		(layer "B.Cu")
		(net "ICE_TMS")
	)
	(segment
		(start 124.000006 -81.2419)
		(end 124.496068 -81.737962)
		(width 0.127)
		(layer "B.Cu")
		(net "ICE_TMS")
	)
	(segment
		(start 128.7018 -85.3948)
		(end 129.417318 -86.110318)
		(width 0.127)
		(layer "B.Cu")
		(net "ICE_TMS")
	)
	(segment
		(start 124.000006 -79.000096)
		(end 124.000006 -81.2419)
		(width 0.127)
		(layer "B.Cu")
		(net "ICE_TMS")
	)
	(segment
		(start 129.417318 -86.110318)
		(end 129.417318 -86.816184)
		(width 0.127)
		(layer "B.Cu")
		(net "ICE_TMS")
	)
	(segment
		(start 124.496068 -81.737962)
		(end 124.496068 -83.053174)
		(width 0.127)
		(layer "B.Cu")
		(net "ICE_TMS")
	)
	(segment
		(start 125.50013 -80.50022)
		(end 126.000002 -81.000092)
		(width 0.127)
		(layer "F.Cu")
		(net "ICE_TDO")
	)
	(via
		(at 126.000002 -81.000092)
		(size 0.4572)
		(drill 0.2032)
		(layers "F.Cu" "B.Cu")
		(net "ICE_TDO")
	)
	(segment
		(start 126.3777 -82.3341)
		(end 126.3777 -81.822798)
		(width 0.127)
		(layer "B.Cu")
		(net "ICE_TDO")
	)
	(segment
		(start 126.000002 -81.4451)
		(end 126.000002 -81.000092)
		(width 0.127)
		(layer "B.Cu")
		(net "ICE_TDO")
	)
	(segment
		(start 126.3777 -81.822798)
		(end 126.000002 -81.4451)
		(width 0.127)
		(layer "B.Cu")
		(net "ICE_TDO")
	)
	(segment
		(start 122.500136 -76.500228)
		(end 123.000008 -77.0001)
		(width 0.127)
		(layer "F.Cu")
		(net "ICE_TDI")
	)
	(via
		(at 123.000008 -77.0001)
		(size 0.4572)
		(drill 0.2032)
		(layers "F.Cu" "B.Cu")
		(net "ICE_TDI")
	)
	(segment
		(start 123.393708 -79.163418)
		(end 123.393708 -77.836776)
		(width 0.127)
		(layer "B.Cu")
		(net "ICE_TDI")
	)
	(segment
		(start 122.606308 -81.163414)
		(end 122.606308 -79.836772)
		(width 0.127)
		(layer "B.Cu")
		(net "ICE_TDI")
	)
	(segment
		(start 127.3556 -85.344)
		(end 128.366266 -86.354666)
		(width 0.127)
		(layer "B.Cu")
		(net "ICE_TDI")
	)
	(segment
		(start 124.1044 -83.020916)
		(end 124.1044 -82.661506)
		(width 0.127)
		(layer "B.Cu")
		(net "ICE_TDI")
	)
	(segment
		(start 123.119134 -79.437992)
		(end 123.393708 -79.163418)
		(width 0.127)
		(layer "B.Cu")
		(net "ICE_TDI")
	)
	(segment
		(start 123.005088 -79.437992)
		(end 123.119134 -79.437992)
		(width 0.127)
		(layer "B.Cu")
		(net "ICE_TDI")
	)
	(segment
		(start 124.1044 -82.661506)
		(end 122.606308 -81.163414)
		(width 0.127)
		(layer "B.Cu")
		(net "ICE_TDI")
	)
	(segment
		(start 127.3556 -85.344)
		(end 126.56947 -84.55787)
		(width 0.127)
		(layer "B.Cu")
		(net "ICE_TDI")
	)
	(segment
		(start 123.000008 -77.443076)
		(end 123.000008 -77.0001)
		(width 0.127)
		(layer "B.Cu")
		(net "ICE_TDI")
	)
	(segment
		(start 128.366266 -86.354666)
		(end 128.366266 -86.807294)
		(width 0.127)
		(layer "B.Cu")
		(net "ICE_TDI")
	)
	(segment
		(start 122.606308 -79.836772)
		(end 123.005088 -79.437992)
		(width 0.127)
		(layer "B.Cu")
		(net "ICE_TDI")
	)
	(segment
		(start 123.393708 -77.836776)
		(end 123.000008 -77.443076)
		(width 0.127)
		(layer "B.Cu")
		(net "ICE_TDI")
	)
	(segment
		(start 125.641354 -84.55787)
		(end 124.1044 -83.020916)
		(width 0.127)
		(layer "B.Cu")
		(net "ICE_TDI")
	)
	(segment
		(start 126.56947 -84.55787)
		(end 125.641354 -84.55787)
		(width 0.127)
		(layer "B.Cu")
		(net "ICE_TDI")
	)
	(segment
		(start 119.500142 -73.500234)
		(end 120.000014 -74.000106)
		(width 0.127)
		(layer "F.Cu")
		(net "ICE_TCK")
	)
	(via
		(at 120.000014 -74.000106)
		(size 0.4572)
		(drill 0.2032)
		(layers "F.Cu" "B.Cu")
		(net "ICE_TCK")
	)
	(segment
		(start 120.332246 -88.630506)
		(end 120.523 -88.82126)
		(width 0.127)
		(layer "B.Cu")
		(net "ICE_TCK")
	)
	(segment
		(start 118.999 -84.709)
		(end 118.54815 -84.25815)
		(width 0.127)
		(layer "B.Cu")
		(net "ICE_TCK")
	)
	(segment
		(start 120.4976 -75.4126)
		(end 120.4976 -74.497692)
		(width 0.127)
		(layer "B.Cu")
		(net "ICE_TCK")
	)
	(segment
		(start 119.4308 -85.1408)
		(end 119.4308 -87.01786)
		(width 0.127)
		(layer "B.Cu")
		(net "ICE_TCK")
	)
	(segment
		(start 120.90146 -90.0049)
		(end 121.2596 -90.0049)
		(width 0.127)
		(layer "B.Cu")
		(net "ICE_TCK")
	)
	(segment
		(start 118.334282 -81.543144)
		(end 118.54815 -81.329276)
		(width 0.127)
		(layer "B.Cu")
		(net "ICE_TCK")
	)
	(segment
		(start 119.517414 -78.084934)
		(end 119.517414 -75.7174)
		(width 0.127)
		(layer "B.Cu")
		(net "ICE_TCK")
	)
	(segment
		(start 120.332246 -87.919306)
		(end 120.332246 -88.630506)
		(width 0.127)
		(layer "B.Cu")
		(net "ICE_TCK")
	)
	(segment
		(start 118.54815 -82.980022)
		(end 118.334282 -82.766154)
		(width 0.127)
		(layer "B.Cu")
		(net "ICE_TCK")
	)
	(segment
		(start 118.54815 -78.725776)
		(end 118.774972 -78.498954)
		(width 0.127)
		(layer "B.Cu")
		(net "ICE_TCK")
	)
	(segment
		(start 118.774972 -78.498954)
		(end 119.103394 -78.498954)
		(width 0.127)
		(layer "B.Cu")
		(net "ICE_TCK")
	)
	(segment
		(start 120.3198 -75.5904)
		(end 120.4976 -75.4126)
		(width 0.127)
		(layer "B.Cu")
		(net "ICE_TCK")
	)
	(segment
		(start 118.334282 -82.766154)
		(end 118.334282 -81.543144)
		(width 0.127)
		(layer "B.Cu")
		(net "ICE_TCK")
	)
	(segment
		(start 119.644414 -75.5904)
		(end 120.3198 -75.5904)
		(width 0.127)
		(layer "B.Cu")
		(net "ICE_TCK")
	)
	(segment
		(start 120.523 -88.82126)
		(end 120.523 -89.62644)
		(width 0.127)
		(layer "B.Cu")
		(net "ICE_TCK")
	)
	(segment
		(start 118.54815 -81.329276)
		(end 118.54815 -78.725776)
		(width 0.127)
		(layer "B.Cu")
		(net "ICE_TCK")
	)
	(segment
		(start 118.54815 -84.25815)
		(end 118.54815 -82.980022)
		(width 0.127)
		(layer "B.Cu")
		(net "ICE_TCK")
	)
	(segment
		(start 120.4976 -74.497692)
		(end 120.000014 -74.000106)
		(width 0.127)
		(layer "B.Cu")
		(net "ICE_TCK")
	)
	(segment
		(start 120.523 -89.62644)
		(end 120.90146 -90.0049)
		(width 0.127)
		(layer "B.Cu")
		(net "ICE_TCK")
	)
	(segment
		(start 119.103394 -78.498954)
		(end 119.517414 -78.084934)
		(width 0.127)
		(layer "B.Cu")
		(net "ICE_TCK")
	)
	(segment
		(start 119.4308 -87.01786)
		(end 120.332246 -87.919306)
		(width 0.127)
		(layer "B.Cu")
		(net "ICE_TCK")
	)
	(segment
		(start 118.999 -84.709)
		(end 119.4308 -85.1408)
		(width 0.127)
		(layer "B.Cu")
		(net "ICE_TCK")
	)
	(segment
		(start 119.517414 -75.7174)
		(end 119.644414 -75.5904)
		(width 0.127)
		(layer "B.Cu")
		(net "ICE_TCK")
	)
	(segment
		(start 167.39997 -42.800016)
		(end 167.799766 -43.199812)
		(width 0.127)
		(layer "F.Cu")
		(net "ICE_SEL")
	)
	(via
		(at 167.799766 -43.199812)
		(size 0.508)
		(drill 0.254)
		(layers "F.Cu" "B.Cu")
		(net "ICE_SEL")
	)
	(segment
		(start 167.799766 -43.387772)
		(end 167.799766 -43.199812)
		(width 0.127)
		(layer "B.Cu")
		(net "ICE_SEL")
	)
	(segment
		(start 166.245286 -49.733454)
		(end 166.245286 -48.420274)
		(width 0.127)
		(layer "B.Cu")
		(net "ICE_SEL")
	)
	(segment
		(start 165.537388 -50.441352)
		(end 166.624 -51.527964)
		(width 0.127)
		(layer "B.Cu")
		(net "ICE_SEL")
	)
	(segment
		(start 166.624 -51.527964)
		(end 166.624 -51.6255)
		(width 0.127)
		(layer "B.Cu")
		(net "ICE_SEL")
	)
	(segment
		(start 166.245286 -48.420274)
		(end 167.34917 -47.31639)
		(width 0.127)
		(layer "B.Cu")
		(net "ICE_SEL")
	)
	(segment
		(start 167.34917 -43.838368)
		(end 167.799766 -43.387772)
		(width 0.127)
		(layer "B.Cu")
		(net "ICE_SEL")
	)
	(segment
		(start 165.537388 -50.441352)
		(end 166.245286 -49.733454)
		(width 0.127)
		(layer "B.Cu")
		(net "ICE_SEL")
	)
	(segment
		(start 167.34917 -47.31639)
		(end 167.34917 -43.838368)
		(width 0.127)
		(layer "B.Cu")
		(net "ICE_SEL")
	)
	(segment
		(start 173.713902 -54.181502)
		(end 173.800008 -54.095396)
		(width 0.3556)
		(layer "F.Cu")
		(net "HM40ADC_VDDA")
	)
	(segment
		(start 173.800008 -54.095396)
		(end 173.800008 -51.599846)
		(width 0.3556)
		(layer "F.Cu")
		(net "HM40ADC_VDDA")
	)
	(via
		(at 166.732458 -57.459118)
		(size 0.6096)
		(drill 0.3048)
		(layers "F.Cu" "B.Cu")
		(net "HM40ADC_VDDA")
	)
	(via
		(at 173.713902 -54.181502)
		(size 0.508)
		(drill 0.254)
		(layers "F.Cu" "B.Cu")
		(net "HM40ADC_VDDA")
	)
	(segment
		(start 171.6786 -56.1594)
		(end 168.032176 -56.1594)
		(width 0.508)
		(layer "B.Cu")
		(net "HM40ADC_VDDA")
	)
	(segment
		(start 165.4556 -59.3598)
		(end 165.4556 -58.735976)
		(width 0.508)
		(layer "B.Cu")
		(net "HM40ADC_VDDA")
	)
	(segment
		(start 168.032176 -56.1594)
		(end 166.732458 -57.459118)
		(width 0.508)
		(layer "B.Cu")
		(net "HM40ADC_VDDA")
	)
	(segment
		(start 173.713902 -54.181502)
		(end 171.829476 -56.065928)
		(width 0.508)
		(layer "B.Cu")
		(net "HM40ADC_VDDA")
	)
	(segment
		(start 171.772072 -56.065928)
		(end 171.6786 -56.1594)
		(width 0.508)
		(layer "B.Cu")
		(net "HM40ADC_VDDA")
	)
	(segment
		(start 165.4556 -58.735976)
		(end 166.732458 -57.459118)
		(width 0.508)
		(layer "B.Cu")
		(net "HM40ADC_VDDA")
	)
	(segment
		(start 171.829476 -56.065928)
		(end 171.772072 -56.065928)
		(width 0.508)
		(layer "B.Cu")
		(net "HM40ADC_VDDA")
	)
	(segment
		(start 181.799992 -34.800032)
		(end 182.599838 -35.599878)
		(width 0.3556)
		(layer "F.Cu")
		(net "GND")
	)
	(segment
		(start 173.800008 -29.99994)
		(end 173.800008 -30.000194)
		(width 0.3048)
		(layer "F.Cu")
		(net "GND")
	)
	(segment
		(start 101.499924 -54.500018)
		(end 101.000052 -54.000146)
		(width 0.4572)
		(layer "F.Cu")
		(net "GND")
	)
	(segment
		(start 171.399962 -39.59987)
		(end 171.399454 -39.59987)
		(width 0.3556)
		(layer "F.Cu")
		(net "GND")
	)
	(segment
		(start 179.399946 -34.800032)
		(end 179.00015 -34.400236)
		(width 0.3556)
		(layer "F.Cu")
		(net "GND")
	)
	(segment
		(start 104.499918 -64.500252)
		(end 104.499918 -64.499998)
		(width 0.4572)
		(layer "F.Cu")
		(net "GND")
	)
	(segment
		(start 172.999908 -37.199824)
		(end 173.399958 -37.599874)
		(width 0.3556)
		(layer "F.Cu")
		(net "GND")
	)
	(segment
		(start 113.500154 -57.500012)
		(end 114.000026 -57.00014)
		(width 0.4572)
		(layer "F.Cu")
		(net "GND")
	)
	(segment
		(start 93.7387 -73.152)
		(end 93.149674 -73.152)
		(width 0.508)
		(layer "F.Cu")
		(net "GND")
	)
	(segment
		(start 113.4999 -59.500008)
		(end 112.499902 -60.500006)
		(width 0.4572)
		(layer "F.Cu")
		(net "GND")
	)
	(segment
		(start 191.444372 -76.61148)
		(end 191.573658 -76.482194)
		(width 0.508)
		(layer "F.Cu")
		(net "GND")
	)
	(segment
		(start 7.098538 -85.319108)
		(end 7.0993 -85.31987)
		(width 0.508)
		(layer "F.Cu")
		(net "GND")
	)
	(segment
		(start 169.800016 -43.599862)
		(end 170.199812 -43.999658)
		(width 0.3556)
		(layer "F.Cu")
		(net "GND")
	)
	(segment
		(start 153.67508 -85.775292)
		(end 154.915108 -85.775292)
		(width 0.3048)
		(layer "F.Cu")
		(net "GND")
	)
	(segment
		(start 131.438142 -75.50023)
		(end 130.50012 -75.50023)
		(width 0.254)
		(layer "F.Cu")
		(net "GND")
	)
	(segment
		(start 55.499 -81.3308)
		(end 55.499 -80.6577)
		(width 0.508)
		(layer "F.Cu")
		(net "GND")
	)
	(segment
		(start 167.39997 -31.599886)
		(end 166.99992 -31.199836)
		(width 0.3048)
		(layer "F.Cu")
		(net "GND")
	)
	(segment
		(start 180.199792 -41.199816)
		(end 179.799742 -40.799766)
		(width 0.3556)
		(layer "F.Cu")
		(net "GND")
	)
	(segment
		(start 52.7431 -74.2569)
		(end 52.7304 -74.2696)
		(width 0.508)
		(layer "F.Cu")
		(net "GND")
	)
	(segment
		(start 58.7375 -19.1135)
		(end 58.7375 -18.542)
		(width 0.381)
		(layer "F.Cu")
		(net "GND")
	)
	(segment
		(start 184.199784 -39.59987)
		(end 184.199784 -39.600124)
		(width 0.3556)
		(layer "F.Cu")
		(net "GND")
	)
	(segment
		(start 171.399962 -34.800032)
		(end 171.3992 -34.800032)
		(width 0.3556)
		(layer "F.Cu")
		(net "GND")
	)
	(segment
		(start 168.999916 -33.999932)
		(end 168.999154 -33.999932)
		(width 0.3556)
		(layer "F.Cu")
		(net "GND")
	)
	(segment
		(start 124.500132 -58.50001)
		(end 124.500132 -58.500264)
		(width 0.4572)
		(layer "F.Cu")
		(net "GND")
	)
	(segment
		(start 117.500146 -64.499998)
		(end 116.500148 -63.5)
		(width 0.4572)
		(layer "F.Cu")
		(net "GND")
	)
	(segment
		(start 116.000022 -59.000136)
		(end 116.500148 -58.50001)
		(width 0.4572)
		(layer "F.Cu")
		(net "GND")
	)
	(segment
		(start 69.6595 -9.652)
		(end 68.58 -9.652)
		(width 0.508)
		(layer "F.Cu")
		(net "GND")
	)
	(segment
		(start 170.600624 -48.399954)
		(end 171.40047 -49.1998)
		(width 0.3556)
		(layer "F.Cu")
		(net "GND")
	)
	(segment
		(start 198.53656 -70.77964)
		(end 197.72376 -70.77964)
		(width 0.508)
		(layer "F.Cu")
		(net "GND")
	)
	(segment
		(start 174.5996 -49.9999)
		(end 174.199804 -50.399696)
		(width 0.3556)
		(layer "F.Cu")
		(net "GND")
	)
	(segment
		(start 183.399938 -32.399986)
		(end 183.399938 -32.399732)
		(width 0.3556)
		(layer "F.Cu")
		(net "GND")
	)
	(segment
		(start 171.399962 -45.999908)
		(end 171.800266 -46.400212)
		(width 0.3556)
		(layer "F.Cu")
		(net "GND")
	)
	(segment
		(start 107.499912 -74.499978)
		(end 107.00004 -74.000106)
		(width 0.4572)
		(layer "F.Cu")
		(net "GND")
	)
	(segment
		(start 170.599862 -33.209484)
		(end 170.209464 -33.599882)
		(width 0.3556)
		(layer "F.Cu")
		(net "GND")
	)
	(segment
		(start 159.0802 -117.54104)
		(end 158.69158 -117.15242)
		(width 0.508)
		(layer "F.Cu")
		(net "GND")
	)
	(segment
		(start 174.599854 -41.999916)
		(end 174.999904 -42.399966)
		(width 0.3556)
		(layer "F.Cu")
		(net "GND")
	)
	(segment
		(start 181.799992 -32.399986)
		(end 182.199788 -32.799782)
		(width 0.3556)
		(layer "F.Cu")
		(net "GND")
	)
	(segment
		(start 110.499906 -60.500006)
		(end 110.499906 -60.50026)
		(width 0.4572)
		(layer "F.Cu")
		(net "GND")
	)
	(segment
		(start 173.800008 -36.399978)
		(end 173.799754 -36.399978)
		(width 0.3556)
		(layer "F.Cu")
		(net "GND")
	)
	(segment
		(start 180.999892 -44.399454)
		(end 181.399688 -43.999658)
		(width 0.3556)
		(layer "F.Cu")
		(net "GND")
	)
	(segment
		(start 180.999638 -34.800032)
		(end 180.199792 -35.599878)
		(width 0.3556)
		(layer "F.Cu")
		(net "GND")
	)
	(segment
		(start 85.8266 -108.6485)
		(end 85.8266 -109.5248)
		(width 0.508)
		(layer "F.Cu")
		(net "GND")
	)
	(segment
		(start 12.4333 -86.384892)
		(end 12.56411 -86.515702)
		(width 0.3556)
		(layer "F.Cu")
		(net "GND")
	)
	(segment
		(start 170.40098 -29.89199)
		(end 170.397932 -29.888942)
		(width 0.3048)
		(layer "F.Cu")
		(net "GND")
	)
	(segment
		(start 177.8 -49.1998)
		(end 177.39995 -48.79975)
		(width 0.3556)
		(layer "F.Cu")
		(net "GND")
	)
	(segment
		(start 172.200316 -46.800008)
		(end 172.599858 -46.400466)
		(width 0.3556)
		(layer "F.Cu")
		(net "GND")
	)
	(segment
		(start 116.000022 -66.000122)
		(end 116.500148 -65.499996)
		(width 0.4064)
		(layer "F.Cu")
		(net "GND")
	)
	(segment
		(start 178.599846 -35.599878)
		(end 178.199796 -35.199828)
		(width 0.3556)
		(layer "F.Cu")
		(net "GND")
	)
	(segment
		(start 110.000034 -67.000374)
		(end 110.499906 -67.500246)
		(width 0.4064)
		(layer "F.Cu")
		(net "GND")
	)
	(segment
		(start 186.83478 -108.70692)
		(end 186.83478 -107.88904)
		(width 0.508)
		(layer "F.Cu")
		(net "GND")
	)
	(segment
		(start 168.199816 -38.800024)
		(end 168.599612 -39.19982)
		(width 0.3556)
		(layer "F.Cu")
		(net "GND")
	)
	(segment
		(start 62.4332 -70.9168)
		(end 62.3062 -71.0438)
		(width 0.508)
		(layer "F.Cu")
		(net "GND")
	)
	(segment
		(start 178.08448 -110.20298)
		(end 178.08448 -109.37748)
		(width 0.508)
		(layer "F.Cu")
		(net "GND")
	)
	(segment
		(start 99.499928 -53.50002)
		(end 99.000056 -53.000148)
		(width 0.508)
		(layer "F.Cu")
		(net "GND")
	)
	(segment
		(start 166.59987 -45.999908)
		(end 166.599616 -45.999908)
		(width 0.3556)
		(layer "F.Cu")
		(net "GND")
	)
	(segment
		(start 168.999408 -43.599862)
		(end 168.599612 -43.999658)
		(width 0.3556)
		(layer "F.Cu")
		(net "GND")
	)
	(segment
		(start 181.799484 -45.199808)
		(end 181.399688 -45.599604)
		(width 0.3556)
		(layer "F.Cu")
		(net "GND")
	)
	(segment
		(start 172.199808 -39.59987)
		(end 172.999908 -40.39997)
		(width 0.3556)
		(layer "F.Cu")
		(net "GND")
	)
	(segment
		(start 169.872406 -29.99994)
		(end 169.800016 -29.99994)
		(width 0.3048)
		(layer "F.Cu")
		(net "GND")
	)
	(segment
		(start 184.999884 -42.800016)
		(end 184.999376 -42.800016)
		(width 0.3556)
		(layer "F.Cu")
		(net "GND")
	)
	(segment
		(start 173.7995 -47.599854)
		(end 173.399704 -47.99965)
		(width 0.3556)
		(layer "F.Cu")
		(net "GND")
	)
	(segment
		(start 177.8 -47.599854)
		(end 177.800254 -47.599854)
		(width 0.3556)
		(layer "F.Cu")
		(net "GND")
	)
	(segment
		(start 177.800254 -45.999908)
		(end 178.20005 -46.399704)
		(width 0.3556)
		(layer "F.Cu")
		(net "GND")
	)
	(segment
		(start 180.999892 -47.599854)
		(end 180.999892 -47.600108)
		(width 0.3556)
		(layer "F.Cu")
		(net "GND")
	)
	(segment
		(start 184.999376 -42.800016)
		(end 184.59958 -42.40022)
		(width 0.3556)
		(layer "F.Cu")
		(net "GND")
	)
	(segment
		(start 7.0993 -86.476586)
		(end 7.23011 -86.607396)
		(width 0.3556)
		(layer "F.Cu")
		(net "GND")
	)
	(segment
		(start 163.2966 -100.4316)
		(end 163.2966 -100.1014)
		(width 0.508)
		(layer "F.Cu")
		(net "GND")
	)
	(segment
		(start 168.199816 -39.599616)
		(end 168.599612 -39.19982)
		(width 0.3556)
		(layer "F.Cu")
		(net "GND")
	)
	(segment
		(start 167.39997 -38.009576)
		(end 166.99992 -38.409626)
		(width 0.3556)
		(layer "F.Cu")
		(net "GND")
	)
	(segment
		(start 176.1998 -45.999908)
		(end 176.1998 -45.999654)
		(width 0.3556)
		(layer "F.Cu")
		(net "GND")
	)
	(segment
		(start 104.499918 -78.500224)
		(end 104.000046 -79.000096)
		(width 0.4572)
		(layer "F.Cu")
		(net "GND")
	)
	(segment
		(start 172.999908 -40.39997)
		(end 173.399958 -40.80002)
		(width 0.3556)
		(layer "F.Cu")
		(net "GND")
	)
	(segment
		(start 62.3062 -71.0438)
		(end 61.6077 -71.0438)
		(width 0.508)
		(layer "F.Cu")
		(net "GND")
	)
	(segment
		(start 17.9451 -85.37067)
		(end 17.9451 -85.852)
		(width 0.508)
		(layer "F.Cu")
		(net "GND")
	)
	(segment
		(start 63.034926 -18.911316)
		(end 63.034926 -20.675346)
		(width 0.3556)
		(layer "F.Cu")
		(net "GND")
	)
	(segment
		(start 172.199808 -48.399954)
		(end 172.199808 -48.3997)
		(width 0.3556)
		(layer "F.Cu")
		(net "GND")
	)
	(segment
		(start 107.499912 -73.500234)
		(end 107.00004 -74.000106)
		(width 0.4572)
		(layer "F.Cu")
		(net "GND")
	)
	(segment
		(start 125.000004 -51.000152)
		(end 125.499876 -51.500024)
		(width 0.4572)
		(layer "F.Cu")
		(net "GND")
	)
	(segment
		(start 162.796474 -45.999908)
		(end 163.399978 -45.999908)
		(width 0.3048)
		(layer "F.Cu")
		(net "GND")
	)
	(segment
		(start 115.50015 -68.500244)
		(end 115.499896 -68.500244)
		(width 0.4064)
		(layer "F.Cu")
		(net "GND")
	)
	(segment
		(start 118.500144 -67.500246)
		(end 118.000018 -68.000372)
		(width 0.4064)
		(layer "F.Cu")
		(net "GND")
	)
	(segment
		(start 168.999916 -41.199816)
		(end 168.999662 -41.199816)
		(width 0.3556)
		(layer "F.Cu")
		(net "GND")
	)
	(segment
		(start 122.00001 -61.000132)
		(end 122.499882 -61.500004)
		(width 0.4572)
		(layer "F.Cu")
		(net "GND")
	)
	(segment
		(start 123.603258 -91.523058)
		(end 124.46 -92.3798)
		(width 0.508)
		(layer "F.Cu")
		(net "GND")
	)
	(segment
		(start 62.2935 -24.13)
		(end 62.2935 -24.9555)
		(width 0.508)
		(layer "F.Cu")
		(net "GND")
	)
	(segment
		(start 161.090864 -6.418072)
		(end 160.580324 -6.418072)
		(width 0.2032)
		(layer "F.Cu")
		(net "GND")
	)
	(segment
		(start 168.999916 -37.199824)
		(end 168.999916 -37.199316)
		(width 0.3556)
		(layer "F.Cu")
		(net "GND")
	)
	(segment
		(start 105.499916 -77.500226)
		(end 105.000044 -78.000098)
		(width 0.4572)
		(layer "F.Cu")
		(net "GND")
	)
	(segment
		(start 122.500136 -54.500018)
		(end 123.000008 -54.000146)
		(width 0.4572)
		(layer "F.Cu")
		(net "GND")
	)
	(segment
		(start 168.999154 -33.999932)
		(end 168.599612 -34.399474)
		(width 0.3556)
		(layer "F.Cu")
		(net "GND")
	)
	(segment
		(start 100.499926 -58.50001)
		(end 100.000054 -58.000138)
		(width 0.4572)
		(layer "F.Cu")
		(net "GND")
	)
	(segment
		(start 176.1998 -46.7995)
		(end 175.800004 -46.399704)
		(width 0.3556)
		(layer "F.Cu")
		(net "GND")
	)
	(segment
		(start 124.500132 -55.500016)
		(end 125.000004 -55.000144)
		(width 0.4572)
		(layer "F.Cu")
		(net "GND")
	)
	(segment
		(start 12.6238 -100.2411)
		(end 12.6238 -99.314)
		(width 0.508)
		(layer "F.Cu")
		(net "GND")
	)
	(segment
		(start 73.27773 -14.749272)
		(end 72.897492 -15.12951)
		(width 0.2032)
		(layer "F.Cu")
		(net "GND")
	)
	(segment
		(start 174.599854 -35.599878)
		(end 174.19955 -35.199574)
		(width 0.3556)
		(layer "F.Cu")
		(net "GND")
	)
	(segment
		(start 176.1998 -34.799778)
		(end 175.799496 -34.399474)
		(width 0.3556)
		(layer "F.Cu")
		(net "GND")
	)
	(segment
		(start 124.500132 -57.500012)
		(end 125.000004 -57.00014)
		(width 0.4572)
		(layer "F.Cu")
		(net "GND")
	)
	(segment
		(start 184.199784 -31.599632)
		(end 183.799988 -31.199836)
		(width 0.3048)
		(layer "F.Cu")
		(net "GND")
	)
	(segment
		(start 111.499904 -71.458582)
		(end 111.499904 -71.500238)
		(width 0.4064)
		(layer "F.Cu")
		(net "GND")
	)
	(segment
		(start 101.499924 -64.499998)
		(end 101.000052 -64.000126)
		(width 0.4572)
		(layer "F.Cu")
		(net "GND")
	)
	(segment
		(start 180.199792 -35.599878)
		(end 180.599842 -35.999928)
		(width 0.3556)
		(layer "F.Cu")
		(net "GND")
	)
	(segment
		(start 168.999916 -48.399954)
		(end 169.00017 -48.399954)
		(width 0.3556)
		(layer "F.Cu")
		(net "GND")
	)
	(segment
		(start 170.599862 -42.799762)
		(end 170.199812 -42.399712)
		(width 0.3556)
		(layer "F.Cu")
		(net "GND")
	)
	(segment
		(start 175.401986 -33.199832)
		(end 175.805592 -32.796226)
		(width 0.3556)
		(layer "F.Cu")
		(net "GND")
	)
	(segment
		(start 124.500132 -59.500008)
		(end 125.000004 -59.000136)
		(width 0.4572)
		(layer "F.Cu")
		(net "GND")
	)
	(segment
		(start 112.499902 -60.50026)
		(end 112.00003 -61.000132)
		(width 0.4572)
		(layer "F.Cu")
		(net "GND")
	)
	(segment
		(start 175.3997 -48.399954)
		(end 174.999904 -48.79975)
		(width 0.3556)
		(layer "F.Cu")
		(net "GND")
	)
	(segment
		(start 177.8 -37.199824)
		(end 177.8 -37.200078)
		(width 0.3556)
		(layer "F.Cu")
		(net "GND")
	)
	(segment
		(start 107.499658 -59.500008)
		(end 106.999532 -58.999882)
		(width 0.4572)
		(layer "F.Cu")
		(net "GND")
	)
	(segment
		(start 174.599854 -45.199808)
		(end 174.599854 -45.200062)
		(width 0.3556)
		(layer "F.Cu")
		(net "GND")
	)
	(segment
		(start 172.199808 -36.399978)
		(end 172.200062 -36.399978)
		(width 0.3556)
		(layer "F.Cu")
		(net "GND")
	)
	(segment
		(start 164.600128 -34.400236)
		(end 164.999924 -34.00044)
		(width 0.3048)
		(layer "F.Cu")
		(net "GND")
	)
	(segment
		(start 6.9215 -80.899)
		(end 5.8674 -80.899)
		(width 0.508)
		(layer "F.Cu")
		(net "GND")
	)
	(segment
		(start 169.800016 -37.199824)
		(end 169.800524 -37.199824)
		(width 0.3556)
		(layer "F.Cu")
		(net "GND")
	)
	(segment
		(start 171.3992 -36.399978)
		(end 170.999658 -36.79952)
		(width 0.3556)
		(layer "F.Cu")
		(net "GND")
	)
	(segment
		(start 105.499916 -57.500012)
		(end 105.000044 -57.00014)
		(width 0.4572)
		(layer "F.Cu")
		(net "GND")
	)
	(segment
		(start 174.599854 -46.000162)
		(end 173.800008 -46.800008)
		(width 0.3556)
		(layer "F.Cu")
		(net "GND")
	)
	(segment
		(start 181.799992 -44.399962)
		(end 181.399688 -43.999658)
		(width 0.3556)
		(layer "F.Cu")
		(net "GND")
	)
	(segment
		(start 183.428132 -56.1213)
		(end 183.520842 -56.21401)
		(width 0.508)
		(layer "F.Cu")
		(net "GND")
	)
	(segment
		(start 180.199792 -34.800032)
		(end 179.399946 -35.599878)
		(width 0.3556)
		(layer "F.Cu")
		(net "GND")
	)
	(segment
		(start 160.580324 -6.418072)
		(end 159.972502 -7.025894)
		(width 0.2032)
		(layer "F.Cu")
		(net "GND")
	)
	(segment
		(start 171.40047 -49.1998)
		(end 171.800266 -48.800004)
		(width 0.3556)
		(layer "F.Cu")
		(net "GND")
	)
	(segment
		(start 128.500124 -53.50002)
		(end 128.999996 -53.000148)
		(width 0.508)
		(layer "F.Cu")
		(net "GND")
	)
	(segment
		(start 163.399978 -41.999916)
		(end 162.954716 -41.999916)
		(width 0.3048)
		(layer "F.Cu")
		(net "GND")
	)
	(segment
		(start 176.999646 -36.399978)
		(end 176.1998 -37.199824)
		(width 0.3556)
		(layer "F.Cu")
		(net "GND")
	)
	(segment
		(start 55.3593 -80.518)
		(end 55.3593 -80.34274)
		(width 0.3556)
		(layer "F.Cu")
		(net "GND")
	)
	(segment
		(start 168.999916 -37.199316)
		(end 169.399712 -36.79952)
		(width 0.3556)
		(layer "F.Cu")
		(net "GND")
	)
	(segment
		(start 180.199538 -40.39997)
		(end 179.799742 -40.799766)
		(width 0.3556)
		(layer "F.Cu")
		(net "GND")
	)
	(segment
		(start 166.59987 -49.9999)
		(end 166.59987 -49.1998)
		(width 0.3556)
		(layer "F.Cu")
		(net "GND")
	)
	(segment
		(start 182.599838 -37.999924)
		(end 182.599584 -37.999924)
		(width 0.3556)
		(layer "F.Cu")
		(net "GND")
	)
	(segment
		(start 183.391556 -46.800008)
		(end 182.990998 -47.200566)
		(width 0.3556)
		(layer "F.Cu")
		(net "GND")
	)
	(segment
		(start 182.599838 -32.399986)
		(end 182.599584 -32.399986)
		(width 0.3556)
		(layer "F.Cu")
		(net "GND")
	)
	(segment
		(start 168.999408 -41.999916)
		(end 168.599612 -42.399712)
		(width 0.3556)
		(layer "F.Cu")
		(net "GND")
	)
	(segment
		(start 173.800008 -33.999932)
		(end 173.800008 -34.000948)
		(width 0.3556)
		(layer "F.Cu")
		(net "GND")
	)
	(segment
		(start 174.599854 -46.800008)
		(end 173.800008 -47.599854)
		(width 0.3556)
		(layer "F.Cu")
		(net "GND")
	)
	(segment
		(start 95.0595 -77.0128)
		(end 95.0595 -75.9968)
		(width 0.508)
		(layer "F.Cu")
		(net "GND")
	)
	(segment
		(start 108.49991 -54.500018)
		(end 108.000038 -54.000146)
		(width 0.4572)
		(layer "F.Cu")
		(net "GND")
	)
	(segment
		(start 108.49991 -67.500246)
		(end 108.337858 -67.338194)
		(width 0.4064)
		(layer "F.Cu")
		(net "GND")
	)
	(segment
		(start 180.199792 -39.59987)
		(end 179.799742 -39.19982)
		(width 0.3556)
		(layer "F.Cu")
		(net "GND")
	)
	(segment
		(start 176.200054 -40.39997)
		(end 176.59985 -40.799766)
		(width 0.3556)
		(layer "F.Cu")
		(net "GND")
	)
	(segment
		(start 124.500132 -71.500238)
		(end 125.000004 -72.00011)
		(width 0.4572)
		(layer "F.Cu")
		(net "GND")
	)
	(segment
		(start 179.399692 -46.800008)
		(end 178.599846 -47.599854)
		(width 0.3556)
		(layer "F.Cu")
		(net "GND")
	)
	(segment
		(start 111.499904 -70.50024)
		(end 111.483394 -70.50024)
		(width 0.4572)
		(layer "F.Cu")
		(net "GND")
	)
	(segment
		(start 182.599838 -42.800016)
		(end 182.599838 -42.799508)
		(width 0.3556)
		(layer "F.Cu")
		(net "GND")
	)
	(segment
		(start 151.515064 -76.019406)
		(end 153.67508 -76.019406)
		(width 0.3048)
		(layer "F.Cu")
		(net "GND")
	)
	(segment
		(start 55.3593 -80.34274)
		(end 55.02656 -80.01)
		(width 0.3556)
		(layer "F.Cu")
		(net "GND")
	)
	(segment
		(start 170.599862 -35.599878)
		(end 170.599862 -35.59937)
		(width 0.3556)
		(layer "F.Cu")
		(net "GND")
	)
	(segment
		(start 119.500142 -71.500238)
		(end 120.000014 -72.00011)
		(width 0.4572)
		(layer "F.Cu")
		(net "GND")
	)
	(segment
		(start 69.37121 -80.168242)
		(end 69.249798 -80.04683)
		(width 0.3556)
		(layer "F.Cu")
		(net "GND")
	)
	(segment
		(start 168.199816 -45.9994)
		(end 168.599612 -45.599604)
		(width 0.3556)
		(layer "F.Cu")
		(net "GND")
	)
	(segment
		(start 117.500146 -59.500008)
		(end 118.000018 -59.000136)
		(width 0.4572)
		(layer "F.Cu")
		(net "GND")
	)
	(segment
		(start 164.999924 -38.009576)
		(end 164.606986 -38.402514)
		(width 0.3556)
		(layer "F.Cu")
		(net "GND")
	)
	(segment
		(start 151.897842 -99.050094)
		(end 152.122378 -99.050094)
		(width 0.3048)
		(layer "F.Cu")
		(net "GND")
	)
	(segment
		(start 171.40047 -46.800008)
		(end 171.800266 -46.400212)
		(width 0.3556)
		(layer "F.Cu")
		(net "GND")
	)
	(segment
		(start 152.586182 -98.58629)
		(end 153.67508 -98.58629)
		(width 0.3048)
		(layer "F.Cu")
		(net "GND")
	)
	(segment
		(start 94.518226 -66.37782)
		(end 93.70314 -66.37782)
		(width 0.508)
		(layer "F.Cu")
		(net "GND")
	)
	(segment
		(start 182.599838 -37.199824)
		(end 182.999888 -37.599874)
		(width 0.3556)
		(layer "F.Cu")
		(net "GND")
	)
	(segment
		(start 177.000408 -31.599886)
		(end 177.400204 -31.20009)
		(width 0.3048)
		(layer "F.Cu")
		(net "GND")
	)
	(segment
		(start 184.199784 -33.200086)
		(end 183.399938 -33.999932)
		(width 0.3556)
		(layer "F.Cu")
		(net "GND")
	)
	(segment
		(start 119.500142 -76.500228)
		(end 120.000014 -77.0001)
		(width 0.4572)
		(layer "F.Cu")
		(net "GND")
	)
	(segment
		(start 120.000014 -68.000118)
		(end 119.500142 -68.49999)
		(width 0.4572)
		(layer "F.Cu")
		(net "GND")
	)
	(segment
		(start 183.399938 -30.80004)
		(end 183.400192 -30.80004)
		(width 0.3048)
		(layer "F.Cu")
		(net "GND")
	)
	(segment
		(start 176.1998 -32.402018)
		(end 175.805592 -32.796226)
		(width 0.3048)
		(layer "F.Cu")
		(net "GND")
	)
	(segment
		(start 121.500138 -64.499998)
		(end 122.00001 -64.000126)
		(width 0.4572)
		(layer "F.Cu")
		(net "GND")
	)
	(segment
		(start 178.599846 -46.7995)
		(end 178.20005 -46.399704)
		(width 0.3556)
		(layer "F.Cu")
		(net "GND")
	)
	(segment
		(start 111.999776 -59.000136)
		(end 112.499902 -58.50001)
		(width 0.4572)
		(layer "F.Cu")
		(net "GND")
	)
	(segment
		(start 168.199816 -39.59987)
		(end 168.199816 -39.599616)
		(width 0.3556)
		(layer "F.Cu")
		(net "GND")
	)
	(segment
		(start 180.999892 -38.800024)
		(end 180.999892 -38.799516)
		(width 0.3556)
		(layer "F.Cu")
		(net "GND")
	)
	(segment
		(start 13.3096 -59.5757)
		(end 13.3096 -60.4012)
		(width 0.508)
		(layer "F.Cu")
		(net "GND")
	)
	(segment
		(start 180.199792 -41.999916)
		(end 179.799742 -42.399966)
		(width 0.3556)
		(layer "F.Cu")
		(net "GND")
	)
	(segment
		(start 180.999892 -41.199816)
		(end 181.399688 -41.599612)
		(width 0.3556)
		(layer "F.Cu")
		(net "GND")
	)
	(segment
		(start 164.234876 -53.56225)
		(end 165.800024 -51.997102)
		(width 0.3556)
		(layer "F.Cu")
		(net "GND")
	)
	(segment
		(start 164.199824 -41.999916)
		(end 164.599874 -41.599866)
		(width 0.3048)
		(layer "F.Cu")
		(net "GND")
	)
	(segment
		(start 179.399946 -43.599862)
		(end 179.399946 -43.600116)
		(width 0.3556)
		(layer "F.Cu")
		(net "GND")
	)
	(segment
		(start 183.400192 -30.80004)
		(end 183.799988 -31.199836)
		(width 0.3048)
		(layer "F.Cu")
		(net "GND")
	)
	(segment
		(start 45.911262 -34.151062)
		(end 45.6692 -33.909)
		(width 0.3048)
		(layer "F.Cu")
		(net "GND")
	)
	(segment
		(start 180.199792 -47.599346)
		(end 180.599588 -47.19955)
		(width 0.3556)
		(layer "F.Cu")
		(net "GND")
	)
	(segment
		(start 8.305546 -48.653192)
		(end 7.302246 -48.653192)
		(width 0.508)
		(layer "F.Cu")
		(net "GND")
	)
	(segment
		(start 12.56411 -86.515702)
		(end 12.56411 -87.377778)
		(width 0.3556)
		(layer "F.Cu")
		(net "GND")
	)
	(segment
		(start 191.703706 -41.676574)
		(end 191.71158 -41.6687)
		(width 0.508)
		(layer "F.Cu")
		(net "GND")
	)
	(segment
		(start 101.499924 -61.500004)
		(end 101.000052 -61.000132)
		(width 0.4572)
		(layer "F.Cu")
		(net "GND")
	)
	(segment
		(start 183.399938 -43.599862)
		(end 182.999888 -43.999912)
		(width 0.3556)
		(layer "F.Cu")
		(net "GND")
	)
	(segment
		(start 181.799992 -33.199578)
		(end 182.199788 -32.799782)
		(width 0.3556)
		(layer "F.Cu")
		(net "GND")
	)
	(segment
		(start 115.50015 -71.499984)
		(end 116.000022 -71.000112)
		(width 0.3556)
		(layer "F.Cu")
		(net "GND")
	)
	(segment
		(start 104.499918 -67.500246)
		(end 104.000046 -68.000118)
		(width 0.4572)
		(layer "F.Cu")
		(net "GND")
	)
	(segment
		(start 167.39997 -38.800024)
		(end 167.390318 -38.800024)
		(width 0.3556)
		(layer "F.Cu")
		(net "GND")
	)
	(segment
		(start 150.9268 -99.1616)
		(end 151.038306 -99.050094)
		(width 0.508)
		(layer "F.Cu")
		(net "GND")
	)
	(segment
		(start 172.200062 -42.800016)
		(end 172.999908 -43.599862)
		(width 0.3556)
		(layer "F.Cu")
		(net "GND")
	)
	(segment
		(start 86.513924 -66.422524)
		(end 86.233 -66.1416)
		(width 0.2032)
		(layer "F.Cu")
		(net "GND")
	)
	(segment
		(start 173.800008 -47.599854)
		(end 173.7995 -47.599854)
		(width 0.3556)
		(layer "F.Cu")
		(net "GND")
	)
	(segment
		(start 45.6692 -33.909)
		(end 45.1612 -33.401)
		(width 0.3048)
		(layer "F.Cu")
		(net "GND")
	)
	(segment
		(start 170.599862 -41.20007)
		(end 169.800016 -41.999916)
		(width 0.3556)
		(layer "F.Cu")
		(net "GND")
	)
	(segment
		(start 63.27013 -71.051928)
		(end 63.211202 -70.993)
		(width 0.508)
		(layer "F.Cu")
		(net "GND")
	)
	(segment
		(start 151.710898 -72.140318)
		(end 150.88235 -72.140318)
		(width 0.508)
		(layer "F.Cu")
		(net "GND")
	)
	(segment
		(start 170.8912 -111.463328)
		(end 170.8912 -112.3696)
		(width 0.508)
		(layer "F.Cu")
		(net "GND")
	)
	(segment
		(start 182.600092 -40.39997)
		(end 182.999888 -40.799766)
		(width 0.3556)
		(layer "F.Cu")
		(net "GND")
	)
	(segment
		(start 160.7312 -87.5919)
		(end 160.7566 -87.6173)
		(width 0.508)
		(layer "F.Cu")
		(net "GND")
	)
	(segment
		(start 75.564492 -76.447142)
		(end 75.564492 -77.314806)
		(width 0.381)
		(layer "F.Cu")
		(net "GND")
	)
	(segment
		(start 111.500158 -63.5)
		(end 111.499904 -63.5)
		(width 0.4572)
		(layer "F.Cu")
		(net "GND")
	)
	(segment
		(start 123.500134 -66.499994)
		(end 124.000006 -66.000122)
		(width 0.4572)
		(layer "F.Cu")
		(net "GND")
	)
	(segment
		(start 176.1998 -34.800032)
		(end 176.1998 -34.799778)
		(width 0.3556)
		(layer "F.Cu")
		(net "GND")
	)
	(segment
		(start 59.817 -80.5307)
		(end 59.7789 -80.4926)
		(width 0.508)
		(layer "F.Cu")
		(net "GND")
	)
	(segment
		(start 186.599322 -42.800016)
		(end 186.199526 -42.40022)
		(width 0.3556)
		(layer "F.Cu")
		(net "GND")
	)
	(segment
		(start 178.599846 -44.399962)
		(end 178.199796 -43.999912)
		(width 0.3556)
		(layer "F.Cu")
		(net "GND")
	)
	(segment
		(start 100.499926 -55.500016)
		(end 100.000054 -55.000144)
		(width 0.4572)
		(layer "F.Cu")
		(net "GND")
	)
	(segment
		(start 109.500162 -57.500012)
		(end 110.000034 -57.00014)
		(width 0.4572)
		(layer "F.Cu")
		(net "GND")
	)
	(segment
		(start 174.600108 -40.39997)
		(end 174.999904 -40.799766)
		(width 0.3556)
		(layer "F.Cu")
		(net "GND")
	)
	(segment
		(start 84.25942 -73.69175)
		(end 84.5185 -73.43267)
		(width 0.508)
		(layer "F.Cu")
		(net "GND")
	)
	(segment
		(start 106.499914 -54.500018)
		(end 106.000042 -54.000146)
		(width 0.4572)
		(layer "F.Cu")
		(net "GND")
	)
	(segment
		(start 123.500134 -63.5)
		(end 124.000006 -63.000128)
		(width 0.4572)
		(layer "F.Cu")
		(net "GND")
	)
	(segment
		(start 177.799746 -33.199832)
		(end 177.39995 -32.800036)
		(width 0.3556)
		(layer "F.Cu")
		(net "GND")
	)
	(segment
		(start 177.8 -33.999932)
		(end 177.39995 -34.399982)
		(width 0.3556)
		(layer "F.Cu")
		(net "GND")
	)
	(segment
		(start 160.7185 -74.21753)
		(end 160.7185 -73.34123)
		(width 0.508)
		(layer "F.Cu")
		(net "GND")
	)
	(segment
		(start 182.599838 -43.599862)
		(end 182.999888 -43.999912)
		(width 0.3556)
		(layer "F.Cu")
		(net "GND")
	)
	(segment
		(start 103.49992 -76.500228)
		(end 103.000048 -77.0001)
		(width 0.4572)
		(layer "F.Cu")
		(net "GND")
	)
	(segment
		(start 113.4999 -57.500012)
		(end 113.500154 -57.500012)
		(width 0.4572)
		(layer "F.Cu")
		(net "GND")
	)
	(segment
		(start 160.7312 -76.934314)
		(end 160.7312 -77.4954)
		(width 0.508)
		(layer "F.Cu")
		(net "GND")
	)
	(segment
		(start 183.39943 -41.999916)
		(end 182.999634 -42.399712)
		(width 0.3556)
		(layer "F.Cu")
		(net "GND")
	)
	(segment
		(start 177.8 -44.399962)
		(end 177.8 -44.399708)
		(width 0.3556)
		(layer "F.Cu")
		(net "GND")
	)
	(segment
		(start 168.999916 -43.599862)
		(end 168.999408 -43.599862)
		(width 0.3556)
		(layer "F.Cu")
		(net "GND")
	)
	(segment
		(start 69.6595 -7.366)
		(end 68.58 -7.366)
		(width 0.508)
		(layer "F.Cu")
		(net "GND")
	)
	(segment
		(start 171.318428 -29.99994)
		(end 171.210478 -29.89199)
		(width 0.3048)
		(layer "F.Cu")
		(net "GND")
	)
	(segment
		(start 122.499882 -67.500246)
		(end 122.500136 -67.500246)
		(width 0.4572)
		(layer "F.Cu")
		(net "GND")
	)
	(segment
		(start 115.50015 -68.500244)
		(end 116.000022 -68.000372)
		(width 0.4064)
		(layer "F.Cu")
		(net "GND")
	)
	(segment
		(start 103.441246 -57.441338)
		(end 103.49992 -57.500012)
		(width 0.4572)
		(layer "F.Cu")
		(net "GND")
	)
	(segment
		(start 179.399946 -34.00044)
		(end 179.00015 -34.400236)
		(width 0.3556)
		(layer "F.Cu")
		(net "GND")
	)
	(segment
		(start 101.499924 -74.500232)
		(end 101.000052 -75.000104)
		(width 0.4572)
		(layer "F.Cu")
		(net "GND")
	)
	(segment
		(start 20.867624 -101.588824)
		(end 20.35937 -101.08057)
		(width 0.4064)
		(layer "F.Cu")
		(net "GND")
	)
	(segment
		(start 164.203634 -36.399978)
		(end 164.199824 -36.399978)
		(width 0.3048)
		(layer "F.Cu")
		(net "GND")
	)
	(segment
		(start 66.22288 -94.44736)
		(end 66.441574 -94.228666)
		(width 0.508)
		(layer "F.Cu")
		(net "GND")
	)
	(segment
		(start 164.999924 -44.399708)
		(end 165.800024 -43.599608)
		(width 0.3556)
		(layer "F.Cu")
		(net "GND")
	)
	(segment
		(start 176.1998 -35.599878)
		(end 175.79975 -35.199828)
		(width 0.3556)
		(layer "F.Cu")
		(net "GND")
	)
	(segment
		(start 99.499928 -52.500022)
		(end 99.000056 -52.00015)
		(width 0.508)
		(layer "F.Cu")
		(net "GND")
	)
	(segment
		(start 169.399966 -29.59989)
		(end 169.800016 -29.99994)
		(width 0.3048)
		(layer "F.Cu")
		(net "GND")
	)
	(segment
		(start 120.000014 -64.000126)
		(end 119.500142 -63.500254)
		(width 0.4572)
		(layer "F.Cu")
		(net "GND")
	)
	(segment
		(start 20.35937 -101.08057)
		(end 19.623278 -101.08057)
		(width 0.4064)
		(layer "F.Cu")
		(net "GND")
	)
	(segment
		(start 37.8714 -34.671)
		(end 37.0586 -34.671)
		(width 0.508)
		(layer "F.Cu")
		(net "GND")
	)
	(segment
		(start 168.199816 -43.599862)
		(end 168.599612 -43.999658)
		(width 0.3048)
		(layer "F.Cu")
		(net "GND")
	)
	(segment
		(start 180.199792 -48.399954)
		(end 180.2003 -48.399954)
		(width 0.3556)
		(layer "F.Cu")
		(net "GND")
	)
	(segment
		(start 181.799992 -47.599854)
		(end 181.799738 -47.599854)
		(width 0.3048)
		(layer "F.Cu")
		(net "GND")
	)
	(segment
		(start 122.3645 -93.1672)
		(end 123.2154 -93.1672)
		(width 0.508)
		(layer "F.Cu")
		(net "GND")
	)
	(segment
		(start 122.499882 -65.499996)
		(end 122.500136 -65.499996)
		(width 0.4572)
		(layer "F.Cu")
		(net "GND")
	)
	(segment
		(start 120.50014 -60.500006)
		(end 120.000014 -61.000132)
		(width 0.4572)
		(layer "F.Cu")
		(net "GND")
	)
	(segment
		(start 90.9955 -87.0839)
		(end 91.2876 -87.376)
		(width 0.508)
		(layer "F.Cu")
		(net "GND")
	)
	(segment
		(start 180.999892 -49.1998)
		(end 180.999892 -49.199546)
		(width 0.3556)
		(layer "F.Cu")
		(net "GND")
	)
	(segment
		(start 176.200054 -49.1998)
		(end 176.9999 -48.399954)
		(width 0.3048)
		(layer "F.Cu")
		(net "GND")
	)
	(segment
		(start 115.000278 -71.000366)
		(end 115.000278 -71.000112)
		(width 0.3556)
		(layer "F.Cu")
		(net "GND")
	)
	(segment
		(start 169.800016 -44.399962)
		(end 169.800016 -44.399454)
		(width 0.3556)
		(layer "F.Cu")
		(net "GND")
	)
	(segment
		(start 110.000034 -61.000132)
		(end 109.500162 -61.500004)
		(width 0.4572)
		(layer "F.Cu")
		(net "GND")
	)
	(segment
		(start 184.199784 -38.000178)
		(end 183.399938 -38.800024)
		(width 0.3556)
		(layer "F.Cu")
		(net "GND")
	)
	(segment
		(start 174.599854 -47.600108)
		(end 173.800008 -48.399954)
		(width 0.3556)
		(layer "F.Cu")
		(net "GND")
	)
	(segment
		(start 192.29832 -54.4068)
		(end 193.22161 -54.4068)
		(width 0.508)
		(layer "F.Cu")
		(net "GND")
	)
	(segment
		(start 168.999916 -33.199832)
		(end 169.800016 -33.999932)
		(width 0.3048)
		(layer "F.Cu")
		(net "GND")
	)
	(segment
		(start 83.278472 -73.69175)
		(end 84.25942 -73.69175)
		(width 0.508)
		(layer "F.Cu")
		(net "GND")
	)
	(segment
		(start 127.500126 -74.500232)
		(end 127.999998 -75.000104)
		(width 0.4572)
		(layer "F.Cu")
		(net "GND")
	)
	(segment
		(start 180.999384 -46.799754)
		(end 180.999892 -46.799754)
		(width 0.3556)
		(layer "F.Cu")
		(net "GND")
	)
	(segment
		(start 169.799762 -45.199808)
		(end 168.999916 -44.399962)
		(width 0.3556)
		(layer "F.Cu")
		(net "GND")
	)
	(segment
		(start 170.599862 -40.399462)
		(end 170.999658 -39.999666)
		(width 0.3556)
		(layer "F.Cu")
		(net "GND")
	)
	(segment
		(start 127.500126 -64.499998)
		(end 127.999998 -64.000126)
		(width 0.4572)
		(layer "F.Cu")
		(net "GND")
	)
	(segment
		(start 131.445 -75.493372)
		(end 131.438142 -75.50023)
		(width 0.254)
		(layer "F.Cu")
		(net "GND")
	)
	(segment
		(start 184.199784 -49.1998)
		(end 184.59958 -48.800004)
		(width 0.3556)
		(layer "F.Cu")
		(net "GND")
	)
	(segment
		(start 170.599862 -43.599862)
		(end 170.599608 -43.599862)
		(width 0.254)
		(layer "F.Cu")
		(net "GND")
	)
	(segment
		(start 109.499908 -66.500248)
		(end 110.000034 -67.000374)
		(width 0.4064)
		(layer "F.Cu")
		(net "GND")
	)
	(segment
		(start 170.600116 -34.800032)
		(end 170.999658 -35.199574)
		(width 0.3556)
		(layer "F.Cu")
		(net "GND")
	)
	(segment
		(start 169.800016 -41.999916)
		(end 170.199812 -42.399712)
		(width 0.3556)
		(layer "F.Cu")
		(net "GND")
	)
	(segment
		(start 166.19982 -28.79979)
		(end 165.800024 -29.199586)
		(width 0.3048)
		(layer "F.Cu")
		(net "GND")
	)
	(segment
		(start 115.000278 -71.000112)
		(end 115.50015 -70.50024)
		(width 0.3556)
		(layer "F.Cu")
		(net "GND")
	)
	(segment
		(start 120.000014 -72.00011)
		(end 120.499886 -71.500238)
		(width 0.4572)
		(layer "F.Cu")
		(net "GND")
	)
	(segment
		(start 114.499898 -61.500004)
		(end 114.000026 -61.000132)
		(width 0.4572)
		(layer "F.Cu")
		(net "GND")
	)
	(segment
		(start 176.9999 -42.800016)
		(end 176.59985 -42.399966)
		(width 0.3556)
		(layer "F.Cu")
		(net "GND")
	)
	(segment
		(start 115.50015 -61.500004)
		(end 116.000022 -61.000132)
		(width 0.4572)
		(layer "F.Cu")
		(net "GND")
	)
	(segment
		(start 176.1998 -43.599862)
		(end 176.59985 -43.999912)
		(width 0.3556)
		(layer "F.Cu")
		(net "GND")
	)
	(segment
		(start 107.499912 -70.50024)
		(end 107.00004 -71.000112)
		(width 0.4572)
		(layer "F.Cu")
		(net "GND")
	)
	(segment
		(start 154.915108 -85.775292)
		(end 155.1305 -85.5599)
		(width 0.3048)
		(layer "F.Cu")
		(net "GND")
	)
	(segment
		(start 173.800008 -34.800032)
		(end 174.19955 -35.199574)
		(width 0.3556)
		(layer "F.Cu")
		(net "GND")
	)
	(segment
		(start 122.536458 -91.039696)
		(end 123.603258 -91.039696)
		(width 0.508)
		(layer "F.Cu")
		(net "GND")
	)
	(segment
		(start 106.499914 -59.500008)
		(end 106.499914 -59.4995)
		(width 0.4572)
		(layer "F.Cu")
		(net "GND")
	)
	(segment
		(start 93.570806 -66.410586)
		(end 93.653356 -66.328036)
		(width 0.508)
		(layer "F.Cu")
		(net "GND")
	)
	(segment
		(start 176.1998 -33.190434)
		(end 175.805592 -32.796226)
		(width 0.3556)
		(layer "F.Cu")
		(net "GND")
	)
	(segment
		(start 177.8 -37.200078)
		(end 178.199796 -37.599874)
		(width 0.3556)
		(layer "F.Cu")
		(net "GND")
	)
	(segment
		(start 86.806278 -53.608224)
		(end 86.806278 -54.753002)
		(width 0.508)
		(layer "F.Cu")
		(net "GND")
	)
	(segment
		(start 58.081926 -20.675346)
		(end 58.081926 -19.769074)
		(width 0.381)
		(layer "F.Cu")
		(net "GND")
	)
	(segment
		(start 163.6014 -28.399994)
		(end 164.199824 -28.399994)
		(width 0.3048)
		(layer "F.Cu")
		(net "GND")
	)
	(segment
		(start 80.6958 -69.9516)
		(end 80.6958 -70.178168)
		(width 0.2032)
		(layer "F.Cu")
		(net "GND")
	)
	(segment
		(start 173.800008 -49.9999)
		(end 174.199804 -50.399696)
		(width 0.3556)
		(layer "F.Cu")
		(net "GND")
	)
	(segment
		(start 76.10729 -75.904344)
		(end 75.564492 -76.447142)
		(width 0.381)
		(layer "F.Cu")
		(net "GND")
	)
	(segment
		(start 174.599854 -37.199824)
		(end 174.999904 -37.599874)
		(width 0.3556)
		(layer "F.Cu")
		(net "GND")
	)
	(segment
		(start 172.999908 -34.800032)
		(end 173.000924 -34.800032)
		(width 0.3556)
		(layer "F.Cu")
		(net "GND")
	)
	(segment
		(start 182.599584 -41.999916)
		(end 182.199788 -42.399712)
		(width 0.3556)
		(layer "F.Cu")
		(net "GND")
	)
	(segment
		(start 171.799758 -29.600144)
		(end 172.199554 -29.99994)
		(width 0.3048)
		(layer "F.Cu")
		(net "GND")
	)
	(segment
		(start 176.1998 -49.1998)
		(end 176.200054 -49.1998)
		(width 0.3048)
		(layer "F.Cu")
		(net "GND")
	)
	(segment
		(start 173.11116 -106.54284)
		(end 174.1805 -106.54284)
		(width 0.508)
		(layer "F.Cu")
		(net "GND")
	)
	(segment
		(start 87.6681 -82.2706)
		(end 88.5444 -82.2706)
		(width 0.508)
		(layer "F.Cu")
		(net "GND")
	)
	(segment
		(start 150.8887 -76.64577)
		(end 151.515064 -76.019406)
		(width 0.3048)
		(layer "F.Cu")
		(net "GND")
	)
	(segment
		(start 176.999646 -45.199808)
		(end 176.1998 -44.399962)
		(width 0.3556)
		(layer "F.Cu")
		(net "GND")
	)
	(segment
		(start 177.8 -31.599886)
		(end 177.400204 -31.20009)
		(width 0.3048)
		(layer "F.Cu")
		(net "GND")
	)
	(segment
		(start 176.200054 -38.800024)
		(end 176.59985 -39.19982)
		(width 0.3556)
		(layer "F.Cu")
		(net "GND")
	)
	(segment
		(start 113.4999 -71.500238)
		(end 113.000028 -71.000366)
		(width 0.4064)
		(layer "F.Cu")
		(net "GND")
	)
	(segment
		(start 174.600108 -38.800024)
		(end 174.999904 -39.19982)
		(width 0.3556)
		(layer "F.Cu")
		(net "GND")
	)
	(segment
		(start 164.999924 -31.599886)
		(end 164.600128 -31.20009)
		(width 0.3048)
		(layer "F.Cu")
		(net "GND")
	)
	(segment
		(start 164.606478 -35.997134)
		(end 164.608002 -35.998658)
		(width 0.3048)
		(layer "F.Cu")
		(net "GND")
	)
	(segment
		(start 104.499918 -65.499996)
		(end 104.000046 -65.000124)
		(width 0.4572)
		(layer "F.Cu")
		(net "GND")
	)
	(segment
		(start 109.499908 -64.499998)
		(end 109.99978 -64.99987)
		(width 0.4572)
		(layer "F.Cu")
		(net "GND")
	)
	(segment
		(start 181.799992 -37.199316)
		(end 182.199788 -36.79952)
		(width 0.3556)
		(layer "F.Cu")
		(net "GND")
	)
	(segment
		(start 103.500174 -57.500012)
		(end 104.000046 -57.00014)
		(width 0.4572)
		(layer "F.Cu")
		(net "GND")
	)
	(segment
		(start 103.49992 -57.500012)
		(end 103.500174 -57.500012)
		(width 0.4572)
		(layer "F.Cu")
		(net "GND")
	)
	(segment
		(start 121.500138 -65.499996)
		(end 122.00001 -65.000124)
		(width 0.4572)
		(layer "F.Cu")
		(net "GND")
	)
	(segment
		(start 169.800016 -38.800024)
		(end 168.999916 -37.999924)
		(width 0.3556)
		(layer "F.Cu")
		(net "GND")
	)
	(segment
		(start 176.1998 -45.999654)
		(end 175.800004 -45.599858)
		(width 0.3556)
		(layer "F.Cu")
		(net "GND")
	)
	(segment
		(start 167.39997 -29.99994)
		(end 167.20439 -30.19552)
		(width 0.3048)
		(layer "F.Cu")
		(net "GND")
	)
	(segment
		(start 121.500138 -70.50024)
		(end 122.00001 -71.000112)
		(width 0.4572)
		(layer "F.Cu")
		(net "GND")
	)
	(segment
		(start 183.399938 -45.199808)
		(end 182.999888 -45.599858)
		(width 0.3556)
		(layer "F.Cu")
		(net "GND")
	)
	(segment
		(start 159.37357 -45.595032)
		(end 159.375856 -45.592746)
		(width 0.508)
		(layer "F.Cu")
		(net "GND")
	)
	(segment
		(start 169.399712 -36.79952)
		(end 169.00017 -36.399978)
		(width 0.3556)
		(layer "F.Cu")
		(net "GND")
	)
	(segment
		(start 169.800016 -45.199808)
		(end 169.799762 -45.199808)
		(width 0.3556)
		(layer "F.Cu")
		(net "GND")
	)
	(segment
		(start 10.392156 -52.013866)
		(end 9.982454 -51.604164)
		(width 0.3048)
		(layer "F.Cu")
		(net "GND")
	)
	(segment
		(start 166.599616 -45.999908)
		(end 166.19982 -46.399704)
		(width 0.3556)
		(layer "F.Cu")
		(net "GND")
	)
	(segment
		(start 180.199792 -37.999924)
		(end 179.799742 -37.599874)
		(width 0.3556)
		(layer "F.Cu")
		(net "GND")
	)
	(segment
		(start 180.199792 -47.599854)
		(end 180.199792 -47.599346)
		(width 0.3556)
		(layer "F.Cu")
		(net "GND")
	)
	(segment
		(start 171.399962 -45.200062)
		(end 172.199808 -45.999908)
		(width 0.3556)
		(layer "F.Cu")
		(net "GND")
	)
	(segment
		(start 105.499916 -70.50024)
		(end 106.000042 -70.000114)
		(width 0.4572)
		(layer "F.Cu")
		(net "GND")
	)
	(segment
		(start 178.6001 -48.399954)
		(end 178.999896 -48.79975)
		(width 0.3556)
		(layer "F.Cu")
		(net "GND")
	)
	(segment
		(start 169.800016 -49.1998)
		(end 169.399966 -48.79975)
		(width 0.3556)
		(layer "F.Cu")
		(net "GND")
	)
	(segment
		(start 116.499894 -63.5)
		(end 116.500148 -63.5)
		(width 0.4572)
		(layer "F.Cu")
		(net "GND")
	)
	(segment
		(start 164.199824 -50.799746)
		(end 163.399978 -49.9999)
		(width 0.3556)
		(layer "F.Cu")
		(net "GND")
	)
	(segment
		(start 99.499928 -58.50001)
		(end 99.000056 -58.000138)
		(width 0.4572)
		(layer "F.Cu")
		(net "GND")
	)
	(segment
		(start 191.71158 -41.6687)
		(end 192.5447 -41.6687)
		(width 0.508)
		(layer "F.Cu")
		(net "GND")
	)
	(segment
		(start 176.9999 -33.999932)
		(end 176.999138 -33.999932)
		(width 0.3556)
		(layer "F.Cu")
		(net "GND")
	)
	(segment
		(start 170.599862 -42.800016)
		(end 170.599862 -42.799762)
		(width 0.3556)
		(layer "F.Cu")
		(net "GND")
	)
	(segment
		(start 56.89473 -16.952214)
		(end 56.894476 -16.95196)
		(width 0.508)
		(layer "F.Cu")
		(net "GND")
	)
	(segment
		(start 168.999408 -40.39997)
		(end 168.599612 -40.799766)
		(width 0.3556)
		(layer "F.Cu")
		(net "GND")
	)
	(segment
		(start 127.500126 -68.500244)
		(end 127.999998 -69.000116)
		(width 0.4572)
		(layer "F.Cu")
		(net "GND")
	)
	(segment
		(start 59.817 -81.3054)
		(end 59.817 -80.5307)
		(width 0.508)
		(layer "F.Cu")
		(net "GND")
	)
	(segment
		(start 123.500134 -70.50024)
		(end 124.000006 -71.000112)
		(width 0.4572)
		(layer "F.Cu")
		(net "GND")
	)
	(segment
		(start 120.50014 -80.50022)
		(end 121.000012 -81.000092)
		(width 0.4572)
		(layer "F.Cu")
		(net "GND")
	)
	(segment
		(start 168.39184 -34.191956)
		(end 168.392094 -34.191956)
		(width 0.3556)
		(layer "F.Cu")
		(net "GND")
	)
	(segment
		(start 175.387 -95.5802)
		(end 176.149 -94.8182)
		(width 0.508)
		(layer "F.Cu")
		(net "GND")
	)
	(segment
		(start 124.500132 -75.50023)
		(end 124.500132 -76.500228)
		(width 0.254)
		(layer "F.Cu")
		(net "GND")
	)
	(segment
		(start 167.20439 -30.60446)
		(end 167.39997 -30.80004)
		(width 0.3048)
		(layer "F.Cu")
		(net "GND")
	)
	(segment
		(start 177.8 -43.600116)
		(end 178.199796 -43.999912)
		(width 0.3556)
		(layer "F.Cu")
		(net "GND")
	)
	(segment
		(start 171.399962 -44.399962)
		(end 171.399962 -44.399708)
		(width 0.3556)
		(layer "F.Cu")
		(net "GND")
	)
	(segment
		(start 170.518328 -29.99994)
		(end 170.410378 -29.89199)
		(width 0.3048)
		(layer "F.Cu")
		(net "GND")
	)
	(segment
		(start 118.000018 -59.000136)
		(end 118.500144 -58.50001)
		(width 0.4572)
		(layer "F.Cu")
		(net "GND")
	)
	(segment
		(start 175.399954 -39.59987)
		(end 174.999904 -39.19982)
		(width 0.3556)
		(layer "F.Cu")
		(net "GND")
	)
	(segment
		(start 181.799992 -40.399462)
		(end 182.199788 -39.999666)
		(width 0.3556)
		(layer "F.Cu")
		(net "GND")
	)
	(segment
		(start 104.000046 -65.000124)
		(end 104.499918 -64.500252)
		(width 0.4572)
		(layer "F.Cu")
		(net "GND")
	)
	(segment
		(start 170.599862 -45.999908)
		(end 170.599862 -46.00067)
		(width 0.3556)
		(layer "F.Cu")
		(net "GND")
	)
	(segment
		(start 182.599584 -32.399986)
		(end 182.199788 -32.799782)
		(width 0.3556)
		(layer "F.Cu")
		(net "GND")
	)
	(segment
		(start 117.500146 -70.500494)
		(end 117.500146 -70.50024)
		(width 0.4064)
		(layer "F.Cu")
		(net "GND")
	)
	(segment
		(start 76.10729 -74.3331)
		(end 76.10729 -75.904344)
		(width 0.381)
		(layer "F.Cu")
		(net "GND")
	)
	(segment
		(start 184.999884 -43.599862)
		(end 184.59958 -44.000166)
		(width 0.3556)
		(layer "F.Cu")
		(net "GND")
	)
	(segment
		(start 174.599854 -43.599862)
		(end 174.999904 -43.999912)
		(width 0.3556)
		(layer "F.Cu")
		(net "GND")
	)
	(segment
		(start 124.500132 -80.50022)
		(end 125.000004 -81.000092)
		(width 0.4572)
		(layer "F.Cu")
		(net "GND")
	)
	(segment
		(start 182.599838 -41.999916)
		(end 182.599584 -41.999916)
		(width 0.3556)
		(layer "F.Cu")
		(net "GND")
	)
	(segment
		(start 130.50012 -61.500004)
		(end 130.999992 -61.000132)
		(width 0.4572)
		(layer "F.Cu")
		(net "GND")
	)
	(segment
		(start 75.28179 -26.460958)
		(end 75.28179 -27.489658)
		(width 0.508)
		(layer "F.Cu")
		(net "GND")
	)
	(segment
		(start 174.599854 -47.599854)
		(end 174.599854 -47.600108)
		(width 0.3556)
		(layer "F.Cu")
		(net "GND")
	)
	(segment
		(start 160.7312 -77.4954)
		(end 161.036 -77.8002)
		(width 0.508)
		(layer "F.Cu")
		(net "GND")
	)
	(segment
		(start 180.999892 -37.199824)
		(end 180.999892 -37.199316)
		(width 0.3556)
		(layer "F.Cu")
		(net "GND")
	)
	(segment
		(start 170.599862 -40.39997)
		(end 170.599862 -40.399462)
		(width 0.3556)
		(layer "F.Cu")
		(net "GND")
	)
	(segment
		(start 172.199808 -42.800016)
		(end 172.200062 -42.800016)
		(width 0.3556)
		(layer "F.Cu")
		(net "GND")
	)
	(segment
		(start 72.262492 -77.314806)
		(end 72.262492 -76.193904)
		(width 0.4064)
		(layer "F.Cu")
		(net "GND")
	)
	(segment
		(start 182.599838 -37.999924)
		(end 182.999888 -37.599874)
		(width 0.3556)
		(layer "F.Cu")
		(net "GND")
	)
	(segment
		(start 174.599854 -32.399986)
		(end 174.200058 -32.00019)
		(width 0.3556)
		(layer "F.Cu")
		(net "GND")
	)
	(segment
		(start 180.199792 -30.80004)
		(end 180.200046 -30.80004)
		(width 0.3048)
		(layer "F.Cu")
		(net "GND")
	)
	(segment
		(start 169.983404 -29.888942)
		(end 169.872406 -29.99994)
		(width 0.3048)
		(layer "F.Cu")
		(net "GND")
	)
	(segment
		(start 172.199808 -43.599862)
		(end 172.199808 -43.600116)
		(width 0.3556)
		(layer "F.Cu")
		(net "GND")
	)
	(segment
		(start 173.800008 -39.59987)
		(end 173.399958 -39.19982)
		(width 0.3556)
		(layer "F.Cu")
		(net "GND")
	)
	(segment
		(start 164.999924 -44.399962)
		(end 164.999924 -44.399708)
		(width 0.3556)
		(layer "F.Cu")
		(net "GND")
	)
	(segment
		(start 17.9451 -85.852)
		(end 17.9451 -86.53653)
		(width 0.3556)
		(layer "F.Cu")
		(net "GND")
	)
	(segment
		(start 173.4058 -60.2615)
		(end 173.4058 -61.049916)
		(width 0.508)
		(layer "F.Cu")
		(net "GND")
	)
	(segment
		(start 118.49989 -61.500004)
		(end 118.500144 -61.500004)
		(width 0.4572)
		(layer "F.Cu")
		(net "GND")
	)
	(segment
		(start 64.44615 -81.284318)
		(end 64.40805 -81.322418)
		(width 0.508)
		(layer "F.Cu")
		(net "GND")
	)
	(segment
		(start 106.499914 -67.500246)
		(end 106.000042 -68.000118)
		(width 0.4572)
		(layer "F.Cu")
		(net "GND")
	)
	(segment
		(start 152.739852 -92.90177)
		(end 153.67508 -92.90177)
		(width 0.3048)
		(layer "F.Cu")
		(net "GND")
	)
	(segment
		(start 180.999892 -47.600108)
		(end 180.600096 -47.999904)
		(width 0.3556)
		(layer "F.Cu")
		(net "GND")
	)
	(segment
		(start 179.399946 -38.800024)
		(end 179.799742 -39.19982)
		(width 0.3556)
		(layer "F.Cu")
		(net "GND")
	)
	(segment
		(start 190.787782 -80.216502)
		(end 190.787782 -79.751936)
		(width 0.508)
		(layer "F.Cu")
		(net "GND")
	)
	(segment
		(start 85.268054 -55.743094)
		(end 85.268054 -56.89473)
		(width 0.508)
		(layer "F.Cu")
		(net "GND")
	)
	(segment
		(start 179.399946 -33.999932)
		(end 179.399946 -34.00044)
		(width 0.3556)
		(layer "F.Cu")
		(net "GND")
	)
	(segment
		(start 168.999916 -45.199808)
		(end 168.999408 -45.199808)
		(width 0.3556)
		(layer "F.Cu")
		(net "GND")
	)
	(segment
		(start 63.211202 -70.993)
		(end 62.5094 -70.993)
		(width 0.508)
		(layer "F.Cu")
		(net "GND")
	)
	(segment
		(start 172.999908 -43.599862)
		(end 173.399958 -43.999912)
		(width 0.3556)
		(layer "F.Cu")
		(net "GND")
	)
	(segment
		(start 164.999924 -33.199832)
		(end 164.600128 -32.800036)
		(width 0.3048)
		(layer "F.Cu")
		(net "GND")
	)
	(segment
		(start 101.499924 -63.5)
		(end 101.499924 -63.500254)
		(width 0.4572)
		(layer "F.Cu")
		(net "GND")
	)
	(segment
		(start 165.800024 -41.999662)
		(end 165.800024 -41.999916)
		(width 0.3048)
		(layer "F.Cu")
		(net "GND")
	)
	(segment
		(start 170.599862 -46.799754)
		(end 170.20032 -46.400212)
		(width 0.3556)
		(layer "F.Cu")
		(net "GND")
	)
	(segment
		(start 130.50012 -69.500242)
		(end 130.999992 -70.000114)
		(width 0.4572)
		(layer "F.Cu")
		(net "GND")
	)
	(segment
		(start 127.500126 -58.50001)
		(end 127.999998 -58.000138)
		(width 0.4572)
		(layer "F.Cu")
		(net "GND")
	)
	(segment
		(start 173.7995 -46.800008)
		(end 173.399704 -47.199804)
		(width 0.3556)
		(layer "F.Cu")
		(net "GND")
	)
	(segment
		(start 58.7375 -18.542)
		(end 59.5503 -18.542)
		(width 0.508)
		(layer "F.Cu")
		(net "GND")
	)
	(segment
		(start 127.500126 -70.50024)
		(end 127.999998 -71.000112)
		(width 0.4572)
		(layer "F.Cu")
		(net "GND")
	)
	(segment
		(start 184.199784 -31.599886)
		(end 184.199784 -31.599632)
		(width 0.3048)
		(layer "F.Cu")
		(net "GND")
	)
	(segment
		(start 176.9999 -45.999908)
		(end 176.1998 -45.199808)
		(width 0.3556)
		(layer "F.Cu")
		(net "GND")
	)
	(segment
		(start 169.799254 -36.399978)
		(end 169.399712 -36.79952)
		(width 0.3556)
		(layer "F.Cu")
		(net "GND")
	)
	(segment
		(start 118.500144 -54.500018)
		(end 119.000016 -54.000146)
		(width 0.4572)
		(layer "F.Cu")
		(net "GND")
	)
	(segment
		(start 120.499886 -61.500004)
		(end 120.50014 -61.500004)
		(width 0.4572)
		(layer "F.Cu")
		(net "GND")
	)
	(segment
		(start 114.499898 -69.500242)
		(end 113.4999 -70.50024)
		(width 0.4064)
		(layer "F.Cu")
		(net "GND")
	)
	(segment
		(start 115.499896 -68.500244)
		(end 114.499898 -69.500242)
		(width 0.4064)
		(layer "F.Cu")
		(net "GND")
	)
	(segment
		(start 172.999908 -35.599878)
		(end 172.599604 -35.199574)
		(width 0.3556)
		(layer "F.Cu")
		(net "GND")
	)
	(segment
		(start 177.8 -41.999916)
		(end 177.8 -42.00017)
		(width 0.3556)
		(layer "F.Cu")
		(net "GND")
	)
	(segment
		(start 165.000178 -28.399994)
		(end 165.800024 -29.19984)
		(width 0.3048)
		(layer "F.Cu")
		(net "GND")
	)
	(segment
		(start 105.499916 -66.499994)
		(end 105.000044 -66.000122)
		(width 0.4572)
		(layer "F.Cu")
		(net "GND")
	)
	(segment
		(start 159.08528 -93.80728)
		(end 159.96158 -93.80728)
		(width 0.508)
		(layer "F.Cu")
		(net "GND")
	)
	(segment
		(start 173.800008 -33.199832)
		(end 173.800008 -33.200086)
		(width 0.3556)
		(layer "F.Cu")
		(net "GND")
	)
	(segment
		(start 93.7387 -72.1106)
		(end 93.7387 -73.152)
		(width 0.508)
		(layer "F.Cu")
		(net "GND")
	)
	(segment
		(start 152.122378 -99.050094)
		(end 152.586182 -98.58629)
		(width 0.3048)
		(layer "F.Cu")
		(net "GND")
	)
	(segment
		(start 159.26308 -99.04476)
		(end 159.26308 -99.914456)
		(width 0.508)
		(layer "F.Cu")
		(net "GND")
	)
	(segment
		(start 177.8 -42.00017)
		(end 178.199796 -42.399966)
		(width 0.3556)
		(layer "F.Cu")
		(net "GND")
	)
	(segment
		(start 112.499902 -69.500242)
		(end 111.499904 -70.50024)
		(width 0.4064)
		(layer "F.Cu")
		(net "GND")
	)
	(segment
		(start 165.800024 -43.599862)
		(end 165.800024 -43.599608)
		(width 0.3556)
		(layer "F.Cu")
		(net "GND")
	)
	(segment
		(start 101.499924 -51.500024)
		(end 101.000052 -51.000152)
		(width 0.508)
		(layer "F.Cu")
		(net "GND")
	)
	(segment
		(start 174.599854 -50.799746)
		(end 174.199804 -50.399696)
		(width 0.3556)
		(layer "F.Cu")
		(net "GND")
	)
	(segment
		(start 104.499918 -79.500222)
		(end 104.000046 -80.000094)
		(width 0.4572)
		(layer "F.Cu")
		(net "GND")
	)
	(segment
		(start 131.318 -55.499)
		(end 131.316984 -55.500016)
		(width 0.4064)
		(layer "F.Cu")
		(net "GND")
	)
	(segment
		(start 112.499902 -54.500018)
		(end 112.00003 -54.000146)
		(width 0.4572)
		(layer "F.Cu")
		(net "GND")
	)
	(segment
		(start 114.499898 -60.50026)
		(end 114.000026 -61.000132)
		(width 0.4572)
		(layer "F.Cu")
		(net "GND")
	)
	(segment
		(start 164.199824 -40.399716)
		(end 163.800028 -39.99992)
		(width 0.3048)
		(layer "F.Cu")
		(net "GND")
	)
	(segment
		(start 6.731 -55.245)
		(end 5.56514 -55.245)
		(width 0.508)
		(layer "F.Cu")
		(net "GND")
	)
	(segment
		(start 178.599846 -34.000186)
		(end 178.20005 -34.399982)
		(width 0.3556)
		(layer "F.Cu")
		(net "GND")
	)
	(segment
		(start 100.499926 -54.500018)
		(end 100.000054 -54.000146)
		(width 0.4572)
		(layer "F.Cu")
		(net "GND")
	)
	(segment
		(start 116.500148 -69.500242)
		(end 117.500146 -68.500244)
		(width 0.4064)
		(layer "F.Cu")
		(net "GND")
	)
	(segment
		(start 182.92826 -109.21238)
		(end 182.85968 -109.1438)
		(width 0.508)
		(layer "F.Cu")
		(net "GND")
	)
	(segment
		(start 103.49992 -51.500024)
		(end 103.000048 -51.000152)
		(width 0.4572)
		(layer "F.Cu")
		(net "GND")
	)
	(segment
		(start 124.500132 -74.499978)
		(end 124.500132 -74.500232)
		(width 0.4572)
		(layer "F.Cu")
		(net "GND")
	)
	(segment
		(start 172.199554 -29.99994)
		(end 172.199808 -29.99994)
		(width 0.3048)
		(layer "F.Cu")
		(net "GND")
	)
	(segment
		(start 172.999908 -49.1998)
		(end 173.399958 -48.79975)
		(width 0.3556)
		(layer "F.Cu")
		(net "GND")
	)
	(segment
		(start 121.500138 -60.500006)
		(end 121.500138 -60.50026)
		(width 0.4572)
		(layer "F.Cu")
		(net "GND")
	)
	(segment
		(start 172.199808 -44.399962)
		(end 171.399962 -45.199808)
		(width 0.3556)
		(layer "F.Cu")
		(net "GND")
	)
	(segment
		(start 115.50015 -64.499998)
		(end 115.499896 -64.499998)
		(width 0.4572)
		(layer "F.Cu")
		(net "GND")
	)
	(segment
		(start 183.399938 -40.39997)
		(end 183.399684 -40.39997)
		(width 0.3556)
		(layer "F.Cu")
		(net "GND")
	)
	(segment
		(start 129.500122 -77.500226)
		(end 129.999994 -78.000098)
		(width 0.4572)
		(layer "F.Cu")
		(net "GND")
	)
	(segment
		(start 128.500124 -80.50022)
		(end 128.999996 -81.000092)
		(width 0.508)
		(layer "F.Cu")
		(net "GND")
	)
	(segment
		(start 123.500134 -64.500252)
		(end 123.500134 -64.499998)
		(width 0.4572)
		(layer "F.Cu")
		(net "GND")
	)
	(segment
		(start 93.7895 -69.977)
		(end 93.63837 -69.977)
		(width 0.508)
		(layer "F.Cu")
		(net "GND")
	)
	(segment
		(start 108.49991 -78.500224)
		(end 108.000038 -79.000096)
		(width 0.4572)
		(layer "F.Cu")
		(net "GND")
	)
	(segment
		(start 172.199808 -29.200094)
		(end 171.799758 -29.600144)
		(width 0.3048)
		(layer "F.Cu")
		(net "GND")
	)
	(segment
		(start 172.199808 -49.199546)
		(end 171.800266 -48.800004)
		(width 0.3556)
		(layer "F.Cu")
		(net "GND")
	)
	(segment
		(start 168.392094 -34.191956)
		(end 168.599612 -34.399474)
		(width 0.3556)
		(layer "F.Cu")
		(net "GND")
	)
	(segment
		(start 180.999892 -40.399462)
		(end 181.399688 -39.999666)
		(width 0.3556)
		(layer "F.Cu")
		(net "GND")
	)
	(segment
		(start 177.8 -43.599862)
		(end 177.8 -43.600116)
		(width 0.3556)
		(layer "F.Cu")
		(net "GND")
	)
	(segment
		(start 9.911588 -77.450188)
		(end 10.770616 -77.450188)
		(width 0.508)
		(layer "F.Cu")
		(net "GND")
	)
	(segment
		(start 182.599838 -36.399978)
		(end 182.59933 -36.399978)
		(width 0.3556)
		(layer "F.Cu")
		(net "GND")
	)
	(segment
		(start 176.1998 -46.800008)
		(end 176.1998 -46.7995)
		(width 0.3556)
		(layer "F.Cu")
		(net "GND")
	)
	(segment
		(start 167.390318 -38.800024)
		(end 166.99992 -38.409626)
		(width 0.3556)
		(layer "F.Cu")
		(net "GND")
	)
	(segment
		(start 124.500132 -61.500004)
		(end 125.000004 -61.000132)
		(width 0.4572)
		(layer "F.Cu")
		(net "GND")
	)
	(segment
		(start 176.9999 -31.599886)
		(end 177.000408 -31.599886)
		(width 0.3048)
		(layer "F.Cu")
		(net "GND")
	)
	(segment
		(start 104.499918 -69.500242)
		(end 104.000046 -70.000114)
		(width 0.4572)
		(layer "F.Cu")
		(net "GND")
	)
	(segment
		(start 183.399938 -46.800008)
		(end 183.391556 -46.800008)
		(width 0.3556)
		(layer "F.Cu")
		(net "GND")
	)
	(segment
		(start 179.399946 -46.800008)
		(end 179.399692 -46.800008)
		(width 0.3556)
		(layer "F.Cu")
		(net "GND")
	)
	(segment
		(start 118.000018 -63.000128)
		(end 118.49989 -63.5)
		(width 0.4572)
		(layer "F.Cu")
		(net "GND")
	)
	(segment
		(start 6.6421 -56.769)
		(end 5.6515 -56.769)
		(width 0.508)
		(layer "F.Cu")
		(net "GND")
	)
	(segment
		(start 113.4999 -66.499994)
		(end 113.999772 -66.000122)
		(width 0.4064)
		(layer "F.Cu")
		(net "GND")
	)
	(segment
		(start 170.410378 -29.89199)
		(end 170.40098 -29.89199)
		(width 0.3048)
		(layer "F.Cu")
		(net "GND")
	)
	(segment
		(start 180.999892 -36.399978)
		(end 181.000146 -36.399978)
		(width 0.3556)
		(layer "F.Cu")
		(net "GND")
	)
	(segment
		(start 181.799992 -46.800008)
		(end 182.199788 -46.400212)
		(width 0.3556)
		(layer "F.Cu")
		(net "GND")
	)
	(segment
		(start 105.499916 -68.500244)
		(end 106.000042 -68.000118)
		(width 0.4572)
		(layer "F.Cu")
		(net "GND")
	)
	(segment
		(start 111.499904 -57.500012)
		(end 111.500158 -57.500012)
		(width 0.4572)
		(layer "F.Cu")
		(net "GND")
	)
	(segment
		(start 180.999892 -40.39997)
		(end 180.999892 -40.399462)
		(width 0.3556)
		(layer "F.Cu")
		(net "GND")
	)
	(segment
		(start 170.599862 -37.200078)
		(end 170.20032 -37.59962)
		(width 0.3556)
		(layer "F.Cu")
		(net "GND")
	)
	(segment
		(start 127.500126 -54.500018)
		(end 127.999998 -54.000146)
		(width 0.4572)
		(layer "F.Cu")
		(net "GND")
	)
	(segment
		(start 117.500146 -76.500228)
		(end 118.000018 -76.000356)
		(width 0.4572)
		(layer "F.Cu")
		(net "GND")
	)
	(segment
		(start 174.60087 -34.800032)
		(end 175.000412 -34.40049)
		(width 0.3556)
		(layer "F.Cu")
		(net "GND")
	)
	(segment
		(start 163.399978 -40.39997)
		(end 163.800028 -39.99992)
		(width 0.3048)
		(layer "F.Cu")
		(net "GND")
	)
	(segment
		(start 109.99978 -59.000136)
		(end 110.499906 -58.50001)
		(width 0.4572)
		(layer "F.Cu")
		(net "GND")
	)
	(segment
		(start 168.199816 -41.199816)
		(end 168.199816 -41.199562)
		(width 0.3556)
		(layer "F.Cu")
		(net "GND")
	)
	(segment
		(start 182.3974 -113.34242)
		(end 182.39994 -113.33988)
		(width 0.508)
		(layer "F.Cu")
		(net "GND")
	)
	(segment
		(start 61.654182 -16.102838)
		(end 61.652658 -16.101314)
		(width 0.508)
		(layer "F.Cu")
		(net "GND")
	)
	(segment
		(start 123.500134 -60.50026)
		(end 123.500134 -60.500006)
		(width 0.4572)
		(layer "F.Cu")
		(net "GND")
	)
	(segment
		(start 173.800008 -35.599878)
		(end 173.800008 -35.599116)
		(width 0.3556)
		(layer "F.Cu")
		(net "GND")
	)
	(segment
		(start 181.799992 -48.399954)
		(end 180.999892 -47.599854)
		(width 0.3048)
		(layer "F.Cu")
		(net "GND")
	)
	(segment
		(start 168.999916 -40.39997)
		(end 168.999408 -40.39997)
		(width 0.3556)
		(layer "F.Cu")
		(net "GND")
	)
	(segment
		(start 172.199808 -37.999924)
		(end 172.999908 -38.800024)
		(width 0.3556)
		(layer "F.Cu")
		(net "GND")
	)
	(segment
		(start 149.8854 -85.8266)
		(end 149.8727 -85.8393)
		(width 0.508)
		(layer "F.Cu")
		(net "GND")
	)
	(segment
		(start 128.500124 -51.500024)
		(end 128.999996 -51.000152)
		(width 0.508)
		(layer "F.Cu")
		(net "GND")
	)
	(segment
		(start 173.800008 -45.999908)
		(end 173.399958 -46.399958)
		(width 0.3556)
		(layer "F.Cu")
		(net "GND")
	)
	(segment
		(start 167.20439 -30.19552)
		(end 167.20439 -30.60446)
		(width 0.3048)
		(layer "F.Cu")
		(net "GND")
	)
	(segment
		(start 164.999924 -37.999924)
		(end 164.999924 -38.009576)
		(width 0.3556)
		(layer "F.Cu")
		(net "GND")
	)
	(segment
		(start 167.39997 -29.99994)
		(end 167.799766 -29.600144)
		(width 0.3048)
		(layer "F.Cu")
		(net "GND")
	)
	(segment
		(start 116.500148 -58.50001)
		(end 117.500146 -57.500012)
		(width 0.4572)
		(layer "F.Cu")
		(net "GND")
	)
	(segment
		(start 69.15658 -70.350126)
		(end 69.503036 -70.696582)
		(width 0.508)
		(layer "F.Cu")
		(net "GND")
	)
	(segment
		(start 114.000026 -61.000132)
		(end 113.500154 -61.500004)
		(width 0.4572)
		(layer "F.Cu")
		(net "GND")
	)
	(segment
		(start 174.599854 -31.600394)
		(end 174.200058 -32.00019)
		(width 0.3048)
		(layer "F.Cu")
		(net "GND")
	)
	(segment
		(start 173.000162 -48.399954)
		(end 173.399958 -48.79975)
		(width 0.3556)
		(layer "F.Cu")
		(net "GND")
	)
	(segment
		(start 107.500166 -57.500012)
		(end 108.000038 -57.00014)
		(width 0.4572)
		(layer "F.Cu")
		(net "GND")
	)
	(segment
		(start 166.59987 -42.800016)
		(end 166.599616 -42.800016)
		(width 0.3556)
		(layer "F.Cu")
		(net "GND")
	)
	(segment
		(start 164.323268 -23.935944)
		(end 164.323268 -24.78024)
		(width 0.508)
		(layer "F.Cu")
		(net "GND")
	)
	(segment
		(start 172.199808 -43.600116)
		(end 171.399962 -44.399962)
		(width 0.3556)
		(layer "F.Cu")
		(net "GND")
	)
	(segment
		(start 190.68288 -76.61148)
		(end 191.444372 -76.61148)
		(width 0.508)
		(layer "F.Cu")
		(net "GND")
	)
	(segment
		(start 193.1543 -44.1198)
		(end 193.15049 -44.12361)
		(width 0.508)
		(layer "F.Cu")
		(net "GND")
	)
	(segment
		(start 119.500142 -51.500024)
		(end 120.000014 -51.000152)
		(width 0.4572)
		(layer "F.Cu")
		(net "GND")
	)
	(segment
		(start 159.8676 -102.929436)
		(end 159.8676 -105.238296)
		(width 0.9652)
		(layer "F.Cu")
		(net "GND")
	)
	(segment
		(start 181.799992 -37.999924)
		(end 181.799484 -37.999924)
		(width 0.3556)
		(layer "F.Cu")
		(net "GND")
	)
	(segment
		(start 169.800016 -31.599886)
		(end 169.399966 -31.999936)
		(width 0.3048)
		(layer "F.Cu")
		(net "GND")
	)
	(segment
		(start 183.399684 -40.39997)
		(end 182.999888 -40.799766)
		(width 0.3556)
		(layer "F.Cu")
		(net "GND")
	)
	(segment
		(start 176.9999 -48.399954)
		(end 177.000154 -48.399954)
		(width 0.3556)
		(layer "F.Cu")
		(net "GND")
	)
	(segment
		(start 7.9756 -76.6445)
		(end 9.1059 -76.6445)
		(width 0.508)
		(layer "F.Cu")
		(net "GND")
	)
	(segment
		(start 103.49992 -68.500244)
		(end 104.000046 -68.000118)
		(width 0.4572)
		(layer "F.Cu")
		(net "GND")
	)
	(segment
		(start 184.199784 -41.20007)
		(end 183.399938 -41.999916)
		(width 0.3048)
		(layer "F.Cu")
		(net "GND")
	)
	(segment
		(start 124.000006 -66.000122)
		(end 124.500132 -65.499996)
		(width 0.4572)
		(layer "F.Cu")
		(net "GND")
	)
	(segment
		(start 101.499924 -59.500008)
		(end 101.000052 -59.000136)
		(width 0.4572)
		(layer "F.Cu")
		(net "GND")
	)
	(segment
		(start 95.749872 -77.0128)
		(end 95.840296 -76.922376)
		(width 0.508)
		(layer "F.Cu")
		(net "GND")
	)
	(segment
		(start 169.800016 -40.39997)
		(end 169.799762 -40.39997)
		(width 0.3556)
		(layer "F.Cu")
		(net "GND")
	)
	(segment
		(start 182.599584 -37.999924)
		(end 182.199788 -38.39972)
		(width 0.3556)
		(layer "F.Cu")
		(net "GND")
	)
	(segment
		(start 180.199792 -46.800008)
		(end 180.199792 -46.7995)
		(width 0.3556)
		(layer "F.Cu")
		(net "GND")
	)
	(segment
		(start 164.199824 -50.8)
		(end 164.199824 -50.799746)
		(width 0.3556)
		(layer "F.Cu")
		(net "GND")
	)
	(segment
		(start 177.8 -46.799754)
		(end 178.20005 -46.399704)
		(width 0.3556)
		(layer "F.Cu")
		(net "GND")
	)
	(segment
		(start 180.999892 -37.999924)
		(end 181.399688 -38.39972)
		(width 0.3556)
		(layer "F.Cu")
		(net "GND")
	)
	(segment
		(start 180.199792 -34.000186)
		(end 179.399946 -34.800032)
		(width 0.3556)
		(layer "F.Cu")
		(net "GND")
	)
	(segment
		(start 175.399954 -44.399962)
		(end 174.999904 -43.999912)
		(width 0.3556)
		(layer "F.Cu")
		(net "GND")
	)
	(segment
		(start 174.599854 -34.800032)
		(end 174.60087 -34.800032)
		(width 0.3556)
		(layer "F.Cu")
		(net "GND")
	)
	(segment
		(start 180.199792 -45.999908)
		(end 180.199792 -45.9994)
		(width 0.3556)
		(layer "F.Cu")
		(net "GND")
	)
	(segment
		(start 127.500126 -52.500022)
		(end 127.999998 -52.00015)
		(width 0.4572)
		(layer "F.Cu")
		(net "GND")
	)
	(segment
		(start 129.500122 -53.50002)
		(end 129.999994 -53.000148)
		(width 0.508)
		(layer "F.Cu")
		(net "GND")
	)
	(segment
		(start 123.603258 -91.039696)
		(end 123.603258 -91.523058)
		(width 0.508)
		(layer "F.Cu")
		(net "GND")
	)
	(segment
		(start 171.399962 -44.399708)
		(end 171.000166 -43.999912)
		(width 0.3556)
		(layer "F.Cu")
		(net "GND")
	)
	(segment
		(start 80.6958 -70.178168)
		(end 80.939386 -70.421754)
		(width 0.2032)
		(layer "F.Cu")
		(net "GND")
	)
	(segment
		(start 170.397932 -29.888942)
		(end 169.983404 -29.888942)
		(width 0.3048)
		(layer "F.Cu")
		(net "GND")
	)
	(segment
		(start 168.999662 -39.59987)
		(end 168.599612 -39.19982)
		(width 0.3556)
		(layer "F.Cu")
		(net "GND")
	)
	(segment
		(start 167.39997 -35.599878)
		(end 166.59987 -36.399978)
		(width 0.3048)
		(layer "F.Cu")
		(net "GND")
	)
	(segment
		(start 176.9999 -45.199808)
		(end 176.999646 -45.199808)
		(width 0.3556)
		(layer "F.Cu")
		(net "GND")
	)
	(segment
		(start 104.499918 -81.499964)
		(end 104.000046 -81.000092)
		(width 0.4572)
		(layer "F.Cu")
		(net "GND")
	)
	(segment
		(start 112.499902 -63.5)
		(end 112.00003 -63.000128)
		(width 0.4572)
		(layer "F.Cu")
		(net "GND")
	)
	(segment
		(start 80.939386 -70.421754)
		(end 81.9531 -70.421754)
		(width 0.2032)
		(layer "F.Cu")
		(net "GND")
	)
	(segment
		(start 168.199816 -33.999932)
		(end 168.39184 -34.191956)
		(width 0.3556)
		(layer "F.Cu")
		(net "GND")
	)
	(segment
		(start 104.499918 -80.50022)
		(end 104.000046 -81.000092)
		(width 0.4572)
		(layer "F.Cu")
		(net "GND")
	)
	(segment
		(start 174.599854 -50.8)
		(end 174.599854 -50.799746)
		(width 0.3556)
		(layer "F.Cu")
		(net "GND")
	)
	(segment
		(start 114.499898 -58.50001)
		(end 114.500152 -58.50001)
		(width 0.4572)
		(layer "F.Cu")
		(net "GND")
	)
	(segment
		(start 173.800008 -37.999924)
		(end 173.399958 -37.599874)
		(width 0.3556)
		(layer "F.Cu")
		(net "GND")
	)
	(segment
		(start 61.654182 -16.957294)
		(end 61.654182 -16.102838)
		(width 0.508)
		(layer "F.Cu")
		(net "GND")
	)
	(segment
		(start 150.34768 -108.38688)
		(end 149.32406 -108.38688)
		(width 0.508)
		(layer "F.Cu")
		(net "GND")
	)
	(segment
		(start 190.87338 -78.93558)
		(end 190.87338 -79.666338)
		(width 0.508)
		(layer "F.Cu")
		(net "GND")
	)
	(segment
		(start 178.599846 -34.799778)
		(end 178.6001 -34.800032)
		(width 0.3556)
		(layer "F.Cu")
		(net "GND")
	)
	(segment
		(start 121.500138 -61.500004)
		(end 122.00001 -61.000132)
		(width 0.4572)
		(layer "F.Cu")
		(net "GND")
	)
	(segment
		(start 182.199788 -46.400212)
		(end 182.199788 -46.399704)
		(width 0.3556)
		(layer "F.Cu")
		(net "GND")
	)
	(segment
		(start 172.999908 -47.599854)
		(end 173.399704 -47.99965)
		(width 0.3556)
		(layer "F.Cu")
		(net "GND")
	)
	(segment
		(start 173.800008 -48.399954)
		(end 173.799754 -48.399954)
		(width 0.3556)
		(layer "F.Cu")
		(net "GND")
	)
	(segment
		(start 124.500132 -76.500228)
		(end 125.000004 -77.0001)
		(width 0.4572)
		(layer "F.Cu")
		(net "GND")
	)
	(segment
		(start 164.199824 -38.800024)
		(end 164.209476 -38.800024)
		(width 0.3556)
		(layer "F.Cu")
		(net "GND")
	)
	(segment
		(start 100.499926 -56.500014)
		(end 100.000054 -56.000142)
		(width 0.4572)
		(layer "F.Cu")
		(net "GND")
	)
	(segment
		(start 170.599862 -44.399708)
		(end 170.199812 -43.999658)
		(width 0.3556)
		(layer "F.Cu")
		(net "GND")
	)
	(segment
		(start 80.8355 -66.675)
		(end 80.983074 -66.822574)
		(width 0.2032)
		(layer "F.Cu")
		(net "GND")
	)
	(segment
		(start 177.39995 -29.59989)
		(end 176.9999 -29.99994)
		(width 0.3048)
		(layer "F.Cu")
		(net "GND")
	)
	(segment
		(start 178.599846 -30.80004)
		(end 178.6001 -30.80004)
		(width 0.3048)
		(layer "F.Cu")
		(net "GND")
	)
	(segment
		(start 14.5669 -99.3267)
		(end 14.5669 -98.5012)
		(width 0.508)
		(layer "F.Cu")
		(net "GND")
	)
	(segment
		(start 101.499924 -76.500228)
		(end 101.000052 -77.0001)
		(width 0.4572)
		(layer "F.Cu")
		(net "GND")
	)
	(segment
		(start 25.2476 -114.9731)
		(end 26.1239 -114.9731)
		(width 0.508)
		(layer "F.Cu")
		(net "GND")
	)
	(segment
		(start 17.6022 -95.3897)
		(end 17.6022 -96.2152)
		(width 0.508)
		(layer "F.Cu")
		(net "GND")
	)
	(segment
		(start 166.99992 -31.199836)
		(end 167.399716 -30.80004)
		(width 0.3048)
		(layer "F.Cu")
		(net "GND")
	)
	(segment
		(start 182.599838 -47.591726)
		(end 182.990998 -47.200566)
		(width 0.3556)
		(layer "F.Cu")
		(net "GND")
	)
	(segment
		(start 181.799484 -39.59987)
		(end 181.399688 -39.999666)
		(width 0.3556)
		(layer "F.Cu")
		(net "GND")
	)
	(segment
		(start 170.599862 -37.999162)
		(end 170.20032 -37.59962)
		(width 0.3556)
		(layer "F.Cu")
		(net "GND")
	)
	(segment
		(start 7.0993 -85.8012)
		(end 7.0993 -86.476586)
		(width 0.3556)
		(layer "F.Cu")
		(net "GND")
	)
	(segment
		(start 111.499904 -51.500024)
		(end 111.000032 -51.000152)
		(width 0.4572)
		(layer "F.Cu")
		(net "GND")
	)
	(segment
		(start 165.800024 -46.800008)
		(end 165.800024 -46.7995)
		(width 0.3556)
		(layer "F.Cu")
		(net "GND")
	)
	(segment
		(start 124.500132 -54.500018)
		(end 125.000004 -54.000146)
		(width 0.4572)
		(layer "F.Cu")
		(net "GND")
	)
	(segment
		(start 111.500158 -61.500004)
		(end 111.499904 -61.500004)
		(width 0.4572)
		(layer "F.Cu")
		(net "GND")
	)
	(segment
		(start 68.616322 -70.350126)
		(end 69.15658 -70.350126)
		(width 0.508)
		(layer "F.Cu")
		(net "GND")
	)
	(segment
		(start 169.00017 -36.399978)
		(end 168.999916 -36.399978)
		(width 0.3556)
		(layer "F.Cu")
		(net "GND")
	)
	(segment
		(start 165.800024 -46.7995)
		(end 166.19982 -46.399704)
		(width 0.3556)
		(layer "F.Cu")
		(net "GND")
	)
	(segment
		(start 7.098538 -84.852764)
		(end 7.098538 -85.319108)
		(width 0.508)
		(layer "F.Cu")
		(net "GND")
	)
	(segment
		(start 116.500148 -54.500018)
		(end 117.00002 -54.000146)
		(width 0.4572)
		(layer "F.Cu")
		(net "GND")
	)
	(segment
		(start 183.399938 -32.399732)
		(end 184.199784 -31.599886)
		(width 0.3556)
		(layer "F.Cu")
		(net "GND")
	)
	(segment
		(start 171.19219 -29.883354)
		(end 170.791378 -29.883354)
		(width 0.3048)
		(layer "F.Cu")
		(net "GND")
	)
	(segment
		(start 178.599846 -48.399954)
		(end 178.6001 -48.399954)
		(width 0.3556)
		(layer "F.Cu")
		(net "GND")
	)
	(segment
		(start 184.199784 -47.599854)
		(end 184.59958 -47.200058)
		(width 0.3556)
		(layer "F.Cu")
		(net "GND")
	)
	(segment
		(start 154.561286 -80.007714)
		(end 154.559 -80.01)
		(width 0.508)
		(layer "F.Cu")
		(net "GND")
	)
	(segment
		(start 124.000006 -65.000124)
		(end 123.500134 -64.500252)
		(width 0.4572)
		(layer "F.Cu")
		(net "GND")
	)
	(segment
		(start 170.599862 -36.399978)
		(end 170.600116 -36.399978)
		(width 0.3556)
		(layer "F.Cu")
		(net "GND")
	)
	(segment
		(start 173.800008 -42.800016)
		(end 173.399958 -42.399966)
		(width 0.3556)
		(layer "F.Cu")
		(net "GND")
	)
	(segment
		(start 179.399946 -45.999908)
		(end 178.599846 -46.800008)
		(width 0.3556)
		(layer "F.Cu")
		(net "GND")
	)
	(segment
		(start 160.7185 -84.036916)
		(end 160.7185 -83.224116)
		(width 0.508)
		(layer "F.Cu")
		(net "GND")
	)
	(segment
		(start 66.319908 -19.7866)
		(end 66.319908 -19.12874)
		(width 0.2032)
		(layer "F.Cu")
		(net "GND")
	)
	(segment
		(start 169.800016 -32.399986)
		(end 169.399966 -31.999936)
		(width 0.3048)
		(layer "F.Cu")
		(net "GND")
	)
	(segment
		(start 170.599862 -35.59937)
		(end 170.999658 -35.199574)
		(width 0.3556)
		(layer "F.Cu")
		(net "GND")
	)
	(segment
		(start 115.499896 -64.499998)
		(end 114.499898 -63.5)
		(width 0.4572)
		(layer "F.Cu")
		(net "GND")
	)
	(segment
		(start 46.712124 -34.151062)
		(end 45.911262 -34.151062)
		(width 0.3048)
		(layer "F.Cu")
		(net "GND")
	)
	(segment
		(start 183.82615 -109.21238)
		(end 182.92826 -109.21238)
		(width 0.508)
		(layer "F.Cu")
		(net "GND")
	)
	(segment
		(start 165.399974 -39.99992)
		(end 164.999924 -39.59987)
		(width 0.3048)
		(layer "F.Cu")
		(net "GND")
	)
	(segment
		(start 131.736338 -73.391522)
		(end 131.627626 -73.500234)
		(width 0.254)
		(layer "F.Cu")
		(net "GND")
	)
	(segment
		(start 9.410446 -76.949046)
		(end 9.911588 -77.450188)
		(width 0.508)
		(layer "F.Cu")
		(net "GND")
	)
	(segment
		(start 55.02656 -80.01)
		(end 55.02656 -79.121)
		(width 0.3556)
		(layer "F.Cu")
		(net "GND")
	)
	(segment
		(start 181.79923 -36.399978)
		(end 181.399688 -36.79952)
		(width 0.3556)
		(layer "F.Cu")
		(net "GND")
	)
	(segment
		(start 180.999892 -43.599862)
		(end 181.399688 -43.999658)
		(width 0.3556)
		(layer "F.Cu")
		(net "GND")
	)
	(segment
		(start 110.499906 -63.5)
		(end 110.000034 -63.000128)
		(width 0.4572)
		(layer "F.Cu")
		(net "GND")
	)
	(segment
		(start 163.399978 -49.9999)
		(end 162.708336 -49.308258)
		(width 0.3556)
		(layer "F.Cu")
		(net "GND")
	)
	(segment
		(start 80.983074 -66.822574)
		(end 81.9531 -66.822574)
		(width 0.2032)
		(layer "F.Cu")
		(net "GND")
	)
	(segment
		(start 168.999916 -46.800008)
		(end 168.599612 -46.399704)
		(width 0.3556)
		(layer "F.Cu")
		(net "GND")
	)
	(segment
		(start 112.499902 -58.50001)
		(end 113.4999 -57.500012)
		(width 0.4572)
		(layer "F.Cu")
		(net "GND")
	)
	(segment
		(start 167.39997 -29.200348)
		(end 167.799766 -29.600144)
		(width 0.3048)
		(layer "F.Cu")
		(net "GND")
	)
	(segment
		(start 165.800024 -29.199586)
		(end 165.800024 -29.19984)
		(width 0.3048)
		(layer "F.Cu")
		(net "GND")
	)
	(segment
		(start 177.8 -34.800032)
		(end 177.39995 -34.399982)
		(width 0.3556)
		(layer "F.Cu")
		(net "GND")
	)
	(segment
		(start 180.199792 -45.9994)
		(end 180.599588 -45.599604)
		(width 0.3556)
		(layer "F.Cu")
		(net "GND")
	)
	(segment
		(start 172.999908 -36.399978)
		(end 172.999146 -36.399978)
		(width 0.3556)
		(layer "F.Cu")
		(net "GND")
	)
	(segment
		(start 12.4333 -85.7504)
		(end 12.4333 -86.384892)
		(width 0.3556)
		(layer "F.Cu")
		(net "GND")
	)
	(segment
		(start 119.500142 -61.500004)
		(end 120.000014 -61.000132)
		(width 0.4572)
		(layer "F.Cu")
		(net "GND")
	)
	(segment
		(start 114.499898 -60.500006)
		(end 114.499898 -60.50026)
		(width 0.4572)
		(layer "F.Cu")
		(net "GND")
	)
	(segment
		(start 113.500154 -63.5)
		(end 113.4999 -63.5)
		(width 0.4572)
		(layer "F.Cu")
		(net "GND")
	)
	(segment
		(start 181.799992 -42.800016)
		(end 181.799992 -42.799508)
		(width 0.3556)
		(layer "F.Cu")
		(net "GND")
	)
	(segment
		(start 131.315968 -57.500012)
		(end 130.50012 -57.500012)
		(width 0.4064)
		(layer "F.Cu")
		(net "GND")
	)
	(segment
		(start 180.999892 -33.199832)
		(end 180.599842 -33.599882)
		(width 0.3556)
		(layer "F.Cu")
		(net "GND")
	)
	(segment
		(start 21.140928 -101.588824)
		(end 20.867624 -101.588824)
		(width 0.4064)
		(layer "F.Cu")
		(net "GND")
	)
	(segment
		(start 58.081926 -19.769074)
		(end 58.7375 -19.1135)
		(width 0.381)
		(layer "F.Cu")
		(net "GND")
	)
	(segment
		(start 182.600092 -38.800024)
		(end 182.999888 -39.19982)
		(width 0.3556)
		(layer "F.Cu")
		(net "GND")
	)
	(segment
		(start 165.800024 -43.599608)
		(end 166.19982 -43.199812)
		(width 0.3556)
		(layer "F.Cu")
		(net "GND")
	)
	(segment
		(start 179.399946 -43.600116)
		(end 179.799742 -43.999912)
		(width 0.3556)
		(layer "F.Cu")
		(net "GND")
	)
	(segment
		(start 157.0482 -73.34123)
		(end 157.9245 -73.34123)
		(width 0.508)
		(layer "F.Cu")
		(net "GND")
	)
	(segment
		(start 172.200062 -47.599854)
		(end 172.599858 -47.99965)
		(width 0.3556)
		(layer "F.Cu")
		(net "GND")
	)
	(segment
		(start 91.2876 -87.376)
		(end 91.2876 -88.1888)
		(width 0.508)
		(layer "F.Cu")
		(net "GND")
	)
	(segment
		(start 108.49991 -66.499994)
		(end 108.000038 -66.000122)
		(width 0.4572)
		(layer "F.Cu")
		(net "GND")
	)
	(segment
		(start 111.499904 -68.500244)
		(end 111.999776 -68.000372)
		(width 0.4064)
		(layer "F.Cu")
		(net "GND")
	)
	(segment
		(start 19.696684 -72.82053)
		(end 20.547584 -72.82053)
		(width 0.508)
		(layer "F.Cu")
		(net "GND")
	)
	(segment
		(start 110.499906 -65.499996)
		(end 109.99978 -64.99987)
		(width 0.4064)
		(layer "F.Cu")
		(net "GND")
	)
	(segment
		(start 166.59987 -39.59987)
		(end 166.19982 -39.19982)
		(width 0.3048)
		(layer "F.Cu")
		(net "GND")
	)
	(segment
		(start 179.399946 -47.599854)
		(end 178.599846 -48.399954)
		(width 0.3556)
		(layer "F.Cu")
		(net "GND")
	)
	(segment
		(start 181.799992 -33.199832)
		(end 180.999892 -33.999932)
		(width 0.3556)
		(layer "F.Cu")
		(net "GND")
	)
	(segment
		(start 178.599846 -36.399978)
		(end 177.8 -37.199824)
		(width 0.3556)
		(layer "F.Cu")
		(net "GND")
	)
	(segment
		(start 7.23011 -86.607396)
		(end 7.23011 -87.428578)
		(width 0.3556)
		(layer "F.Cu")
		(net "GND")
	)
	(segment
		(start 119.500142 -65.50025)
		(end 119.500142 -65.499996)
		(width 0.4572)
		(layer "F.Cu")
		(net "GND")
	)
	(segment
		(start 174.599854 -45.200062)
		(end 173.800008 -45.999908)
		(width 0.3556)
		(layer "F.Cu")
		(net "GND")
	)
	(segment
		(start 160.7185 -75.092814)
		(end 160.7185 -75.969114)
		(width 0.508)
		(layer "F.Cu")
		(net "GND")
	)
	(segment
		(start 6.8453 -73.0758)
		(end 5.8674 -73.0758)
		(width 0.508)
		(layer "F.Cu")
		(net "GND")
	)
	(segment
		(start 172.199808 -48.3997)
		(end 172.599858 -47.99965)
		(width 0.3556)
		(layer "F.Cu")
		(net "GND")
	)
	(segment
		(start 175.399954 -42.800016)
		(end 174.999904 -42.399966)
		(width 0.3556)
		(layer "F.Cu")
		(net "GND")
	)
	(segment
		(start 116.000022 -61.000132)
		(end 116.499894 -61.500004)
		(width 0.4572)
		(layer "F.Cu")
		(net "GND")
	)
	(segment
		(start 191.698372 -41.676574)
		(end 191.703706 -41.676574)
		(width 0.508)
		(layer "F.Cu")
		(net "GND")
	)
	(segment
		(start 188.8744 -57.785)
		(end 188.7728 -57.8866)
		(width 0.508)
		(layer "F.Cu")
		(net "GND")
	)
	(segment
		(start 123.500134 -65.499996)
		(end 124.000006 -65.000124)
		(width 0.4572)
		(layer "F.Cu")
		(net "GND")
	)
	(segment
		(start 170.599608 -43.599862)
		(end 170.199812 -43.999658)
		(width 0.254)
		(layer "F.Cu")
		(net "GND")
	)
	(segment
		(start 125.50013 -77.500226)
		(end 126.000002 -78.000098)
		(width 0.4572)
		(layer "F.Cu")
		(net "GND")
	)
	(segment
		(start 106.499914 -69.500242)
		(end 106.000042 -70.000114)
		(width 0.4572)
		(layer "F.Cu")
		(net "GND")
	)
	(segment
		(start 196.887846 -71.161656)
		(end 197.269862 -70.77964)
		(width 0.3048)
		(layer "F.Cu")
		(net "GND")
	)
	(segment
		(start 171.210478 -29.89199)
		(end 171.200826 -29.89199)
		(width 0.3048)
		(layer "F.Cu")
		(net "GND")
	)
	(segment
		(start 195.970398 -71.161656)
		(end 196.887846 -71.161656)
		(width 0.3048)
		(layer "F.Cu")
		(net "GND")
	)
	(segment
		(start 190.590932 -70.697598)
		(end 190.977012 -70.311518)
		(width 0.508)
		(layer "F.Cu")
		(net "GND")
	)
	(segment
		(start 180.999892 -41.999916)
		(end 180.999892 -41.999408)
		(width 0.3556)
		(layer "F.Cu")
		(net "GND")
	)
	(segment
		(start 111.500158 -57.500012)
		(end 112.00003 -57.00014)
		(width 0.4572)
		(layer "F.Cu")
		(net "GND")
	)
	(segment
		(start 167.799766 -29.600144)
		(end 168.199562 -29.99994)
		(width 0.3048)
		(layer "F.Cu")
		(net "GND")
	)
	(segment
		(start 168.999916 -35.599878)
		(end 168.999916 -35.59937)
		(width 0.3556)
		(layer "F.Cu")
		(net "GND")
	)
	(segment
		(start 181.799992 -43.599862)
		(end 181.799484 -43.599862)
		(width 0.3556)
		(layer "F.Cu")
		(net "GND")
	)
	(segment
		(start 129.999994 -53.000148)
		(end 130.499866 -53.50002)
		(width 0.508)
		(layer "F.Cu")
		(net "GND")
	)
	(segment
		(start 176.6824 -60.2615)
		(end 176.6824 -61.049916)
		(width 0.508)
		(layer "F.Cu")
		(net "GND")
	)
	(segment
		(start 180.999892 -39.59987)
		(end 181.399688 -39.999666)
		(width 0.3556)
		(layer "F.Cu")
		(net "GND")
	)
	(segment
		(start 172.199808 -41.199816)
		(end 172.599858 -41.599866)
		(width 0.3556)
		(layer "F.Cu")
		(net "GND")
	)
	(segment
		(start 116.499894 -61.500004)
		(end 116.500148 -61.500004)
		(width 0.4572)
		(layer "F.Cu")
		(net "GND")
	)
	(segment
		(start 173.800008 -35.599116)
		(end 174.19955 -35.199574)
		(width 0.3556)
		(layer "F.Cu")
		(net "GND")
	)
	(segment
		(start 176.1998 -40.39997)
		(end 176.200054 -40.39997)
		(width 0.3556)
		(layer "F.Cu")
		(net "GND")
	)
	(segment
		(start 168.199562 -29.99994)
		(end 168.199816 -29.99994)
		(width 0.3048)
		(layer "F.Cu")
		(net "GND")
	)
	(segment
		(start 119.500142 -67.500246)
		(end 120.000014 -68.000118)
		(width 0.4572)
		(layer "F.Cu")
		(net "GND")
	)
	(segment
		(start 66.8655 -104.6734)
		(end 67.6402 -104.6734)
		(width 0.508)
		(layer "F.Cu")
		(net "GND")
	)
	(segment
		(start 191.573658 -76.482194)
		(end 192.401952 -76.482194)
		(width 0.508)
		(layer "F.Cu")
		(net "GND")
	)
	(segment
		(start 177.6984 -60.2615)
		(end 176.6824 -60.2615)
		(width 0.508)
		(layer "F.Cu")
		(net "GND")
	)
	(segment
		(start 164.199824 -28.399994)
		(end 164.999924 -28.399994)
		(width 0.3048)
		(layer "F.Cu")
		(net "GND")
	)
	(segment
		(start 166.19982 -41.599866)
		(end 165.800024 -41.999662)
		(width 0.3048)
		(layer "F.Cu")
		(net "GND")
	)
	(segment
		(start 176.1998 -33.999932)
		(end 176.199038 -33.999932)
		(width 0.3556)
		(layer "F.Cu")
		(net "GND")
	)
	(segment
		(start 175.3997 -36.399978)
		(end 174.599854 -37.199824)
		(width 0.3556)
		(layer "F.Cu")
		(net "GND")
	)
	(segment
		(start 121.500138 -57.500012)
		(end 122.00001 -57.00014)
		(width 0.4572)
		(layer "F.Cu")
		(net "GND")
	)
	(segment
		(start 163.43884 -99.95916)
		(end 163.43884 -99.26828)
		(width 0.508)
		(layer "F.Cu")
		(net "GND")
	)
	(segment
		(start 166.59987 -31.599886)
		(end 166.99992 -31.199836)
		(width 0.3048)
		(layer "F.Cu")
		(net "GND")
	)
	(segment
		(start 59.657488 -79.997554)
		(end 59.657488 -79.12227)
		(width 0.3556)
		(layer "F.Cu")
		(net "GND")
	)
	(segment
		(start 124.000006 -63.000128)
		(end 123.500134 -62.500256)
		(width 0.4572)
		(layer "F.Cu")
		(net "GND")
	)
	(segment
		(start 175.400208 -45.999908)
		(end 175.800004 -46.399704)
		(width 0.3556)
		(layer "F.Cu")
		(net "GND")
	)
	(segment
		(start 110.499906 -54.500018)
		(end 110.000034 -54.000146)
		(width 0.4572)
		(layer "F.Cu")
		(net "GND")
	)
	(segment
		(start 64.44615 -80.086454)
		(end 64.31661 -79.956914)
		(width 0.3556)
		(layer "F.Cu")
		(net "GND")
	)
	(segment
		(start 179.399946 -49.1998)
		(end 178.999896 -48.79975)
		(width 0.3556)
		(layer "F.Cu")
		(net "GND")
	)
	(segment
		(start 127.500126 -60.500006)
		(end 127.999998 -60.000134)
		(width 0.4572)
		(layer "F.Cu")
		(net "GND")
	)
	(segment
		(start 178.599846 -33.199832)
		(end 178.999896 -33.599882)
		(width 0.3556)
		(layer "F.Cu")
		(net "GND")
	)
	(segment
		(start 166.59987 -33.999932)
		(end 167.39997 -34.800032)
		(width 0.3048)
		(layer "F.Cu")
		(net "GND")
	)
	(segment
		(start 180.999892 -49.199546)
		(end 180.600096 -48.79975)
		(width 0.3556)
		(layer "F.Cu")
		(net "GND")
	)
	(segment
		(start 66.22288 -95.57258)
		(end 66.22288 -94.44736)
		(width 0.508)
		(layer "F.Cu")
		(net "GND")
	)
	(segment
		(start 107.499912 -51.500024)
		(end 107.00004 -51.000152)
		(width 0.4572)
		(layer "F.Cu")
		(net "GND")
	)
	(segment
		(start 117.500146 -57.500012)
		(end 118.000018 -57.00014)
		(width 0.4572)
		(layer "F.Cu")
		(net "GND")
	)
	(segment
		(start 124.500132 -51.500024)
		(end 125.000004 -51.000152)
		(width 0.4572)
		(layer "F.Cu")
		(net "GND")
	)
	(segment
		(start 109.99978 -71.000112)
		(end 109.499908 -71.499984)
		(width 0.4572)
		(layer "F.Cu")
		(net "GND")
	)
	(segment
		(start 82.715354 -111.675672)
		(end 83.555332 -111.675672)
		(width 0.508)
		(layer "F.Cu")
		(net "GND")
	)
	(segment
		(start 168.199816 -32.399986)
		(end 167.39997 -32.399986)
		(width 0.3556)
		(layer "F.Cu")
		(net "GND")
	)
	(segment
		(start 91.2876 -88.1888)
		(end 91.2114 -88.265)
		(width 0.508)
		(layer "F.Cu")
		(net "GND")
	)
	(segment
		(start 171.399962 -47.599854)
		(end 172.199808 -48.3997)
		(width 0.3556)
		(layer "F.Cu")
		(net "GND")
	)
	(segment
		(start 117.500146 -71.500238)
		(end 118.000018 -71.000366)
		(width 0.4064)
		(layer "F.Cu")
		(net "GND")
	)
	(segment
		(start 107.499912 -68.500244)
		(end 106.499914 -69.500242)
		(width 0.4572)
		(layer "F.Cu")
		(net "GND")
	)
	(segment
		(start 164.600128 -31.20009)
		(end 164.200332 -31.599886)
		(width 0.3048)
		(layer "F.Cu")
		(net "GND")
	)
	(segment
		(start 109.499908 -51.500024)
		(end 109.000036 -51.000152)
		(width 0.4572)
		(layer "F.Cu")
		(net "GND")
	)
	(segment
		(start 121.500138 -71.500238)
		(end 122.00001 -72.00011)
		(width 0.4572)
		(layer "F.Cu")
		(net "GND")
	)
	(segment
		(start 106.499914 -65.499996)
		(end 106.000042 -65.000124)
		(width 0.4572)
		(layer "F.Cu")
		(net "GND")
	)
	(segment
		(start 182.599838 -39.59987)
		(end 182.599584 -39.59987)
		(width 0.3556)
		(layer "F.Cu")
		(net "GND")
	)
	(segment
		(start 176.1998 -45.199808)
		(end 176.1998 -45.200062)
		(width 0.3556)
		(layer "F.Cu")
		(net "GND")
	)
	(segment
		(start 170.599862 -48.399954)
		(end 170.600624 -48.399954)
		(width 0.3556)
		(layer "F.Cu")
		(net "GND")
	)
	(segment
		(start 178.599846 -46.800008)
		(end 178.599846 -46.7995)
		(width 0.3556)
		(layer "F.Cu")
		(net "GND")
	)
	(segment
		(start 174.599854 -31.599886)
		(end 174.599854 -31.600394)
		(width 0.3048)
		(layer "F.Cu")
		(net "GND")
	)
	(segment
		(start 130.50012 -67.500246)
		(end 130.999992 -68.000118)
		(width 0.4572)
		(layer "F.Cu")
		(net "GND")
	)
	(segment
		(start 113.999772 -68.000372)
		(end 114.499898 -67.500246)
		(width 0.4064)
		(layer "F.Cu")
		(net "GND")
	)
	(segment
		(start 178.599846 -47.599854)
		(end 178.20005 -47.200058)
		(width 0.3556)
		(layer "F.Cu")
		(net "GND")
	)
	(segment
		(start 173.800008 -44.399962)
		(end 173.399958 -43.999912)
		(width 0.3556)
		(layer "F.Cu")
		(net "GND")
	)
	(segment
		(start 130.50012 -65.499996)
		(end 130.999992 -65.000124)
		(width 0.4572)
		(layer "F.Cu")
		(net "GND")
	)
	(segment
		(start 108.49991 -69.500242)
		(end 109.000036 -69.000116)
		(width 0.4572)
		(layer "F.Cu")
		(net "GND")
	)
	(segment
		(start 104.499918 -81.500218)
		(end 104.499918 -81.499964)
		(width 0.4572)
		(layer "F.Cu")
		(net "GND")
	)
	(segment
		(start 164.200332 -31.599886)
		(end 164.199824 -31.599886)
		(width 0.3048)
		(layer "F.Cu")
		(net "GND")
	)
	(segment
		(start 191.6303 -24.8412)
		(end 191.6303 -25.222962)
		(width 0.4572)
		(layer "F.Cu")
		(net "GND")
	)
	(segment
		(start 118.500144 -58.50001)
		(end 119.500142 -57.500012)
		(width 0.4572)
		(layer "F.Cu")
		(net "GND")
	)
	(segment
		(start 182.599584 -39.59987)
		(end 182.199788 -39.999666)
		(width 0.3556)
		(layer "F.Cu")
		(net "GND")
	)
	(segment
		(start 164.199824 -40.39997)
		(end 164.199824 -40.399716)
		(width 0.3048)
		(layer "F.Cu")
		(net "GND")
	)
	(segment
		(start 105.499916 -51.500024)
		(end 105.000044 -51.000152)
		(width 0.4572)
		(layer "F.Cu")
		(net "GND")
	)
	(segment
		(start 106.499914 -82.500216)
		(end 106.000042 -83.000088)
		(width 0.4572)
		(layer "F.Cu")
		(net "GND")
	)
	(segment
		(start 168.999916 -45.999908)
		(end 168.999408 -45.999908)
		(width 0.3556)
		(layer "F.Cu")
		(net "GND")
	)
	(segment
		(start 72.897492 -15.12951)
		(end 71.958708 -15.12951)
		(width 0.2032)
		(layer "F.Cu")
		(net "GND")
	)
	(segment
		(start 98.780346 -86.503002)
		(end 98.780346 -85.791802)
		(width 0.508)
		(layer "F.Cu")
		(net "GND")
	)
	(segment
		(start 179.399946 -40.39997)
		(end 179.799742 -40.799766)
		(width 0.3556)
		(layer "F.Cu")
		(net "GND")
	)
	(segment
		(start 129.500122 -51.500024)
		(end 129.999994 -51.000152)
		(width 0.508)
		(layer "F.Cu")
		(net "GND")
	)
	(segment
		(start 124.500132 -73.500234)
		(end 125.000004 -74.000106)
		(width 0.4572)
		(layer "F.Cu")
		(net "GND")
	)
	(segment
		(start 173.800008 -45.199808)
		(end 173.7995 -45.199808)
		(width 0.3556)
		(layer "F.Cu")
		(net "GND")
	)
	(segment
		(start 187.833 -57.0103)
		(end 188.8744 -57.0103)
		(width 0.508)
		(layer "F.Cu")
		(net "GND")
	)
	(segment
		(start 112.499902 -80.50022)
		(end 112.00003 -81.000092)
		(width 0.4572)
		(layer "F.Cu")
		(net "GND")
	)
	(segment
		(start 176.9999 -39.59987)
		(end 176.59985 -39.19982)
		(width 0.3556)
		(layer "F.Cu")
		(net "GND")
	)
	(segment
		(start 130.50012 -63.5)
		(end 130.999992 -63.000128)
		(width 0.4572)
		(layer "F.Cu")
		(net "GND")
	)
	(segment
		(start 173.800008 -41.199816)
		(end 173.799754 -41.199816)
		(width 0.3556)
		(layer "F.Cu")
		(net "GND")
	)
	(segment
		(start 164.999924 -28.399994)
		(end 165.000178 -28.399994)
		(width 0.3048)
		(layer "F.Cu")
		(net "GND")
	)
	(segment
		(start 192.29832 -53.3908)
		(end 193.22161 -53.3908)
		(width 0.508)
		(layer "F.Cu")
		(net "GND")
	)
	(segment
		(start 113.4999 -68.500244)
		(end 113.999772 -68.000372)
		(width 0.4064)
		(layer "F.Cu")
		(net "GND")
	)
	(segment
		(start 130.50012 -80.50022)
		(end 130.999992 -81.000092)
		(width 0.508)
		(layer "F.Cu")
		(net "GND")
	)
	(segment
		(start 172.999908 -48.399954)
		(end 173.000162 -48.399954)
		(width 0.3556)
		(layer "F.Cu")
		(net "GND")
	)
	(segment
		(start 95.0595 -77.0128)
		(end 95.749872 -77.0128)
		(width 0.508)
		(layer "F.Cu")
		(net "GND")
	)
	(segment
		(start 124.500132 -56.500014)
		(end 125.000004 -56.000142)
		(width 0.4572)
		(layer "F.Cu")
		(net "GND")
	)
	(segment
		(start 118.500144 -69.500242)
		(end 119.500142 -68.500244)
		(width 0.4572)
		(layer "F.Cu")
		(net "GND")
	)
	(segment
		(start 179.399946 -42.00017)
		(end 179.799742 -42.399966)
		(width 0.3556)
		(layer "F.Cu")
		(net "GND")
	)
	(segment
		(start 178.599846 -41.199816)
		(end 178.199796 -40.799766)
		(width 0.3556)
		(layer "F.Cu")
		(net "GND")
	)
	(segment
		(start 124.500132 -63.5)
		(end 125.000004 -63.000128)
		(width 0.4572)
		(layer "F.Cu")
		(net "GND")
	)
	(segment
		(start 168.999916 -37.999924)
		(end 168.199816 -37.199824)
		(width 0.3556)
		(layer "F.Cu")
		(net "GND")
	)
	(segment
		(start 172.199808 -37.199316)
		(end 172.599604 -36.79952)
		(width 0.3556)
		(layer "F.Cu")
		(net "GND")
	)
	(segment
		(start 110.499906 -78.500224)
		(end 110.000034 -79.000096)
		(width 0.4572)
		(layer "F.Cu")
		(net "GND")
	)
	(segment
		(start 174.599854 -44.399962)
		(end 174.999904 -43.999912)
		(width 0.3556)
		(layer "F.Cu")
		(net "GND")
	)
	(segment
		(start 47.5107 -27.94)
		(end 48.514 -27.94)
		(width 0.508)
		(layer "F.Cu")
		(net "GND")
	)
	(segment
		(start 173.800008 -33.200086)
		(end 174.599854 -33.999932)
		(width 0.3556)
		(layer "F.Cu")
		(net "GND")
	)
	(segment
		(start 101.499924 -80.50022)
		(end 101.000052 -81.000092)
		(width 0.508)
		(layer "F.Cu")
		(net "GND")
	)
	(segment
		(start 168.199816 -41.199562)
		(end 168.599612 -40.799766)
		(width 0.3556)
		(layer "F.Cu")
		(net "GND")
	)
	(segment
		(start 118.000018 -68.000372)
		(end 117.500146 -68.500244)
		(width 0.4064)
		(layer "F.Cu")
		(net "GND")
	)
	(segment
		(start 178.6001 -30.80004)
		(end 179.00015 -31.20009)
		(width 0.3048)
		(layer "F.Cu")
		(net "GND")
	)
	(segment
		(start 117.500146 -51.500024)
		(end 118.000018 -51.000152)
		(width 0.4572)
		(layer "F.Cu")
		(net "GND")
	)
	(segment
		(start 23.30323 -85.318092)
		(end 23.30323 -85.799422)
		(width 0.508)
		(layer "F.Cu")
		(net "GND")
	)
	(segment
		(start 174.599854 -29.19984)
		(end 174.999904 -28.79979)
		(width 0.3048)
		(layer "F.Cu")
		(net "GND")
	)
	(segment
		(start 175.387 -95.885)
		(end 175.387 -95.5802)
		(width 0.508)
		(layer "F.Cu")
		(net "GND")
	)
	(segment
		(start 62.5094 -70.993)
		(end 62.4332 -70.9168)
		(width 0.508)
		(layer "F.Cu")
		(net "GND")
	)
	(segment
		(start 175.399954 -46.800008)
		(end 175.399954 -46.799754)
		(width 0.3556)
		(layer "F.Cu")
		(net "GND")
	)
	(segment
		(start 174.599854 -51.599846)
		(end 174.199804 -51.199796)
		(width 0.3556)
		(layer "F.Cu")
		(net "GND")
	)
	(segment
		(start 130.499866 -53.50002)
		(end 130.50012 -53.50002)
		(width 0.508)
		(layer "F.Cu")
		(net "GND")
	)
	(segment
		(start 176.9999 -36.399978)
		(end 176.999646 -36.399978)
		(width 0.3556)
		(layer "F.Cu")
		(net "GND")
	)
	(segment
		(start 111.499904 -64.499998)
		(end 110.499906 -63.5)
		(width 0.4572)
		(layer "F.Cu")
		(net "GND")
	)
	(segment
		(start 7.0993 -85.31987)
		(end 7.0993 -85.8012)
		(width 0.508)
		(layer "F.Cu")
		(net "GND")
	)
	(segment
		(start 182.599838 -35.599878)
		(end 182.599584 -35.599878)
		(width 0.3556)
		(layer "F.Cu")
		(net "GND")
	)
	(segment
		(start 173.000162 -38.800024)
		(end 173.399958 -39.19982)
		(width 0.3556)
		(layer "F.Cu")
		(net "GND")
	)
	(segment
		(start 180.999892 -45.199808)
		(end 181.399688 -45.599604)
		(width 0.3556)
		(layer "F.Cu")
		(net "GND")
	)
	(segment
		(start 171.399962 -49.1998)
		(end 171.40047 -49.1998)
		(width 0.3556)
		(layer "F.Cu")
		(net "GND")
	)
	(segment
		(start 115.499896 -59.500008)
		(end 114.499898 -60.500006)
		(width 0.4572)
		(layer "F.Cu")
		(net "GND")
	)
	(segment
		(start 113.4999 -70.500494)
		(end 113.4999 -70.50024)
		(width 0.4064)
		(layer "F.Cu")
		(net "GND")
	)
	(segment
		(start 174.599854 -45.999908)
		(end 174.599854 -46.000162)
		(width 0.3556)
		(layer "F.Cu")
		(net "GND")
	)
	(segment
		(start 151.930608 -93.037914)
		(end 152.603708 -93.037914)
		(width 0.3048)
		(layer "F.Cu")
		(net "GND")
	)
	(segment
		(start 115.50015 -51.500024)
		(end 116.000022 -51.000152)
		(width 0.4572)
		(layer "F.Cu")
		(net "GND")
	)
	(segment
		(start 169.800016 -32.399986)
		(end 170.599862 -33.199832)
		(width 0.3048)
		(layer "F.Cu")
		(net "GND")
	)
	(segment
		(start 166.59987 -44.399962)
		(end 166.599616 -44.399962)
		(width 0.3556)
		(layer "F.Cu")
		(net "GND")
	)
	(segment
		(start 171.399962 -46.800008)
		(end 171.40047 -46.800008)
		(width 0.3556)
		(layer "F.Cu")
		(net "GND")
	)
	(segment
		(start 169.800016 -46.800008)
		(end 169.800524 -46.800008)
		(width 0.3556)
		(layer "F.Cu")
		(net "GND")
	)
	(segment
		(start 176.1998 -38.800024)
		(end 176.200054 -38.800024)
		(width 0.3556)
		(layer "F.Cu")
		(net "GND")
	)
	(segment
		(start 180.999892 -38.799516)
		(end 181.399688 -38.39972)
		(width 0.3556)
		(layer "F.Cu")
		(net "GND")
	)
	(segment
		(start 107.500166 -66.499994)
		(end 107.499912 -66.499994)
		(width 0.4572)
		(layer "F.Cu")
		(net "GND")
	)
	(segment
		(start 170.599862 -41.999916)
		(end 170.599608 -41.999916)
		(width 0.3556)
		(layer "F.Cu")
		(net "GND")
	)
	(segment
		(start 101.499924 -70.50024)
		(end 101.000052 -71.000112)
		(width 0.4572)
		(layer "F.Cu")
		(net "GND")
	)
	(segment
		(start 183.399938 -42.800016)
		(end 182.999634 -42.399712)
		(width 0.3556)
		(layer "F.Cu")
		(net "GND")
	)
	(segment
		(start 125.499876 -52.500022)
		(end 125.50013 -52.500022)
		(width 0.4572)
		(layer "F.Cu")
		(net "GND")
	)
	(segment
		(start 172.999908 -29.99994)
		(end 172.199808 -29.19984)
		(width 0.3048)
		(layer "F.Cu")
		(net "GND")
	)
	(segment
		(start 87.5919 -66.422524)
		(end 86.513924 -66.422524)
		(width 0.2032)
		(layer "F.Cu")
		(net "GND")
	)
	(segment
		(start 172.199808 -46.00067)
		(end 172.199808 -45.999908)
		(width 0.3556)
		(layer "F.Cu")
		(net "GND")
	)
	(segment
		(start 191.6303 -25.222962)
		(end 191.224662 -25.6286)
		(width 0.4572)
		(layer "F.Cu")
		(net "GND")
	)
	(segment
		(start 184.199784 -44.399962)
		(end 184.59958 -44.000166)
		(width 0.3556)
		(layer "F.Cu")
		(net "GND")
	)
	(segment
		(start 123.500134 -57.500012)
		(end 124.000006 -57.00014)
		(width 0.4572)
		(layer "F.Cu")
		(net "GND")
	)
	(segment
		(start 176.1998 -41.999916)
		(end 176.59985 -42.399966)
		(width 0.3556)
		(layer "F.Cu")
		(net "GND")
	)
	(segment
		(start 170.599862 -46.800008)
		(end 170.599862 -46.799754)
		(width 0.3556)
		(layer "F.Cu")
		(net "GND")
	)
	(segment
		(start 171.400216 -48.399954)
		(end 171.800266 -48.800004)
		(width 0.3556)
		(layer "F.Cu")
		(net "GND")
	)
	(segment
		(start 170.674792 -29.99994)
		(end 170.599862 -29.99994)
		(width 0.3048)
		(layer "F.Cu")
		(net "GND")
	)
	(segment
		(start 64.44615 -80.509618)
		(end 64.44615 -81.284318)
		(width 0.508)
		(layer "F.Cu")
		(net "GND")
	)
	(segment
		(start 23.999952 -122.124978)
		(end 23.999952 -124.431552)
		(width 0.9652)
		(layer "F.Cu")
		(net "GND")
	)
	(segment
		(start 122.499882 -61.500004)
		(end 122.500136 -61.500004)
		(width 0.4572)
		(layer "F.Cu")
		(net "GND")
	)
	(segment
		(start 151.930608 -94.01302)
		(end 151.930608 -93.037914)
		(width 0.508)
		(layer "F.Cu")
		(net "GND")
	)
	(segment
		(start 182.599838 -38.800024)
		(end 182.600092 -38.800024)
		(width 0.3556)
		(layer "F.Cu")
		(net "GND")
	)
	(segment
		(start 131.627626 -73.500234)
		(end 130.50012 -73.500234)
		(width 0.254)
		(layer "F.Cu")
		(net "GND")
	)
	(segment
		(start 181.799992 -30.80004)
		(end 182.199788 -31.199836)
		(width 0.3048)
		(layer "F.Cu")
		(net "GND")
	)
	(segment
		(start 199.78624 -81.63306)
		(end 199.79894 -81.62036)
		(width 0.508)
		(layer "F.Cu")
		(net "GND")
	)
	(segment
		(start 167.39997 -50.8)
		(end 167.80002 -50.39995)
		(width 0.3556)
		(layer "F.Cu")
		(net "GND")
	)
	(segment
		(start 178.599846 -45.999908)
		(end 178.599846 -45.999654)
		(width 0.3556)
		(layer "F.Cu")
		(net "GND")
	)
	(segment
		(start 109.499908 -71.499984)
		(end 109.499908 -71.500238)
		(width 0.4572)
		(layer "F.Cu")
		(net "GND")
	)
	(segment
		(start 22.83333 -95.294704)
		(end 22.83333 -96.120204)
		(width 0.508)
		(layer "F.Cu")
		(net "GND")
	)
	(segment
		(start 116.500148 -60.500006)
		(end 116.000022 -61.000132)
		(width 0.4572)
		(layer "F.Cu")
		(net "GND")
	)
	(segment
		(start 119.500142 -66.499994)
		(end 120.000014 -66.000122)
		(width 0.4572)
		(layer "F.Cu")
		(net "GND")
	)
	(segment
		(start 181.799992 -33.999678)
		(end 182.599838 -33.199832)
		(width 0.3556)
		(layer "F.Cu")
		(net "GND")
	)
	(segment
		(start 174.599854 -36.399978)
		(end 175.399954 -35.599878)
		(width 0.3556)
		(layer "F.Cu")
		(net "GND")
	)
	(segment
		(start 110.000034 -70.000114)
		(end 109.499908 -70.50024)
		(width 0.4064)
		(layer "F.Cu")
		(net "GND")
	)
	(segment
		(start 179.399946 -35.599878)
		(end 179.799996 -35.999928)
		(width 0.3556)
		(layer "F.Cu")
		(net "GND")
	)
	(segment
		(start 182.599838 -46.809406)
		(end 182.990998 -47.200566)
		(width 0.3556)
		(layer "F.Cu")
		(net "GND")
	)
	(segment
		(start 6.9215 -79.756)
		(end 5.8674 -79.756)
		(width 0.508)
		(layer "F.Cu")
		(net "GND")
	)
	(segment
		(start 121.500138 -76.500228)
		(end 122.00001 -77.0001)
		(width 0.4572)
		(layer "F.Cu")
		(net "GND")
	)
	(segment
		(start 120.000014 -59.000136)
		(end 120.50014 -58.50001)
		(width 0.4572)
		(layer "F.Cu")
		(net "GND")
	)
	(segment
		(start 172.999908 -46.800008)
		(end 173.399704 -47.199804)
		(width 0.3556)
		(layer "F.Cu")
		(net "GND")
	)
	(segment
		(start 179.399946 -33.199832)
		(end 178.999896 -33.599882)
		(width 0.3556)
		(layer "F.Cu")
		(net "GND")
	)
	(segment
		(start 167.799766 -48.79975)
		(end 167.39997 -48.399954)
		(width 0.3556)
		(layer "F.Cu")
		(net "GND")
	)
	(segment
		(start 64.44615 -80.509618)
		(end 64.44615 -80.086454)
		(width 0.3556)
		(layer "F.Cu")
		(net "GND")
	)
	(segment
		(start 181.799992 -38.800024)
		(end 181.799992 -38.799516)
		(width 0.3556)
		(layer "F.Cu")
		(net "GND")
	)
	(segment
		(start 93.70314 -66.37782)
		(end 93.653356 -66.328036)
		(width 0.508)
		(layer "F.Cu")
		(net "GND")
	)
	(segment
		(start 170.599862 -44.399962)
		(end 170.599862 -44.399708)
		(width 0.3556)
		(layer "F.Cu")
		(net "GND")
	)
	(segment
		(start 11.4681 -52.013866)
		(end 10.392156 -52.013866)
		(width 0.3048)
		(layer "F.Cu")
		(net "GND")
	)
	(segment
		(start 190.87338 -79.666338)
		(end 190.787782 -79.751936)
		(width 0.508)
		(layer "F.Cu")
		(net "GND")
	)
	(segment
		(start 176.9999 -34.800032)
		(end 176.9999 -34.799778)
		(width 0.3556)
		(layer "F.Cu")
		(net "GND")
	)
	(segment
		(start 69.38391 -81.369154)
		(end 69.38391 -80.569054)
		(width 0.508)
		(layer "F.Cu")
		(net "GND")
	)
	(segment
		(start 173.7995 -45.199808)
		(end 173.399704 -45.599604)
		(width 0.3556)
		(layer "F.Cu")
		(net "GND")
	)
	(segment
		(start 164.999924 -34.800032)
		(end 164.600128 -34.400236)
		(width 0.3048)
		(layer "F.Cu")
		(net "GND")
	)
	(segment
		(start 167.39997 -29.19984)
		(end 167.39997 -29.200348)
		(width 0.3048)
		(layer "F.Cu")
		(net "GND")
	)
	(segment
		(start 171.399962 -49.9999)
		(end 171.799758 -50.399696)
		(width 0.3556)
		(layer "F.Cu")
		(net "GND")
	)
	(segment
		(start 150.8125 -85.8266)
		(end 149.8854 -85.8266)
		(width 0.508)
		(layer "F.Cu")
		(net "GND")
	)
	(segment
		(start 183.399938 -35.599878)
		(end 182.999888 -35.999928)
		(width 0.3556)
		(layer "F.Cu")
		(net "GND")
	)
	(segment
		(start 181.799992 -40.39997)
		(end 181.799992 -40.399462)
		(width 0.3556)
		(layer "F.Cu")
		(net "GND")
	)
	(segment
		(start 121.500138 -60.50026)
		(end 122.00001 -61.000132)
		(width 0.4572)
		(layer "F.Cu")
		(net "GND")
	)
	(segment
		(start 106.499914 -76.500228)
		(end 106.000042 -77.0001)
		(width 0.4572)
		(layer "F.Cu")
		(net "GND")
	)
	(segment
		(start 122.499882 -71.500238)
		(end 122.500136 -71.500238)
		(width 0.4572)
		(layer "F.Cu")
		(net "GND")
	)
	(segment
		(start 99.499928 -56.500014)
		(end 99.000056 -56.000142)
		(width 0.4572)
		(layer "F.Cu")
		(net "GND")
	)
	(segment
		(start 176.999138 -33.999932)
		(end 176.599596 -34.399474)
		(width 0.3556)
		(layer "F.Cu")
		(net "GND")
	)
	(segment
		(start 103.49992 -70.50024)
		(end 104.000046 -70.000114)
		(width 0.4572)
		(layer "F.Cu")
		(net "GND")
	)
	(segment
		(start 103.49992 -72.500236)
		(end 103.000048 -73.000108)
		(width 0.4572)
		(layer "F.Cu")
		(net "GND")
	)
	(segment
		(start 172.599858 -46.400466)
		(end 172.200062 -46.00067)
		(width 0.3556)
		(layer "F.Cu")
		(net "GND")
	)
	(segment
		(start 123.500134 -72.500236)
		(end 124.000006 -73.000108)
		(width 0.4572)
		(layer "F.Cu")
		(net "GND")
	)
	(segment
		(start 122.500136 -80.50022)
		(end 123.000008 -81.000092)
		(width 0.4572)
		(layer "F.Cu")
		(net "GND")
	)
	(segment
		(start 175.399954 -34.800032)
		(end 175.79975 -35.199828)
		(width 0.3556)
		(layer "F.Cu")
		(net "GND")
	)
	(segment
		(start 168.199816 -44.399454)
		(end 168.599612 -43.999658)
		(width 0.3556)
		(layer "F.Cu")
		(net "GND")
	)
	(segment
		(start 180.199792 -38.800024)
		(end 180.199538 -38.800024)
		(width 0.3556)
		(layer "F.Cu")
		(net "GND")
	)
	(segment
		(start 181.799992 -35.599878)
		(end 182.199788 -35.999674)
		(width 0.3556)
		(layer "F.Cu")
		(net "GND")
	)
	(segment
		(start 164.323268 -24.78024)
		(end 164.247322 -24.856186)
		(width 0.508)
		(layer "F.Cu")
		(net "GND")
	)
	(segment
		(start 175.399954 -35.599624)
		(end 175.79975 -35.199828)
		(width 0.3556)
		(layer "F.Cu")
		(net "GND")
	)
	(segment
		(start 173.799754 -48.399954)
		(end 173.399958 -48.79975)
		(width 0.3556)
		(layer "F.Cu")
		(net "GND")
	)
	(segment
		(start 175.399954 -41.199816)
		(end 174.999904 -40.799766)
		(width 0.3556)
		(layer "F.Cu")
		(net "GND")
	)
	(segment
		(start 171.399962 -42.00017)
		(end 171.000166 -42.399966)
		(width 0.3556)
		(layer "F.Cu")
		(net "GND")
	)
	(segment
		(start 168.999916 -44.399962)
		(end 168.999408 -44.399962)
		(width 0.3556)
		(layer "F.Cu")
		(net "GND")
	)
	(segment
		(start 178.599846 -45.999654)
		(end 178.20005 -45.599858)
		(width 0.3556)
		(layer "F.Cu")
		(net "GND")
	)
	(segment
		(start 109.499908 -70.50024)
		(end 109.000036 -71.000112)
		(width 0.4572)
		(layer "F.Cu")
		(net "GND")
	)
	(segment
		(start 177.000154 -33.199832)
		(end 177.39995 -32.800036)
		(width 0.3556)
		(layer "F.Cu")
		(net "GND")
	)
	(segment
		(start 168.199816 -45.199554)
		(end 168.599612 -44.799758)
		(width 0.3556)
		(layer "F.Cu")
		(net "GND")
	)
	(segment
		(start 167.39997 -35.600132)
		(end 167.799766 -35.999928)
		(width 0.3556)
		(layer "F.Cu")
		(net "GND")
	)
	(segment
		(start 107.499912 -72.500236)
		(end 107.999784 -72.000364)
		(width 0.4572)
		(layer "F.Cu")
		(net "GND")
	)
	(segment
		(start 115.50015 -59.500008)
		(end 116.000022 -59.000136)
		(width 0.4572)
		(layer "F.Cu")
		(net "GND")
	)
	(segment
		(start 181.799992 -33.999932)
		(end 181.799992 -33.999678)
		(width 0.3556)
		(layer "F.Cu")
		(net "GND")
	)
	(segment
		(start 180.999892 -37.199316)
		(end 181.399688 -36.79952)
		(width 0.3556)
		(layer "F.Cu")
		(net "GND")
	)
	(segment
		(start 122.00001 -72.00011)
		(end 122.499882 -71.500238)
		(width 0.4572)
		(layer "F.Cu")
		(net "GND")
	)
	(segment
		(start 180.999384 -45.999908)
		(end 180.599588 -46.399704)
		(width 0.3556)
		(layer "F.Cu")
		(net "GND")
	)
	(segment
		(start 130.50012 -59.500008)
		(end 131.318 -59.500008)
		(width 0.4064)
		(layer "F.Cu")
		(net "GND")
	)
	(segment
		(start 179.399946 -37.199824)
		(end 179.399946 -37.200078)
		(width 0.3556)
		(layer "F.Cu")
		(net "GND")
	)
	(segment
		(start 182.599838 -44.399962)
		(end 182.999888 -43.999912)
		(width 0.3556)
		(layer "F.Cu")
		(net "GND")
	)
	(segment
		(start 190.590932 -71.161656)
		(end 190.590932 -70.697598)
		(width 0.508)
		(layer "F.Cu")
		(net "GND")
	)
	(segment
		(start 91.2114 -88.265)
		(end 89.9795 -88.265)
		(width 0.508)
		(layer "F.Cu")
		(net "GND")
	)
	(segment
		(start 105.499916 -78.49997)
		(end 105.000044 -78.000098)
		(width 0.4572)
		(layer "F.Cu")
		(net "GND")
	)
	(segment
		(start 94.1705 -88.1634)
		(end 94.0435 -88.2904)
		(width 0.508)
		(layer "F.Cu")
		(net "GND")
	)
	(segment
		(start 180.10505 -106.83494)
		(end 179.15128 -106.83494)
		(width 0.508)
		(layer "F.Cu")
		(net "GND")
	)
	(segment
		(start 104.499918 -60.500006)
		(end 104.000046 -60.000134)
		(width 0.4572)
		(layer "F.Cu")
		(net "GND")
	)
	(segment
		(start 116.500148 -80.50022)
		(end 117.00002 -81.000092)
		(width 0.4572)
		(layer "F.Cu")
		(net "GND")
	)
	(segment
		(start 180.199538 -38.800024)
		(end 179.799742 -39.19982)
		(width 0.3556)
		(layer "F.Cu")
		(net "GND")
	)
	(segment
		(start 176.9999 -41.199816)
		(end 176.59985 -40.799766)
		(width 0.3556)
		(layer "F.Cu")
		(net "GND")
	)
	(segment
		(start 185.596276 -57.016142)
		(end 186.508644 -57.016142)
		(width 0.508)
		(layer "F.Cu")
		(net "GND")
	)
	(segment
		(start 108.49991 -65.499996)
		(end 108.000038 -65.000124)
		(width 0.4572)
		(layer "F.Cu")
		(net "GND")
	)
	(segment
		(start 178.599846 -37.999924)
		(end 178.199796 -37.599874)
		(width 0.3556)
		(layer "F.Cu")
		(net "GND")
	)
	(segment
		(start 168.199816 -45.999908)
		(end 168.199816 -45.9994)
		(width 0.3556)
		(layer "F.Cu")
		(net "GND")
	)
	(segment
		(start 161.529268 -23.935944)
		(end 161.529268 -24.727154)
		(width 0.508)
		(layer "F.Cu")
		(net "GND")
	)
	(segment
		(start 170.999658 -39.999666)
		(end 170.599862 -39.59987)
		(width 0.3556)
		(layer "F.Cu")
		(net "GND")
	)
	(segment
		(start 174.599854 -30.80004)
		(end 174.402496 -30.997398)
		(width 0.3048)
		(layer "F.Cu")
		(net "GND")
	)
	(segment
		(start 114.000026 -63.000128)
		(end 113.500154 -63.5)
		(width 0.4572)
		(layer "F.Cu")
		(net "GND")
	)
	(segment
		(start 122.500136 -58.50001)
		(end 123.500134 -57.500012)
		(width 0.4572)
		(layer "F.Cu")
		(net "GND")
	)
	(segment
		(start 173.800008 -30.000194)
		(end 174.599854 -30.80004)
		(width 0.3048)
		(layer "F.Cu")
		(net "GND")
	)
	(segment
		(start 182.599838 -40.39997)
		(end 182.600092 -40.39997)
		(width 0.3556)
		(layer "F.Cu")
		(net "GND")
	)
	(segment
		(start 127.500126 -66.499994)
		(end 127.999998 -66.000122)
		(width 0.4572)
		(layer "F.Cu")
		(net "GND")
	)
	(segment
		(start 180.200046 -30.80004)
		(end 180.599842 -31.199836)
		(width 0.3048)
		(layer "F.Cu")
		(net "GND")
	)
	(segment
		(start 170.599862 -41.199816)
		(end 170.599862 -41.20007)
		(width 0.3556)
		(layer "F.Cu")
		(net "GND")
	)
	(segment
		(start 171.399962 -45.199808)
		(end 171.399962 -45.200062)
		(width 0.3556)
		(layer "F.Cu")
		(net "GND")
	)
	(segment
		(start 113.999772 -59.000136)
		(end 114.499898 -58.50001)
		(width 0.4572)
		(layer "F.Cu")
		(net "GND")
	)
	(segment
		(start 172.200062 -36.399978)
		(end 172.599604 -36.79952)
		(width 0.3556)
		(layer "F.Cu")
		(net "GND")
	)
	(segment
		(start 181.799992 -41.999408)
		(end 182.199788 -41.599612)
		(width 0.3556)
		(layer "F.Cu")
		(net "GND")
	)
	(segment
		(start 173.800008 -50.8)
		(end 174.199804 -51.199796)
		(width 0.3556)
		(layer "F.Cu")
		(net "GND")
	)
	(segment
		(start 168.199816 -44.399962)
		(end 168.199816 -44.399454)
		(width 0.3556)
		(layer "F.Cu")
		(net "GND")
	)
	(segment
		(start 168.999408 -45.999908)
		(end 168.599612 -46.399704)
		(width 0.3556)
		(layer "F.Cu")
		(net "GND")
	)
	(segment
		(start 12.7635 -98.425)
		(end 12.7635 -99.1743)
		(width 0.508)
		(layer "F.Cu")
		(net "GND")
	)
	(segment
		(start 151.038306 -99.050094)
		(end 151.897842 -99.050094)
		(width 0.508)
		(layer "F.Cu")
		(net "GND")
	)
	(segment
		(start 113.4999 -68.500244)
		(end 112.499902 -69.500242)
		(width 0.4064)
		(layer "F.Cu")
		(net "GND")
	)
	(segment
		(start 178.599846 -39.59987)
		(end 178.199796 -39.19982)
		(width 0.3556)
		(layer "F.Cu")
		(net "GND")
	)
	(segment
		(start 164.209476 -38.800024)
		(end 164.606986 -38.402514)
		(width 0.3556)
		(layer "F.Cu")
		(net "GND")
	)
	(segment
		(start 181.799992 -38.799516)
		(end 182.199788 -38.39972)
		(width 0.3556)
		(layer "F.Cu")
		(net "GND")
	)
	(segment
		(start 92.808298 -66.410586)
		(end 93.570806 -66.410586)
		(width 0.508)
		(layer "F.Cu")
		(net "GND")
	)
	(segment
		(start 182.59933 -36.399978)
		(end 182.199788 -36.79952)
		(width 0.3556)
		(layer "F.Cu")
		(net "GND")
	)
	(segment
		(start 168.999408 -45.199808)
		(end 168.599612 -45.599604)
		(width 0.3556)
		(layer "F.Cu")
		(net "GND")
	)
	(segment
		(start 121.500138 -63.5)
		(end 122.00001 -63.000128)
		(width 0.4572)
		(layer "F.Cu")
		(net "GND")
	)
	(segment
		(start 184.199784 -45.999908)
		(end 184.59958 -45.600112)
		(width 0.3556)
		(layer "F.Cu")
		(net "GND")
	)
	(segment
		(start 117.500146 -61.500004)
		(end 118.000018 -61.000132)
		(width 0.4572)
		(layer "F.Cu")
		(net "GND")
	)
	(segment
		(start 180.599588 -47.19955)
		(end 180.999384 -46.799754)
		(width 0.3556)
		(layer "F.Cu")
		(net "GND")
	)
	(segment
		(start 176.1998 -33.199832)
		(end 176.1998 -33.190434)
		(width 0.3556)
		(layer "F.Cu")
		(net "GND")
	)
	(segment
		(start 22.920452 -84.935314)
		(end 23.30323 -85.318092)
		(width 0.508)
		(layer "F.Cu")
		(net "GND")
	)
	(segment
		(start 185.79973 -42.800016)
		(end 186.199526 -42.40022)
		(width 0.3556)
		(layer "F.Cu")
		(net "GND")
	)
	(segment
		(start 164.999924 -35.603688)
		(end 164.606478 -35.997134)
		(width 0.3048)
		(layer "F.Cu")
		(net "GND")
	)
	(segment
		(start 125.000004 -74.000106)
		(end 124.500132 -74.499978)
		(width 0.4572)
		(layer "F.Cu")
		(net "GND")
	)
	(segment
		(start 119.500142 -57.500012)
		(end 120.000014 -57.00014)
		(width 0.4572)
		(layer "F.Cu")
		(net "GND")
	)
	(segment
		(start 172.999908 -45.999908)
		(end 173.399958 -46.399958)
		(width 0.3556)
		(layer "F.Cu")
		(net "GND")
	)
	(segment
		(start 170.599862 -33.999932)
		(end 170.599862 -33.99028)
		(width 0.3556)
		(layer "F.Cu")
		(net "GND")
	)
	(segment
		(start 172.999146 -36.399978)
		(end 172.599604 -36.79952)
		(width 0.3556)
		(layer "F.Cu")
		(net "GND")
	)
	(segment
		(start 112.00003 -63.000128)
		(end 111.500158 -63.5)
		(width 0.4572)
		(layer "F.Cu")
		(net "GND")
	)
	(segment
		(start 170.599862 -39.59987)
		(end 170.199812 -39.19982)
		(width 0.3556)
		(layer "F.Cu")
		(net "GND")
	)
	(segment
		(start 118.500144 -80.50022)
		(end 119.000016 -81.000092)
		(width 0.4572)
		(layer "F.Cu")
		(net "GND")
	)
	(segment
		(start 182.7022 -56.1213)
		(end 183.428132 -56.1213)
		(width 0.508)
		(layer "F.Cu")
		(net "GND")
	)
	(segment
		(start 171.399454 -39.59987)
		(end 170.999658 -39.999666)
		(width 0.3556)
		(layer "F.Cu")
		(net "GND")
	)
	(segment
		(start 124.500132 -52.500022)
		(end 125.000004 -52.00015)
		(width 0.4572)
		(layer "F.Cu")
		(net "GND")
	)
	(segment
		(start 172.199808 -33.999932)
		(end 172.199808 -34.000948)
		(width 0.3556)
		(layer "F.Cu")
		(net "GND")
	)
	(segment
		(start 181.799992 -37.199824)
		(end 181.799992 -37.199316)
		(width 0.3556)
		(layer "F.Cu")
		(net "GND")
	)
	(segment
		(start 180.599842 -33.599882)
		(end 180.999892 -33.999932)
		(width 0.3556)
		(layer "F.Cu")
		(net "GND")
	)
	(segment
		(start 122.499882 -69.500242)
		(end 122.500136 -69.500242)
		(width 0.4572)
		(layer "F.Cu")
		(net "GND")
	)
	(segment
		(start 107.499912 -60.500006)
		(end 106.499914 -59.500008)
		(width 0.4572)
		(layer "F.Cu")
		(net "GND")
	)
	(segment
		(start 181.799992 -41.199816)
		(end 182.199788 -41.599612)
		(width 0.3556)
		(layer "F.Cu")
		(net "GND")
	)
	(segment
		(start 175.399954 -35.599878)
		(end 175.399954 -35.599624)
		(width 0.3556)
		(layer "F.Cu")
		(net "GND")
	)
	(segment
		(start 127.500126 -62.500002)
		(end 127.999998 -62.00013)
		(width 0.4572)
		(layer "F.Cu")
		(net "GND")
	)
	(segment
		(start 184.199784 -34.800032)
		(end 183.399938 -35.599878)
		(width 0.3556)
		(layer "F.Cu")
		(net "GND")
	)
	(segment
		(start 122.00001 -70.000114)
		(end 122.499882 -69.500242)
		(width 0.4572)
		(layer "F.Cu")
		(net "GND")
	)
	(segment
		(start 69.503036 -70.696582)
		(end 69.996304 -70.696582)
		(width 0.508)
		(layer "F.Cu")
		(net "GND")
	)
	(segment
		(start 106.499914 -80.50022)
		(end 106.000042 -81.000092)
		(width 0.4572)
		(layer "F.Cu")
		(net "GND")
	)
	(segment
		(start 176.199038 -33.999932)
		(end 175.799496 -34.399474)
		(width 0.3556)
		(layer "F.Cu")
		(net "GND")
	)
	(segment
		(start 183.399684 -48.399954)
		(end 182.999888 -48.79975)
		(width 0.3556)
		(layer "F.Cu")
		(net "GND")
	)
	(segment
		(start 119.500142 -63.500254)
		(end 119.500142 -63.5)
		(width 0.4572)
		(layer "F.Cu")
		(net "GND")
	)
	(segment
		(start 70.3961 -83.4136)
		(end 70.3961 -84.328)
		(width 0.508)
		(layer "F.Cu")
		(net "GND")
	)
	(segment
		(start 173.800008 -34.000948)
		(end 173.400466 -34.40049)
		(width 0.3556)
		(layer "F.Cu")
		(net "GND")
	)
	(segment
		(start 52.7431 -73.1012)
		(end 52.7431 -74.2569)
		(width 0.508)
		(layer "F.Cu")
		(net "GND")
	)
	(segment
		(start 188.8744 -57.0103)
		(end 188.8744 -57.785)
		(width 0.508)
		(layer "F.Cu")
		(net "GND")
	)
	(segment
		(start 174.599854 -40.39997)
		(end 174.600108 -40.39997)
		(width 0.3556)
		(layer "F.Cu")
		(net "GND")
	)
	(segment
		(start 168.199816 -40.39997)
		(end 168.599612 -40.799766)
		(width 0.3556)
		(layer "F.Cu")
		(net "GND")
	)
	(segment
		(start 168.999916 -34.800032)
		(end 169.00017 -34.800032)
		(width 0.3556)
		(layer "F.Cu")
		(net "GND")
	)
	(segment
		(start 176.9999 -29.19984)
		(end 177.39995 -29.59989)
		(width 0.3048)
		(layer "F.Cu")
		(net "GND")
	)
	(segment
		(start 120.50014 -60.500006)
		(end 121.500138 -59.500008)
		(width 0.4572)
		(layer "F.Cu")
		(net "GND")
	)
	(segment
		(start 167.39997 -35.599878)
		(end 167.39997 -35.600132)
		(width 0.3556)
		(layer "F.Cu")
		(net "GND")
	)
	(segment
		(start 108.337858 -66.662046)
		(end 108.49991 -66.499994)
		(width 0.4064)
		(layer "F.Cu")
		(net "GND")
	)
	(segment
		(start 183.399938 -37.199824)
		(end 182.999888 -37.599874)
		(width 0.3556)
		(layer "F.Cu")
		(net "GND")
	)
	(segment
		(start 180.2003 -48.399954)
		(end 180.600096 -48.79975)
		(width 0.3556)
		(layer "F.Cu")
		(net "GND")
	)
	(segment
		(start 192.29832 -51.2318)
		(end 193.22161 -51.2318)
		(width 0.508)
		(layer "F.Cu")
		(net "GND")
	)
	(segment
		(start 172.199808 -49.1998)
		(end 172.199808 -49.199546)
		(width 0.3556)
		(layer "F.Cu")
		(net "GND")
	)
	(segment
		(start 178.599846 -45.200062)
		(end 178.20005 -45.599858)
		(width 0.3556)
		(layer "F.Cu")
		(net "GND")
	)
	(segment
		(start 176.9999 -44.399962)
		(end 176.59985 -43.999912)
		(width 0.3556)
		(layer "F.Cu")
		(net "GND")
	)
	(segment
		(start 131.318 -57.49798)
		(end 131.315968 -57.500012)
		(width 0.4064)
		(layer "F.Cu")
		(net "GND")
	)
	(segment
		(start 113.000028 -71.000366)
		(end 113.4999 -70.500494)
		(width 0.4064)
		(layer "F.Cu")
		(net "GND")
	)
	(segment
		(start 164.999924 -35.599878)
		(end 164.999924 -35.603688)
		(width 0.3048)
		(layer "F.Cu")
		(net "GND")
	)
	(segment
		(start 164.599874 -41.599866)
		(end 164.999924 -41.199816)
		(width 0.3048)
		(layer "F.Cu")
		(net "GND")
	)
	(segment
		(start 93.149674 -73.152)
		(end 92.962984 -72.96531)
		(width 0.508)
		(layer "F.Cu")
		(net "GND")
	)
	(segment
		(start 69.249798 -80.04683)
		(end 69.249798 -79.186024)
		(width 0.3556)
		(layer "F.Cu")
		(net "GND")
	)
	(segment
		(start 102.499922 -64.499998)
		(end 103.000048 -65.000124)
		(width 0.4572)
		(layer "F.Cu")
		(net "GND")
	)
	(segment
		(start 170.599862 -33.99028)
		(end 170.209464 -33.599882)
		(width 0.3556)
		(layer "F.Cu")
		(net "GND")
	)
	(segment
		(start 98.780346 -85.791802)
		(end 98.947986 -85.624162)
		(width 0.508)
		(layer "F.Cu")
		(net "GND")
	)
	(segment
		(start 177.000154 -48.399954)
		(end 177.39995 -48.79975)
		(width 0.3556)
		(layer "F.Cu")
		(net "GND")
	)
	(segment
		(start 172.199808 -31.599886)
		(end 172.600112 -32.00019)
		(width 0.3048)
		(layer "F.Cu")
		(net "GND")
	)
	(segment
		(start 168.999408 -44.399962)
		(end 168.599612 -44.799758)
		(width 0.3556)
		(layer "F.Cu")
		(net "GND")
	)
	(segment
		(start 17.9451 -86.53653)
		(end 18.07591 -86.66734)
		(width 0.3556)
		(layer "F.Cu")
		(net "GND")
	)
	(segment
		(start 69.38391 -80.569054)
		(end 69.37121 -80.556354)
		(width 0.508)
		(layer "F.Cu")
		(net "GND")
	)
	(segment
		(start 23.43404 -86.592156)
		(end 23.43404 -87.4268)
		(width 0.3556)
		(layer "F.Cu")
		(net "GND")
	)
	(segment
		(start 176.1998 -47.599854)
		(end 175.800004 -47.200058)
		(width 0.3556)
		(layer "F.Cu")
		(net "GND")
	)
	(segment
		(start 168.199816 -45.199808)
		(end 168.199816 -45.199554)
		(width 0.3556)
		(layer "F.Cu")
		(net "GND")
	)
	(segment
		(start 172.199808 -29.19984)
		(end 172.199808 -29.200094)
		(width 0.3048)
		(layer "F.Cu")
		(net "GND")
	)
	(segment
		(start 120.50014 -54.500018)
		(end 121.000012 -54.000146)
		(width 0.4572)
		(layer "F.Cu")
		(net "GND")
	)
	(segment
		(start 174.599854 -38.800024)
		(end 174.600108 -38.800024)
		(width 0.3556)
		(layer "F.Cu")
		(net "GND")
	)
	(segment
		(start 59.7789 -80.118966)
		(end 59.657488 -79.997554)
		(width 0.3556)
		(layer "F.Cu")
		(net "GND")
	)
	(segment
		(start 168.999662 -41.199816)
		(end 168.599612 -40.799766)
		(width 0.3556)
		(layer "F.Cu")
		(net "GND")
	)
	(segment
		(start 159.37357 -47.082456)
		(end 159.37357 -45.595032)
		(width 0.508)
		(layer "F.Cu")
		(net "GND")
	)
	(segment
		(start 102.558596 -57.441338)
		(end 103.441246 -57.441338)
		(width 0.4572)
		(layer "F.Cu")
		(net "GND")
	)
	(segment
		(start 167.399716 -33.199832)
		(end 166.99992 -32.800036)
		(width 0.3556)
		(layer "F.Cu")
		(net "GND")
	)
	(segment
		(start 105.499916 -78.500224)
		(end 105.499916 -78.49997)
		(width 0.4572)
		(layer "F.Cu")
		(net "GND")
	)
	(segment
		(start 120.000014 -66.000122)
		(end 119.500142 -65.50025)
		(width 0.4572)
		(layer "F.Cu")
		(net "GND")
	)
	(segment
		(start 115.50015 -71.500238)
		(end 115.50015 -71.499984)
		(width 0.3556)
		(layer "F.Cu")
		(net "GND")
	)
	(segment
		(start 169.800016 -45.999908)
		(end 170.20032 -46.400212)
		(width 0.3556)
		(layer "F.Cu")
		(net "GND")
	)
	(segment
		(start 123.500134 -68.500244)
		(end 124.000006 -69.000116)
		(width 0.4572)
		(layer "F.Cu")
		(net "GND")
	)
	(segment
		(start 55.499 -80.6577)
		(end 55.3593 -80.518)
		(width 0.508)
		(layer "F.Cu")
		(net "GND")
	)
	(segment
		(start 170.599862 -34.800032)
		(end 170.600116 -34.800032)
		(width 0.3556)
		(layer "F.Cu")
		(net "GND")
	)
	(segment
		(start 171.399962 -50.8)
		(end 171.799758 -51.199796)
		(width 0.3556)
		(layer "F.Cu")
		(net "GND")
	)
	(segment
		(start 172.199808 -33.199832)
		(end 172.999908 -33.999932)
		(width 0.3556)
		(layer "F.Cu")
		(net "GND")
	)
	(segment
		(start 173.000924 -34.800032)
		(end 173.400466 -34.40049)
		(width 0.3556)
		(layer "F.Cu")
		(net "GND")
	)
	(segment
		(start 115.50015 -66.499994)
		(end 116.000022 -66.000122)
		(width 0.4064)
		(layer "F.Cu")
		(net "GND")
	)
	(segment
		(start 169.800016 -41.199816)
		(end 168.999916 -41.999916)
		(width 0.3556)
		(layer "F.Cu")
		(net "GND")
	)
	(segment
		(start 120.499886 -71.500238)
		(end 120.50014 -71.500238)
		(width 0.4572)
		(layer "F.Cu")
		(net "GND")
	)
	(segment
		(start 167.399716 -30.80004)
		(end 167.39997 -30.80004)
		(width 0.3048)
		(layer "F.Cu")
		(net "GND")
	)
	(segment
		(start 127.500126 -56.500014)
		(end 127.999998 -56.000142)
		(width 0.4572)
		(layer "F.Cu")
		(net "GND")
	)
	(segment
		(start 171.3992 -34.800032)
		(end 170.999658 -35.199574)
		(width 0.3556)
		(layer "F.Cu")
		(net "GND")
	)
	(segment
		(start 166.59987 -38.800024)
		(end 166.609522 -38.800024)
		(width 0.3556)
		(layer "F.Cu")
		(net "GND")
	)
	(segment
		(start 166.59987 -29.19984)
		(end 166.19982 -28.79979)
		(width 0.3048)
		(layer "F.Cu")
		(net "GND")
	)
	(segment
		(start 180.999892 -44.399962)
		(end 180.999892 -44.399454)
		(width 0.3556)
		(layer "F.Cu")
		(net "GND")
	)
	(segment
		(start 170.599862 -37.999924)
		(end 171.399962 -38.800024)
		(width 0.3556)
		(layer "F.Cu")
		(net "GND")
	)
	(segment
		(start 164.999924 -34.00044)
		(end 164.999924 -33.999932)
		(width 0.3048)
		(layer "F.Cu")
		(net "GND")
	)
	(segment
		(start 181.799992 -39.59987)
		(end 181.799484 -39.59987)
		(width 0.3556)
		(layer "F.Cu")
		(net "GND")
	)
	(segment
		(start 6.731 -39.8145)
		(end 5.7277 -39.8145)
		(width 0.508)
		(layer "F.Cu")
		(net "GND")
	)
	(segment
		(start 122.500136 -59.500008)
		(end 122.499882 -59.500008)
		(width 0.4572)
		(layer "F.Cu")
		(net "GND")
	)
	(segment
		(start 108.49991 -57.500012)
		(end 108.000038 -57.00014)
		(width 0.4572)
		(layer "F.Cu")
		(net "GND")
	)
	(segment
		(start 176.1998 -37.199824)
		(end 176.59985 -37.599874)
		(width 0.3556)
		(layer "F.Cu")
		(net "GND")
	)
	(segment
		(start 118.000018 -66.000122)
		(end 117.500146 -66.499994)
		(width 0.4064)
		(layer "F.Cu")
		(net "GND")
	)
	(segment
		(start 183.399938 -38.800024)
		(end 183.399684 -38.800024)
		(width 0.3556)
		(layer "F.Cu")
		(net "GND")
	)
	(segment
		(start 168.999916 -38.800024)
		(end 168.999408 -38.800024)
		(width 0.3556)
		(layer "F.Cu")
		(net "GND")
	)
	(segment
		(start 164.999924 -30.80004)
		(end 164.999924 -30.800294)
		(width 0.3048)
		(layer "F.Cu")
		(net "GND")
	)
	(segment
		(start 109.499908 -59.500008)
		(end 108.49991 -60.500006)
		(width 0.4572)
		(layer "F.Cu")
		(net "GND")
	)
	(segment
		(start 180.199792 -36.399978)
		(end 180.599842 -35.999928)
		(width 0.3556)
		(layer "F.Cu")
		(net "GND")
	)
	(segment
		(start 171.399962 -29.99994)
		(end 171.318428 -29.99994)
		(width 0.3048)
		(layer "F.Cu")
		(net "GND")
	)
	(segment
		(start 150.8125 -84.9249)
		(end 149.9108 -84.9249)
		(width 0.508)
		(layer "F.Cu")
		(net "GND")
	)
	(segment
		(start 74.8919 -83.3882)
		(end 74.8919 -82.7024)
		(width 0.508)
		(layer "F.Cu")
		(net "GND")
	)
	(segment
		(start 168.199816 -46.800008)
		(end 168.199816 -46.7995)
		(width 0.3556)
		(layer "F.Cu")
		(net "GND")
	)
	(segment
		(start 185.799984 -42.800016)
		(end 185.79973 -42.800016)
		(width 0.3556)
		(layer "F.Cu")
		(net "GND")
	)
	(segment
		(start 176.1998 -44.399962)
		(end 176.59985 -43.999912)
		(width 0.3556)
		(layer "F.Cu")
		(net "GND")
	)
	(segment
		(start 174.599854 -49.9999)
		(end 174.5996 -49.9999)
		(width 0.3556)
		(layer "F.Cu")
		(net "GND")
	)
	(segment
		(start 121.500138 -67.500246)
		(end 122.00001 -68.000118)
		(width 0.4572)
		(layer "F.Cu")
		(net "GND")
	)
	(segment
		(start 181.799992 -42.799508)
		(end 182.199788 -42.399712)
		(width 0.3556)
		(layer "F.Cu")
		(net "GND")
	)
	(segment
		(start 103.49992 -64.500252)
		(end 103.49992 -64.499998)
		(width 0.4572)
		(layer "F.Cu")
		(net "GND")
	)
	(segment
		(start 12.4333 -85.26907)
		(end 12.4333 -85.7504)
		(width 0.508)
		(layer "F.Cu")
		(net "GND")
	)
	(segment
		(start 181.799738 -47.599854)
		(end 180.999892 -46.800008)
		(width 0.3048)
		(layer "F.Cu")
		(net "GND")
	)
	(segment
		(start 174.402496 -30.997398)
		(end 174.402496 -31.402528)
		(width 0.3048)
		(layer "F.Cu")
		(net "GND")
	)
	(segment
		(start 103.49992 -74.500232)
		(end 103.000048 -75.000104)
		(width 0.4572)
		(layer "F.Cu")
		(net "GND")
	)
	(segment
		(start 172.999908 -48.399954)
		(end 172.999908 -48.399446)
		(width 0.3556)
		(layer "F.Cu")
		(net "GND")
	)
	(segment
		(start 121.500138 -59.500008)
		(end 122.00001 -59.000136)
		(width 0.4572)
		(layer "F.Cu")
		(net "GND")
	)
	(segment
		(start 184.199784 -41.199816)
		(end 184.199784 -41.20007)
		(width 0.3048)
		(layer "F.Cu")
		(net "GND")
	)
	(segment
		(start 177.8 -45.199808)
		(end 178.20005 -45.599858)
		(width 0.3048)
		(layer "F.Cu")
		(net "GND")
	)
	(segment
		(start 122.00001 -65.000124)
		(end 122.499882 -65.499996)
		(width 0.4572)
		(layer "F.Cu")
		(net "GND")
	)
	(segment
		(start 173.799754 -36.399978)
		(end 172.999908 -37.199824)
		(width 0.3556)
		(layer "F.Cu")
		(net "GND")
	)
	(segment
		(start 104.499918 -62.500002)
		(end 104.000046 -62.00013)
		(width 0.4572)
		(layer "F.Cu")
		(net "GND")
	)
	(segment
		(start 121.500138 -51.500024)
		(end 122.00001 -51.000152)
		(width 0.4572)
		(layer "F.Cu")
		(net "GND")
	)
	(segment
		(start 169.800016 -29.19984)
		(end 169.399966 -29.59989)
		(width 0.3048)
		(layer "F.Cu")
		(net "GND")
	)
	(segment
		(start 191.136016 -80.564736)
		(end 190.787782 -80.216502)
		(width 0.508)
		(layer "F.Cu")
		(net "GND")
	)
	(segment
		(start 167.39997 -33.199832)
		(end 167.399716 -33.199832)
		(width 0.3556)
		(layer "F.Cu")
		(net "GND")
	)
	(segment
		(start 167.39997 -32.399986)
		(end 166.99992 -32.800036)
		(width 0.3556)
		(layer "F.Cu")
		(net "GND")
	)
	(segment
		(start 6.8453 -74.2188)
		(end 5.8674 -74.2188)
		(width 0.508)
		(layer "F.Cu")
		(net "GND")
	)
	(segment
		(start 113.999772 -66.000122)
		(end 114.499898 -65.499996)
		(width 0.4064)
		(layer "F.Cu")
		(net "GND")
	)
	(segment
		(start 171.799758 -29.600144)
		(end 171.399962 -29.99994)
		(width 0.3048)
		(layer "F.Cu")
		(net "GND")
	)
	(segment
		(start 182.599584 -41.199816)
		(end 182.199788 -41.599612)
		(width 0.3556)
		(layer "F.Cu")
		(net "GND")
	)
	(segment
		(start 117.500146 -59.500008)
		(end 116.500148 -60.500006)
		(width 0.4572)
		(layer "F.Cu")
		(net "GND")
	)
	(segment
		(start 171.399962 -48.399954)
		(end 171.400216 -48.399954)
		(width 0.3556)
		(layer "F.Cu")
		(net "GND")
	)
	(segment
		(start 168.999916 -29.99994)
		(end 169.399966 -29.59989)
		(width 0.3048)
		(layer "F.Cu")
		(net "GND")
	)
	(segment
		(start 167.799766 -35.200336)
		(end 167.39997 -34.80054)
		(width 0.3048)
		(layer "F.Cu")
		(net "GND")
	)
	(segment
		(start 160.7312 -86.741)
		(end 160.7312 -87.5919)
		(width 0.508)
		(layer "F.Cu")
		(net "GND")
	)
	(segment
		(start 181.799992 -41.199816)
		(end 181.799484 -41.199816)
		(width 0.3556)
		(layer "F.Cu")
		(net "GND")
	)
	(segment
		(start 119.500142 -68.49999)
		(end 119.500142 -68.500244)
		(width 0.4572)
		(layer "F.Cu")
		(net "GND")
	)
	(segment
		(start 120.50014 -58.50001)
		(end 121.500138 -57.500012)
		(width 0.4572)
		(layer "F.Cu")
		(net "GND")
	)
	(segment
		(start 110.499906 -69.500242)
		(end 110.000034 -70.000114)
		(width 0.4572)
		(layer "F.Cu")
		(net "GND")
	)
	(segment
		(start 169.800016 -35.599878)
		(end 169.399712 -35.199574)
		(width 0.3556)
		(layer "F.Cu")
		(net "GND")
	)
	(segment
		(start 193.42608 -88.952324)
		(end 193.42608 -86.13394)
		(width 0.9906)
		(layer "F.Cu")
		(net "GND")
	)
	(segment
		(start 119.500142 -59.500008)
		(end 120.000014 -59.000136)
		(width 0.4572)
		(layer "F.Cu")
		(net "GND")
	)
	(segment
		(start 169.800524 -46.800008)
		(end 170.20032 -46.400212)
		(width 0.3556)
		(layer "F.Cu")
		(net "GND")
	)
	(segment
		(start 118.49989 -63.5)
		(end 118.500144 -63.5)
		(width 0.4572)
		(layer "F.Cu")
		(net "GND")
	)
	(segment
		(start 106.499914 -57.500012)
		(end 106.000042 -57.00014)
		(width 0.4572)
		(layer "F.Cu")
		(net "GND")
	)
	(segment
		(start 104.499918 -57.500012)
		(end 104.000046 -57.00014)
		(width 0.4572)
		(layer "F.Cu")
		(net "GND")
	)
	(segment
		(start 178.6001 -34.800032)
		(end 178.599846 -34.800032)
		(width 0.3556)
		(layer "F.Cu")
		(net "GND")
	)
	(segment
		(start 181.799992 -45.999908)
		(end 182.199788 -46.399704)
		(width 0.3556)
		(layer "F.Cu")
		(net "GND")
	)
	(segment
		(start 119.500142 -64.499998)
		(end 120.000014 -64.000126)
		(width 0.4572)
		(layer "F.Cu")
		(net "GND")
	)
	(segment
		(start 168.999408 -42.800016)
		(end 168.599612 -43.199812)
		(width 0.3556)
		(layer "F.Cu")
		(net "GND")
	)
	(segment
		(start 160.7185 -84.9122)
		(end 160.7185 -85.725)
		(width 0.508)
		(layer "F.Cu")
		(net "GND")
	)
	(segment
		(start 182.599838 -31.599886)
		(end 182.199788 -31.199836)
		(width 0.3048)
		(layer "F.Cu")
		(net "GND")
	)
	(segment
		(start 125.000004 -52.00015)
		(end 125.499876 -52.500022)
		(width 0.4572)
		(layer "F.Cu")
		(net "GND")
	)
	(segment
		(start 113.500154 -61.500004)
		(end 113.4999 -61.500004)
		(width 0.4572)
		(layer "F.Cu")
		(net "GND")
	)
	(segment
		(start 176.9999 -32.399986)
		(end 177.39995 -32.800036)
		(width 0.3556)
		(layer "F.Cu")
		(net "GND")
	)
	(segment
		(start 106.499914 -75.50023)
		(end 106.000042 -76.000102)
		(width 0.4572)
		(layer "F.Cu")
		(net "GND")
	)
	(segment
		(start 183.399938 -48.399954)
		(end 183.399684 -48.399954)
		(width 0.3556)
		(layer "F.Cu")
		(net "GND")
	)
	(segment
		(start 181.799992 -36.399978)
		(end 181.79923 -36.399978)
		(width 0.3556)
		(layer "F.Cu")
		(net "GND")
	)
	(segment
		(start 121.500138 -68.500244)
		(end 122.00001 -69.000116)
		(width 0.4572)
		(layer "F.Cu")
		(net "GND")
	)
	(segment
		(start 106.499914 -59.4995)
		(end 106.999532 -58.999882)
		(width 0.4572)
		(layer "F.Cu")
		(net "GND")
	)
	(segment
		(start 178.199796 -35.199828)
		(end 178.599846 -34.799778)
		(width 0.3556)
		(layer "F.Cu")
		(net "GND")
	)
	(segment
		(start 167.39997 -34.80054)
		(end 167.39997 -34.800032)
		(width 0.3048)
		(layer "F.Cu")
		(net "GND")
	)
	(segment
		(start 170.599862 -37.999924)
		(end 170.599862 -37.999162)
		(width 0.3556)
		(layer "F.Cu")
		(net "GND")
	)
	(segment
		(start 123.500134 -61.500004)
		(end 124.000006 -61.000132)
		(width 0.4572)
		(layer "F.Cu")
		(net "GND")
	)
	(segment
		(start 125.499876 -51.500024)
		(end 125.50013 -51.500024)
		(width 0.4572)
		(layer "F.Cu")
		(net "GND")
	)
	(segment
		(start 74.8919 -82.7024)
		(end 74.7395 -82.55)
		(width 0.508)
		(layer "F.Cu")
		(net "GND")
	)
	(segment
		(start 165.800024 -48.399954)
		(end 165.399974 -47.999904)
		(width 0.3556)
		(layer "F.Cu")
		(net "GND")
	)
	(segment
		(start 176.9999 -34.799778)
		(end 176.599596 -34.399474)
		(width 0.3556)
		(layer "F.Cu")
		(net "GND")
	)
	(segment
		(start 171.399962 -35.599878)
		(end 170.999658 -35.199574)
		(width 0.3556)
		(layer "F.Cu")
		(net "GND")
	)
	(segment
		(start 175.399954 -45.999908)
		(end 175.400208 -45.999908)
		(width 0.3556)
		(layer "F.Cu")
		(net "GND")
	)
	(segment
		(start 85.64753 -52.34686)
		(end 85.637878 -52.337208)
		(width 0.508)
		(layer "F.Cu")
		(net "GND")
	)
	(segment
		(start 102.499922 -54.500018)
		(end 102.00005 -54.000146)
		(width 0.4572)
		(layer "F.Cu")
		(net "GND")
	)
	(segment
		(start 83.15071 -109.006894)
		(end 83.15071 -110.167928)
		(width 0.381)
		(layer "F.Cu")
		(net "GND")
	)
	(segment
		(start 104.499918 -58.50001)
		(end 105.499916 -57.500012)
		(width 0.4572)
		(layer "F.Cu")
		(net "GND")
	)
	(segment
		(start 123.500134 -73.500234)
		(end 124.000006 -74.000106)
		(width 0.4572)
		(layer "F.Cu")
		(net "GND")
	)
	(segment
		(start 177.8 -40.39997)
		(end 178.199796 -40.799766)
		(width 0.3556)
		(layer "F.Cu")
		(net "GND")
	)
	(segment
		(start 116.000022 -68.000372)
		(end 116.500148 -67.500246)
		(width 0.4064)
		(layer "F.Cu")
		(net "GND")
	)
	(segment
		(start 109.499908 -66.499994)
		(end 109.499908 -66.500248)
		(width 0.4064)
		(layer "F.Cu")
		(net "GND")
	)
	(segment
		(start 173.799754 -41.199816)
		(end 173.399958 -40.80002)
		(width 0.3556)
		(layer "F.Cu")
		(net "GND")
	)
	(segment
		(start 183.399938 -33.999932)
		(end 182.999888 -34.399982)
		(width 0.3556)
		(layer "F.Cu")
		(net "GND")
	)
	(segment
		(start 127.500126 -76.500228)
		(end 127.999998 -77.0001)
		(width 0.4572)
		(layer "F.Cu")
		(net "GND")
	)
	(segment
		(start 107.499912 -59.500008)
		(end 107.499658 -59.500008)
		(width 0.4572)
		(layer "F.Cu")
		(net "GND")
	)
	(segment
		(start 183.399684 -38.800024)
		(end 182.999888 -39.19982)
		(width 0.3556)
		(layer "F.Cu")
		(net "GND")
	)
	(segment
		(start 170.305476 -109.716824)
		(end 169.523156 -109.716824)
		(width 0.3556)
		(layer "F.Cu")
		(net "GND")
	)
	(segment
		(start 103.49992 -66.499994)
		(end 103.000048 -66.000122)
		(width 0.4572)
		(layer "F.Cu")
		(net "GND")
	)
	(segment
		(start 164.999924 -32.40024)
		(end 164.600128 -32.800036)
		(width 0.3048)
		(layer "F.Cu")
		(net "GND")
	)
	(segment
		(start 131.316984 -55.500016)
		(end 130.50012 -55.500016)
		(width 0.4064)
		(layer "F.Cu")
		(net "GND")
	)
	(segment
		(start 110.499906 -60.50026)
		(end 110.000034 -61.000132)
		(width 0.4572)
		(layer "F.Cu")
		(net "GND")
	)
	(segment
		(start 167.39997 -37.999924)
		(end 167.39997 -38.009576)
		(width 0.3556)
		(layer "F.Cu")
		(net "GND")
	)
	(segment
		(start 170.199812 -39.19982)
		(end 169.800016 -38.800024)
		(width 0.3556)
		(layer "F.Cu")
		(net "GND")
	)
	(segment
		(start 124.000006 -61.000132)
		(end 123.500134 -60.50026)
		(width 0.4572)
		(layer "F.Cu")
		(net "GND")
	)
	(segment
		(start 119.500142 -70.499986)
		(end 119.500142 -70.50024)
		(width 0.4572)
		(layer "F.Cu")
		(net "GND")
	)
	(segment
		(start 179.92217 -115.496848)
		(end 178.88077 -115.496848)
		(width 0.254)
		(layer "F.Cu")
		(net "GND")
	)
	(segment
		(start 182.599838 -39.59987)
		(end 182.999888 -39.19982)
		(width 0.3556)
		(layer "F.Cu")
		(net "GND")
	)
	(segment
		(start 112.499902 -61.500004)
		(end 112.00003 -61.000132)
		(width 0.4572)
		(layer "F.Cu")
		(net "GND")
	)
	(segment
		(start 180.199792 -42.800016)
		(end 179.799742 -42.399966)
		(width 0.3556)
		(layer "F.Cu")
		(net "GND")
	)
	(segment
		(start 171.399962 -32.399986)
		(end 171.000166 -32.00019)
		(width 0.3048)
		(layer "F.Cu")
		(net "GND")
	)
	(segment
		(start 128.500124 -77.500226)
		(end 128.999996 -78.000098)
		(width 0.4572)
		(layer "F.Cu")
		(net "GND")
	)
	(segment
		(start 106.49966 -58.50001)
		(end 106.499914 -58.50001)
		(width 0.4572)
		(layer "F.Cu")
		(net "GND")
	)
	(segment
		(start 175.399954 -33.999932)
		(end 175.799496 -34.399474)
		(width 0.3556)
		(layer "F.Cu")
		(net "GND")
	)
	(segment
		(start 107.499912 -74.500232)
		(end 107.499912 -74.499978)
		(width 0.4572)
		(layer "F.Cu")
		(net "GND")
	)
	(segment
		(start 166.609522 -38.800024)
		(end 166.99992 -38.409626)
		(width 0.3556)
		(layer "F.Cu")
		(net "GND")
	)
	(segment
		(start 166.599616 -42.800016)
		(end 166.19982 -43.199812)
		(width 0.3556)
		(layer "F.Cu")
		(net "GND")
	)
	(segment
		(start 175.399954 -33.199832)
		(end 175.401986 -33.199832)
		(width 0.3556)
		(layer "F.Cu")
		(net "GND")
	)
	(segment
		(start 164.608002 -35.998658)
		(end 164.608002 -36.008056)
		(width 0.3048)
		(layer "F.Cu")
		(net "GND")
	)
	(segment
		(start 109.499908 -68.500244)
		(end 109.000036 -69.000116)
		(width 0.4572)
		(layer "F.Cu")
		(net "GND")
	)
	(segment
		(start 182.599838 -49.1998)
		(end 182.999888 -48.79975)
		(width 0.3556)
		(layer "F.Cu")
		(net "GND")
	)
	(segment
		(start 50.028602 -30.110176)
		(end 50.028602 -30.995366)
		(width 0.508)
		(layer "F.Cu")
		(net "GND")
	)
	(segment
		(start 193.15049 -44.12361)
		(end 192.291208 -44.12361)
		(width 0.508)
		(layer "F.Cu")
		(net "GND")
	)
	(segment
		(start 165.800024 -38.800024)
		(end 165.399974 -38.399974)
		(width 0.3048)
		(layer "F.Cu")
		(net "GND")
	)
	(segment
		(start 169.00017 -34.800032)
		(end 169.399712 -35.199574)
		(width 0.3556)
		(layer "F.Cu")
		(net "GND")
	)
	(segment
		(start 177.8 -45.999908)
		(end 177.800254 -45.999908)
		(width 0.3556)
		(layer "F.Cu")
		(net "GND")
	)
	(segment
		(start 91.4527 -84.836)
		(end 91.4527 -85.6488)
		(width 0.508)
		(layer "F.Cu")
		(net "GND")
	)
	(segment
		(start 108.49991 -61.500004)
		(end 109.499908 -61.500004)
		(width 0.4572)
		(layer "F.Cu")
		(net "GND")
	)
	(segment
		(start 175.399954 -46.799754)
		(end 175.800004 -46.399704)
		(width 0.3556)
		(layer "F.Cu")
		(net "GND")
	)
	(segment
		(start 12.7635 -99.1743)
		(end 12.6238 -99.314)
		(width 0.508)
		(layer "F.Cu")
		(net "GND")
	)
	(segment
		(start 18.07591 -86.66734)
		(end 18.07591 -87.479378)
		(width 0.3556)
		(layer "F.Cu")
		(net "GND")
	)
	(segment
		(start 180.199792 -40.39997)
		(end 180.199538 -40.39997)
		(width 0.3556)
		(layer "F.Cu")
		(net "GND")
	)
	(segment
		(start 185.79973 -42.800016)
		(end 184.999884 -42.800016)
		(width 0.3556)
		(layer "F.Cu")
		(net "GND")
	)
	(segment
		(start 170.599608 -41.999916)
		(end 170.199812 -42.399712)
		(width 0.3556)
		(layer "F.Cu")
		(net "GND")
	)
	(segment
		(start 172.199808 -34.800032)
		(end 171.800266 -34.40049)
		(width 0.3556)
		(layer "F.Cu")
		(net "GND")
	)
	(segment
		(start 121.500138 -66.499994)
		(end 122.00001 -66.000122)
		(width 0.4572)
		(layer "F.Cu")
		(net "GND")
	)
	(segment
		(start 9.3599 -99.93376)
		(end 7.93496 -99.93376)
		(width 0.4064)
		(layer "F.Cu")
		(net "GND")
	)
	(segment
		(start 169.800016 -44.399454)
		(end 170.199812 -43.999658)
		(width 0.3556)
		(layer "F.Cu")
		(net "GND")
	)
	(segment
		(start 171.399962 -43.600116)
		(end 171.000166 -43.999912)
		(width 0.3556)
		(layer "F.Cu")
		(net "GND")
	)
	(segment
		(start 120.000014 -70.000114)
		(end 119.500142 -70.499986)
		(width 0.4572)
		(layer "F.Cu")
		(net "GND")
	)
	(segment
		(start 106.999532 -58.999882)
		(end 106.49966 -58.50001)
		(width 0.4572)
		(layer "F.Cu")
		(net "GND")
	)
	(segment
		(start 174.599854 -33.999932)
		(end 175.000412 -34.40049)
		(width 0.3556)
		(layer "F.Cu")
		(net "GND")
	)
	(segment
		(start 101.499924 -82.500216)
		(end 101.000052 -83.000088)
		(width 0.508)
		(layer "F.Cu")
		(net "GND")
	)
	(segment
		(start 121.500138 -69.500242)
		(end 122.00001 -70.000114)
		(width 0.4572)
		(layer "F.Cu")
		(net "GND")
	)
	(segment
		(start 104.499918 -82.500216)
		(end 104.000046 -83.000088)
		(width 0.4572)
		(layer "F.Cu")
		(net "GND")
	)
	(segment
		(start 113.4999 -64.499998)
		(end 112.499902 -63.5)
		(width 0.4572)
		(layer "F.Cu")
		(net "GND")
	)
	(segment
		(start 193.1924 -44.1198)
		(end 193.1543 -44.1198)
		(width 0.508)
		(layer "F.Cu")
		(net "GND")
	)
	(segment
		(start 172.999908 -48.399446)
		(end 173.399704 -47.99965)
		(width 0.3556)
		(layer "F.Cu")
		(net "GND")
	)
	(segment
		(start 176.9999 -47.599854)
		(end 176.999646 -47.599854)
		(width 0.3556)
		(layer "F.Cu")
		(net "GND")
	)
	(segment
		(start 179.399946 -45.199808)
		(end 178.599846 -45.999908)
		(width 0.3556)
		(layer "F.Cu")
		(net "GND")
	)
	(segment
		(start 11.9126 -95.245682)
		(end 11.9126 -96.071182)
		(width 0.508)
		(layer "F.Cu")
		(net "GND")
	)
	(segment
		(start 103.000048 -65.000124)
		(end 103.49992 -64.500252)
		(width 0.4572)
		(layer "F.Cu")
		(net "GND")
	)
	(segment
		(start 164.608002 -36.008056)
		(end 164.999924 -36.399978)
		(width 0.3048)
		(layer "F.Cu")
		(net "GND")
	)
	(segment
		(start 113.4999 -59.500008)
		(end 113.999772 -59.000136)
		(width 0.4572)
		(layer "F.Cu")
		(net "GND")
	)
	(segment
		(start 184.199784 -39.600124)
		(end 183.399938 -40.39997)
		(width 0.3556)
		(layer "F.Cu")
		(net "GND")
	)
	(segment
		(start 164.999924 -30.800294)
		(end 164.600128 -31.20009)
		(width 0.3048)
		(layer "F.Cu")
		(net "GND")
	)
	(segment
		(start 170.791378 -29.883354)
		(end 170.674792 -29.99994)
		(width 0.3048)
		(layer "F.Cu")
		(net "GND")
	)
	(segment
		(start 124.500132 -60.500006)
		(end 125.000004 -60.000134)
		(width 0.4572)
		(layer "F.Cu")
		(net "GND")
	)
	(segment
		(start 183.399938 -41.999916)
		(end 183.39943 -41.999916)
		(width 0.3556)
		(layer "F.Cu")
		(net "GND")
	)
	(segment
		(start 122.00001 -68.000118)
		(end 122.499882 -67.500246)
		(width 0.4572)
		(layer "F.Cu")
		(net "GND")
	)
	(segment
		(start 164.199824 -29.19984)
		(end 164.999924 -29.99994)
		(width 0.3048)
		(layer "F.Cu")
		(net "GND")
	)
	(segment
		(start 59.7789 -80.4926)
		(end 59.7789 -80.118966)
		(width 0.3556)
		(layer "F.Cu")
		(net "GND")
	)
	(segment
		(start 102.499922 -57.500012)
		(end 102.558596 -57.441338)
		(width 0.4572)
		(layer "F.Cu")
		(net "GND")
	)
	(segment
		(start 109.499908 -63.5)
		(end 109.000036 -63.000128)
		(width 0.4572)
		(layer "F.Cu")
		(net "GND")
	)
	(segment
		(start 179.399946 -31.599886)
		(end 179.00015 -31.20009)
		(width 0.3048)
		(layer "F.Cu")
		(net "GND")
	)
	(segment
		(start 109.000036 -63.000128)
		(end 108.49991 -62.500002)
		(width 0.4572)
		(layer "F.Cu")
		(net "GND")
	)
	(segment
		(start 100.499926 -64.499998)
		(end 100.000054 -64.000126)
		(width 0.4572)
		(layer "F.Cu")
		(net "GND")
	)
	(segment
		(start 172.199808 -46.800008)
		(end 172.200316 -46.800008)
		(width 0.3556)
		(layer "F.Cu")
		(net "GND")
	)
	(segment
		(start 57.3405 -24.13)
		(end 58.166 -24.13)
		(width 0.508)
		(layer "F.Cu")
		(net "GND")
	)
	(segment
		(start 93.63837 -69.977)
		(end 92.962984 -69.301614)
		(width 0.508)
		(layer "F.Cu")
		(net "GND")
	)
	(segment
		(start 172.999908 -38.800024)
		(end 173.000162 -38.800024)
		(width 0.3556)
		(layer "F.Cu")
		(net "GND")
	)
	(segment
		(start 109.000036 -71.000112)
		(end 108.49991 -71.500238)
		(width 0.4572)
		(layer "F.Cu")
		(net "GND")
	)
	(segment
		(start 171.399962 -41.999916)
		(end 171.399962 -42.00017)
		(width 0.3556)
		(layer "F.Cu")
		(net "GND")
	)
	(segment
		(start 14.230604 -63.535306)
		(end 14.230604 -65.053718)
		(width 0.508)
		(layer "F.Cu")
		(net "GND")
	)
	(segment
		(start 184.199784 -37.999924)
		(end 184.199784 -38.000178)
		(width 0.3556)
		(layer "F.Cu")
		(net "GND")
	)
	(segment
		(start 87.602314 -52.34686)
		(end 85.64753 -52.34686)
		(width 0.508)
		(layer "F.Cu")
		(net "GND")
	)
	(segment
		(start 186.59983 -42.800016)
		(end 186.599322 -42.800016)
		(width 0.3556)
		(layer "F.Cu")
		(net "GND")
	)
	(segment
		(start 19.7231 -74.0918)
		(end 20.574 -74.0918)
		(width 0.508)
		(layer "F.Cu")
		(net "GND")
	)
	(segment
		(start 107.00004 -71.000112)
		(end 106.499914 -71.500238)
		(width 0.4572)
		(layer "F.Cu")
		(net "GND")
	)
	(segment
		(start 177.8 -46.800008)
		(end 177.8 -46.799754)
		(width 0.3556)
		(layer "F.Cu")
		(net "GND")
	)
	(segment
		(start 8.23087 -47.692818)
		(end 7.22757 -47.692818)
		(width 0.508)
		(layer "F.Cu")
		(net "GND")
	)
	(segment
		(start 171.399962 -51.599846)
		(end 171.799758 -51.999642)
		(width 0.3556)
		(layer "F.Cu")
		(net "GND")
	)
	(segment
		(start 14.56182 -101.44506)
		(end 13.72616 -101.44506)
		(width 0.508)
		(layer "F.Cu")
		(net "GND")
	)
	(segment
		(start 197.269862 -70.77964)
		(end 197.72376 -70.77964)
		(width 0.3048)
		(layer "F.Cu")
		(net "GND")
	)
	(segment
		(start 176.9999 -33.199832)
		(end 177.000154 -33.199832)
		(width 0.3556)
		(layer "F.Cu")
		(net "GND")
	)
	(segment
		(start 8.5598 -57.6453)
		(end 8.5598 -58.5724)
		(width 0.508)
		(layer "F.Cu")
		(net "GND")
	)
	(segment
		(start 108.000038 -66.000122)
		(end 107.500166 -66.499994)
		(width 0.4572)
		(layer "F.Cu")
		(net "GND")
	)
	(segment
		(start 178.599846 -33.999932)
		(end 178.599846 -34.000186)
		(width 0.3556)
		(layer "F.Cu")
		(net "GND")
	)
	(segment
		(start 122.499882 -59.500008)
		(end 122.00001 -59.000136)
		(width 0.4572)
		(layer "F.Cu")
		(net "GND")
	)
	(segment
		(start 165.800024 -51.997102)
		(end 165.800024 -51.599846)
		(width 0.3556)
		(layer "F.Cu")
		(net "GND")
	)
	(segment
		(start 101.499924 -68.500244)
		(end 101.000052 -69.000116)
		(width 0.4572)
		(layer "F.Cu")
		(net "GND")
	)
	(segment
		(start 175.399954 -36.399978)
		(end 175.3997 -36.399978)
		(width 0.3556)
		(layer "F.Cu")
		(net "GND")
	)
	(segment
		(start 121.500138 -62.500002)
		(end 122.00001 -62.00013)
		(width 0.4572)
		(layer "F.Cu")
		(net "GND")
	)
	(segment
		(start 124.500132 -67.500246)
		(end 125.000004 -68.000118)
		(width 0.4572)
		(layer "F.Cu")
		(net "GND")
	)
	(segment
		(start 124.500132 -53.50002)
		(end 125.000004 -53.000148)
		(width 0.4572)
		(layer "F.Cu")
		(net "GND")
	)
	(segment
		(start 180.999892 -46.799754)
		(end 180.999892 -46.800008)
		(width 0.3556)
		(layer "F.Cu")
		(net "GND")
	)
	(segment
		(start 164.999924 -38.800024)
		(end 165.399974 -38.399974)
		(width 0.3556)
		(layer "F.Cu")
		(net "GND")
	)
	(segment
		(start 118.500144 -60.500006)
		(end 118.000018 -61.000132)
		(width 0.4572)
		(layer "F.Cu")
		(net "GND")
	)
	(segment
		(start 64.31661 -79.956914)
		(end 64.31661 -79.112618)
		(width 0.3556)
		(layer "F.Cu")
		(net "GND")
	)
	(segment
		(start 12.050522 -84.886292)
		(end 12.4333 -85.26907)
		(width 0.508)
		(layer "F.Cu")
		(net "GND")
	)
	(segment
		(start 180.199792 -46.7995)
		(end 180.599588 -46.399704)
		(width 0.3556)
		(layer "F.Cu")
		(net "GND")
	)
	(segment
		(start 157.9245 -83.224116)
		(end 157.0482 -83.224116)
		(width 0.508)
		(layer "F.Cu")
		(net "GND")
	)
	(segment
		(start 164.999924 -48.399954)
		(end 165.399974 -47.999904)
		(width 0.3556)
		(layer "F.Cu")
		(net "GND")
	)
	(segment
		(start 165.800024 -40.39997)
		(end 165.399974 -39.99992)
		(width 0.3048)
		(layer "F.Cu")
		(net "GND")
	)
	(segment
		(start 104.499918 -54.500018)
		(end 104.000046 -54.000146)
		(width 0.4572)
		(layer "F.Cu")
		(net "GND")
	)
	(segment
		(start 176.999646 -47.599854)
		(end 176.1998 -46.800008)
		(width 0.3556)
		(layer "F.Cu")
		(net "GND")
	)
	(segment
		(start 170.599862 -29.99994)
		(end 170.518328 -29.99994)
		(width 0.3048)
		(layer "F.Cu")
		(net "GND")
	)
	(segment
		(start 118.500144 -60.500006)
		(end 119.500142 -59.500008)
		(width 0.4572)
		(layer "F.Cu")
		(net "GND")
	)
	(segment
		(start 164.199824 -28.399994)
		(end 164.199824 -29.19984)
		(width 0.3048)
		(layer "F.Cu")
		(net "GND")
	)
	(segment
		(start 168.199816 -41.999916)
		(end 168.599612 -42.399712)
		(width 0.3556)
		(layer "F.Cu")
		(net "GND")
	)
	(segment
		(start 170.599862 -45.199808)
		(end 171.399962 -45.999908)
		(width 0.3556)
		(layer "F.Cu")
		(net "GND")
	)
	(segment
		(start 182.599838 -45.999908)
		(end 182.999888 -45.599858)
		(width 0.3556)
		(layer "F.Cu")
		(net "GND")
	)
	(segment
		(start 155.3972 -80.007714)
		(end 154.561286 -80.007714)
		(width 0.508)
		(layer "F.Cu")
		(net "GND")
	)
	(segment
		(start 175.399954 -47.599854)
		(end 175.400208 -47.599854)
		(width 0.3556)
		(layer "F.Cu")
		(net "GND")
	)
	(segment
		(start 172.199808 -35.59937)
		(end 172.599604 -35.199574)
		(width 0.3556)
		(layer "F.Cu")
		(net "GND")
	)
	(segment
		(start 182.599838 -46.800008)
		(end 182.599838 -46.809406)
		(width 0.3556)
		(layer "F.Cu")
		(net "GND")
	)
	(segment
		(start 90.9955 -86.487)
		(end 90.9955 -87.0839)
		(width 0.508)
		(layer "F.Cu")
		(net "GND")
	)
	(segment
		(start 107.499912 -57.500012)
		(end 107.500166 -57.500012)
		(width 0.4572)
		(layer "F.Cu")
		(net "GND")
	)
	(segment
		(start 168.199816 -35.599878)
		(end 167.799766 -35.999928)
		(width 0.3048)
		(layer "F.Cu")
		(net "GND")
	)
	(segment
		(start 23.30323 -86.461346)
		(end 23.43404 -86.592156)
		(width 0.3556)
		(layer "F.Cu")
		(net "GND")
	)
	(segment
		(start 182.39994 -113.33988)
		(end 182.39994 -112.51184)
		(width 0.508)
		(layer "F.Cu")
		(net "GND")
	)
	(segment
		(start 110.499906 -61.500004)
		(end 110.000034 -61.000132)
		(width 0.4572)
		(layer "F.Cu")
		(net "GND")
	)
	(segment
		(start 176.1998 -29.99994)
		(end 176.9999 -29.99994)
		(width 0.3048)
		(layer "F.Cu")
		(net "GND")
	)
	(segment
		(start 176.9999 -35.599878)
		(end 177.39995 -35.199828)
		(width 0.3556)
		(layer "F.Cu")
		(net "GND")
	)
	(segment
		(start 106.499914 -77.500226)
		(end 106.000042 -78.000098)
		(width 0.4572)
		(layer "F.Cu")
		(net "GND")
	)
	(segment
		(start 166.59987 -47.599854)
		(end 167.39997 -48.399954)
		(width 0.3556)
		(layer "F.Cu")
		(net "GND")
	)
	(segment
		(start 180.999892 -42.800016)
		(end 180.999892 -41.999916)
		(width 0.3556)
		(layer "F.Cu")
		(net "GND")
	)
	(segment
		(start 181.799992 -33.199832)
		(end 181.799992 -33.199578)
		(width 0.3556)
		(layer "F.Cu")
		(net "GND")
	)
	(segment
		(start 118.000018 -71.000366)
		(end 117.500146 -70.500494)
		(width 0.4064)
		(layer "F.Cu")
		(net "GND")
	)
	(segment
		(start 176.1998 -45.200062)
		(end 175.800004 -45.599858)
		(width 0.3556)
		(layer "F.Cu")
		(net "GND")
	)
	(segment
		(start 94.1705 -87.503)
		(end 94.1705 -88.1634)
		(width 0.508)
		(layer "F.Cu")
		(net "GND")
	)
	(segment
		(start 172.199808 -34.000948)
		(end 171.800266 -34.40049)
		(width 0.3556)
		(layer "F.Cu")
		(net "GND")
	)
	(segment
		(start 182.599838 -45.199808)
		(end 182.999888 -45.599858)
		(width 0.3556)
		(layer "F.Cu")
		(net "GND")
	)
	(segment
		(start 108.337858 -67.338194)
		(end 108.337858 -66.662046)
		(width 0.4064)
		(layer "F.Cu")
		(net "GND")
	)
	(segment
		(start 114.499898 -80.50022)
		(end 114.000026 -81.000092)
		(width 0.4572)
		(layer "F.Cu")
		(net "GND")
	)
	(segment
		(start 115.50015 -57.500012)
		(end 116.000022 -57.00014)
		(width 0.4572)
		(layer "F.Cu")
		(net "GND")
	)
	(segment
		(start 118.500144 -65.499996)
		(end 118.000018 -66.000122)
		(width 0.4064)
		(layer "F.Cu")
		(net "GND")
	)
	(segment
		(start 169.800016 -36.399978)
		(end 169.799254 -36.399978)
		(width 0.3556)
		(layer "F.Cu")
		(net "GND")
	)
	(segment
		(start 122.00001 -63.000128)
		(end 122.499882 -63.5)
		(width 0.4572)
		(layer "F.Cu")
		(net "GND")
	)
	(segment
		(start 171.399962 -43.599862)
		(end 171.399962 -43.600116)
		(width 0.3556)
		(layer "F.Cu")
		(net "GND")
	)
	(segment
		(start 122.0978 -87.4395)
		(end 122.0978 -88.155272)
		(width 0.508)
		(layer "F.Cu")
		(net "GND")
	)
	(segment
		(start 174.402496 -31.402528)
		(end 174.599854 -31.599886)
		(width 0.3048)
		(layer "F.Cu")
		(net "GND")
	)
	(segment
		(start 177.8 -44.399708)
		(end 178.199796 -43.999912)
		(width 0.3556)
		(layer "F.Cu")
		(net "GND")
	)
	(segment
		(start 202.47737 -75.442318)
		(end 201.65441 -75.442318)
		(width 0.508)
		(layer "F.Cu")
		(net "GND")
	)
	(segment
		(start 169.800016 -33.999932)
		(end 169.809414 -33.999932)
		(width 0.3556)
		(layer "F.Cu")
		(net "GND")
	)
	(segment
		(start 130.50012 -71.500238)
		(end 130.999992 -72.00011)
		(width 0.4572)
		(layer "F.Cu")
		(net "GND")
	)
	(segment
		(start 127.500126 -72.500236)
		(end 127.999998 -73.000108)
		(width 0.4572)
		(layer "F.Cu")
		(net "GND")
	)
	(segment
		(start 166.600124 -36.399978)
		(end 167.39997 -37.199824)
		(width 0.3048)
		(layer "F.Cu")
		(net "GND")
	)
	(segment
		(start 111.483394 -70.50024)
		(end 111.012478 -70.971156)
		(width 0.4572)
		(layer "F.Cu")
		(net "GND")
	)
	(segment
		(start 164.199824 -33.999932)
		(end 164.600128 -34.400236)
		(width 0.3048)
		(layer "F.Cu")
		(net "GND")
	)
	(segment
		(start 171.200826 -29.89199)
		(end 171.19219 -29.883354)
		(width 0.3048)
		(layer "F.Cu")
		(net "GND")
	)
	(segment
		(start 175.399954 -37.999924)
		(end 174.999904 -37.599874)
		(width 0.3556)
		(layer "F.Cu")
		(net "GND")
	)
	(segment
		(start 169.800524 -37.199824)
		(end 170.20032 -37.59962)
		(width 0.3556)
		(layer "F.Cu")
		(net "GND")
	)
	(segment
		(start 112.00003 -61.000132)
		(end 111.500158 -61.500004)
		(width 0.4572)
		(layer "F.Cu")
		(net "GND")
	)
	(segment
		(start 176.1998 -32.399986)
		(end 176.1998 -32.402018)
		(width 0.3048)
		(layer "F.Cu")
		(net "GND")
	)
	(segment
		(start 182.599838 -41.199816)
		(end 182.599584 -41.199816)
		(width 0.3556)
		(layer "F.Cu")
		(net "GND")
	)
	(segment
		(start 115.50015 -76.500228)
		(end 116.000022 -77.0001)
		(width 0.4572)
		(layer "F.Cu")
		(net "GND")
	)
	(segment
		(start 105.499916 -58.50001)
		(end 106.499914 -57.500012)
		(width 0.4572)
		(layer "F.Cu")
		(net "GND")
	)
	(segment
		(start 69.6595 -8.509)
		(end 68.58 -8.509)
		(width 0.508)
		(layer "F.Cu")
		(net "GND")
	)
	(segment
		(start 173.800008 -46.800008)
		(end 173.7995 -46.800008)
		(width 0.3556)
		(layer "F.Cu")
		(net "GND")
	)
	(segment
		(start 120.000014 -61.000132)
		(end 120.499886 -61.500004)
		(width 0.4572)
		(layer "F.Cu")
		(net "GND")
	)
	(segment
		(start 168.199816 -49.1998)
		(end 167.799766 -48.79975)
		(width 0.3556)
		(layer "F.Cu")
		(net "GND")
	)
	(segment
		(start 111.999776 -68.000372)
		(end 112.499902 -67.500246)
		(width 0.4064)
		(layer "F.Cu")
		(net "GND")
	)
	(segment
		(start 184.199784 -36.399978)
		(end 183.399938 -37.199824)
		(width 0.3556)
		(layer "F.Cu")
		(net "GND")
	)
	(segment
		(start 113.4999 -51.500024)
		(end 113.000028 -51.000152)
		(width 0.4572)
		(layer "F.Cu")
		(net "GND")
	)
	(segment
		(start 168.999916 -39.59987)
		(end 168.999662 -39.59987)
		(width 0.3556)
		(layer "F.Cu")
		(net "GND")
	)
	(segment
		(start 126.499874 -77.500226)
		(end 126.000002 -78.000098)
		(width 0.4572)
		(layer "F.Cu")
		(net "GND")
	)
	(segment
		(start 152.603708 -93.037914)
		(end 152.739852 -92.90177)
		(width 0.3048)
		(layer "F.Cu")
		(net "GND")
	)
	(segment
		(start 180.199792 -45.199808)
		(end 180.599588 -45.599604)
		(width 0.3556)
		(layer "F.Cu")
		(net "GND")
	)
	(segment
		(start 6.6294 -95.275908)
		(end 6.6294 -96.101408)
		(width 0.508)
		(layer "F.Cu")
		(net "GND")
	)
	(segment
		(start 168.999916 -41.999916)
		(end 168.999408 -41.999916)
		(width 0.3556)
		(layer "F.Cu")
		(net "GND")
	)
	(segment
		(start 181.799484 -41.199816)
		(end 181.399688 -41.599612)
		(width 0.3556)
		(layer "F.Cu")
		(net "GND")
	)
	(segment
		(start 182.599838 -47.599854)
		(end 182.599838 -47.591726)
		(width 0.3556)
		(layer "F.Cu")
		(net "GND")
	)
	(segment
		(start 109.499908 -59.500008)
		(end 109.99978 -59.000136)
		(width 0.4572)
		(layer "F.Cu")
		(net "GND")
	)
	(segment
		(start 182.599838 -42.799508)
		(end 182.999634 -42.399712)
		(width 0.3556)
		(layer "F.Cu")
		(net "GND")
	)
	(segment
		(start 109.499908 -57.500012)
		(end 109.500162 -57.500012)
		(width 0.4572)
		(layer "F.Cu")
		(net "GND")
	)
	(segment
		(start 180.199792 -33.199832)
		(end 180.599842 -33.599882)
		(width 0.3556)
		(layer "F.Cu")
		(net "GND")
	)
	(segment
		(start 116.000022 -63.000128)
		(end 116.499894 -63.5)
		(width 0.4572)
		(layer "F.Cu")
		(net "GND")
	)
	(segment
		(start 169.799762 -40.39997)
		(end 168.999916 -41.199816)
		(width 0.3556)
		(layer "F.Cu")
		(net "GND")
	)
	(segment
		(start 182.599838 -34.800032)
		(end 182.999888 -34.399982)
		(width 0.3556)
		(layer "F.Cu")
		(net "GND")
	)
	(segment
		(start 173.800008 -49.1998)
		(end 173.399958 -48.79975)
		(width 0.3556)
		(layer "F.Cu")
		(net "GND")
	)
	(segment
		(start 180.199792 -37.199824)
		(end 179.799742 -37.599874)
		(width 0.3556)
		(layer "F.Cu")
		(net "GND")
	)
	(segment
		(start 172.199808 -47.599854)
		(end 172.200062 -47.599854)
		(width 0.3556)
		(layer "F.Cu")
		(net "GND")
	)
	(segment
		(start 180.199792 -33.999932)
		(end 180.199792 -34.000186)
		(width 0.3556)
		(layer "F.Cu")
		(net "GND")
	)
	(segment
		(start 166.599616 -44.399962)
		(end 166.19982 -44.799758)
		(width 0.3556)
		(layer "F.Cu")
		(net "GND")
	)
	(segment
		(start 180.999892 -41.999408)
		(end 181.399688 -41.599612)
		(width 0.3556)
		(layer "F.Cu")
		(net "GND")
	)
	(segment
		(start 176.9999 -37.999924)
		(end 176.59985 -37.599874)
		(width 0.3556)
		(layer "F.Cu")
		(net "GND")
	)
	(segment
		(start 168.199816 -46.7995)
		(end 168.599612 -46.399704)
		(width 0.3556)
		(layer "F.Cu")
		(net "GND")
	)
	(segment
		(start 164.644578 -17.9705)
		(end 165.76675 -17.9705)
		(width 0.508)
		(layer "F.Cu")
		(net "GND")
	)
	(segment
		(start 158.385764 -44.054522)
		(end 157.0736 -44.054522)
		(width 0.508)
		(layer "F.Cu")
		(net "GND")
	)
	(segment
		(start 201.65441 -75.442318)
		(end 201.653648 -75.44308)
		(width 0.508)
		(layer "F.Cu")
		(net "GND")
	)
	(segment
		(start 181.799992 -45.199808)
		(end 181.799484 -45.199808)
		(width 0.3556)
		(layer "F.Cu")
		(net "GND")
	)
	(segment
		(start 124.500132 -58.500264)
		(end 125.000004 -59.000136)
		(width 0.4572)
		(layer "F.Cu")
		(net "GND")
	)
	(segment
		(start 181.000146 -36.399978)
		(end 181.399688 -36.79952)
		(width 0.3556)
		(layer "F.Cu")
		(net "GND")
	)
	(segment
		(start 122.00001 -59.000136)
		(end 122.500136 -58.50001)
		(width 0.4572)
		(layer "F.Cu")
		(net "GND")
	)
	(segment
		(start 17.562322 -84.987892)
		(end 17.9451 -85.37067)
		(width 0.508)
		(layer "F.Cu")
		(net "GND")
	)
	(segment
		(start 177.800254 -47.599854)
		(end 178.20005 -47.200058)
		(width 0.3556)
		(layer "F.Cu")
		(net "GND")
	)
	(segment
		(start 168.199816 -42.800016)
		(end 168.599612 -43.199812)
		(width 0.3556)
		(layer "F.Cu")
		(net "GND")
	)
	(segment
		(start 169.809414 -33.999932)
		(end 170.209464 -33.599882)
		(width 0.3556)
		(layer "F.Cu")
		(net "GND")
	)
	(segment
		(start 175.399954 -48.399954)
		(end 175.3997 -48.399954)
		(width 0.3556)
		(layer "F.Cu")
		(net "GND")
	)
	(segment
		(start 170.600116 -36.399978)
		(end 170.999658 -36.79952)
		(width 0.3556)
		(layer "F.Cu")
		(net "GND")
	)
	(segment
		(start 101.499924 -63.500254)
		(end 101.000052 -64.000126)
		(width 0.4572)
		(layer "F.Cu")
		(net "GND")
	)
	(segment
		(start 180.199792 -44.399962)
		(end 179.799742 -43.999912)
		(width 0.3556)
		(layer "F.Cu")
		(net "GND")
	)
	(segment
		(start 109.500162 -61.500004)
		(end 109.499908 -61.500004)
		(width 0.4572)
		(layer "F.Cu")
		(net "GND")
	)
	(segment
		(start 171.399962 -41.199816)
		(end 172.199808 -41.199816)
		(width 0.3556)
		(layer "F.Cu")
		(net "GND")
	)
	(segment
		(start 181.799484 -43.599862)
		(end 181.399688 -43.999658)
		(width 0.3556)
		(layer "F.Cu")
		(net "GND")
	)
	(segment
		(start 172.199808 -37.199824)
		(end 172.199808 -37.199316)
		(width 0.3556)
		(layer "F.Cu")
		(net "GND")
	)
	(segment
		(start 119.500142 -69.500242)
		(end 120.000014 -70.000114)
		(width 0.4572)
		(layer "F.Cu")
		(net "GND")
	)
	(segment
		(start 177.8 -38.800024)
		(end 178.199796 -39.19982)
		(width 0.3556)
		(layer "F.Cu")
		(net "GND")
	)
	(segment
		(start 174.599854 -49.1998)
		(end 174.999904 -48.79975)
		(width 0.3556)
		(layer "F.Cu")
		(net "GND")
	)
	(segment
		(start 182.599584 -35.599878)
		(end 182.199788 -35.999674)
		(width 0.3556)
		(layer "F.Cu")
		(net "GND")
	)
	(segment
		(start 111.499904 -59.500008)
		(end 111.999776 -59.000136)
		(width 0.4572)
		(layer "F.Cu")
		(net "GND")
	)
	(segment
		(start 184.199784 -33.199832)
		(end 184.199784 -33.200086)
		(width 0.3556)
		(layer "F.Cu")
		(net "GND")
	)
	(segment
		(start 113.4999 -76.500228)
		(end 113.999772 -76.000356)
		(width 0.4572)
		(layer "F.Cu")
		(net "GND")
	)
	(segment
		(start 114.499898 -63.5)
		(end 114.000026 -63.000128)
		(width 0.4572)
		(layer "F.Cu")
		(net "GND")
	)
	(segment
		(start 73.446894 -14.749272)
		(end 73.27773 -14.749272)
		(width 0.2032)
		(layer "F.Cu")
		(net "GND")
	)
	(segment
		(start 115.50015 -59.500008)
		(end 115.499896 -59.500008)
		(width 0.4572)
		(layer "F.Cu")
		(net "GND")
	)
	(segment
		(start 164.999924 -32.399986)
		(end 164.999924 -32.40024)
		(width 0.3048)
		(layer "F.Cu")
		(net "GND")
	)
	(segment
		(start 124.500132 -69.500242)
		(end 125.000004 -70.000114)
		(width 0.4572)
		(layer "F.Cu")
		(net "GND")
	)
	(segment
		(start 172.200062 -46.00067)
		(end 172.199808 -46.00067)
		(width 0.3556)
		(layer "F.Cu")
		(net "GND")
	)
	(segment
		(start 111.012478 -70.971156)
		(end 111.499904 -71.458582)
		(width 0.4064)
		(layer "F.Cu")
		(net "GND")
	)
	(segment
		(start 111.499904 -59.500008)
		(end 110.499906 -60.500006)
		(width 0.4572)
		(layer "F.Cu")
		(net "GND")
	)
	(segment
		(start 171.399962 -37.199824)
		(end 170.999658 -36.79952)
		(width 0.3556)
		(layer "F.Cu")
		(net "GND")
	)
	(segment
		(start 117.500146 -63.5)
		(end 118.000018 -63.000128)
		(width 0.4572)
		(layer "F.Cu")
		(net "GND")
	)
	(segment
		(start 172.999908 -32.399986)
		(end 172.600112 -32.00019)
		(width 0.3048)
		(layer "F.Cu")
		(net "GND")
	)
	(segment
		(start 181.799484 -37.999924)
		(end 181.399688 -38.39972)
		(width 0.3556)
		(layer "F.Cu")
		(net "GND")
	)
	(segment
		(start 177.8 -33.199832)
		(end 177.799746 -33.199832)
		(width 0.3556)
		(layer "F.Cu")
		(net "GND")
	)
	(segment
		(start 175.399954 -29.99994)
		(end 174.599854 -29.19984)
		(width 0.3048)
		(layer "F.Cu")
		(net "GND")
	)
	(segment
		(start 191.549782 -80.564736)
		(end 191.136016 -80.564736)
		(width 0.508)
		(layer "F.Cu")
		(net "GND")
	)
	(segment
		(start 172.999908 -41.999916)
		(end 173.399958 -42.399966)
		(width 0.3556)
		(layer "F.Cu")
		(net "GND")
	)
	(segment
		(start 177.8 -35.599878)
		(end 177.39995 -35.199828)
		(width 0.3556)
		(layer "F.Cu")
		(net "GND")
	)
	(segment
		(start 123.500134 -58.50001)
		(end 124.500132 -57.500012)
		(width 0.4572)
		(layer "F.Cu")
		(net "GND")
	)
	(segment
		(start 114.500152 -58.50001)
		(end 115.50015 -57.500012)
		(width 0.4572)
		(layer "F.Cu")
		(net "GND")
	)
	(segment
		(start 176.9999 -46.800008)
		(end 176.1998 -45.999908)
		(width 0.3556)
		(layer "F.Cu")
		(net "GND")
	)
	(segment
		(start 115.50015 -70.50024)
		(end 116.500148 -69.500242)
		(width 0.4064)
		(layer "F.Cu")
		(net "GND")
	)
	(segment
		(start 69.37121 -80.556354)
		(end 69.37121 -80.168242)
		(width 0.3556)
		(layer "F.Cu")
		(net "GND")
	)
	(segment
		(start 115.50015 -63.5)
		(end 116.000022 -63.000128)
		(width 0.4572)
		(layer "F.Cu")
		(net "GND")
	)
	(segment
		(start 181.799992 -41.999916)
		(end 181.799992 -41.999408)
		(width 0.3556)
		(layer "F.Cu")
		(net "GND")
	)
	(segment
		(start 168.999916 -35.59937)
		(end 169.399712 -35.199574)
		(width 0.3556)
		(layer "F.Cu")
		(net "GND")
	)
	(segment
		(start 110.499906 -58.50001)
		(end 111.499904 -57.500012)
		(width 0.4572)
		(layer "F.Cu")
		(net "GND")
	)
	(segment
		(start 23.30323 -85.799422)
		(end 23.30323 -86.461346)
		(width 0.3556)
		(layer "F.Cu")
		(net "GND")
	)
	(segment
		(start 166.59987 -49.1998)
		(end 165.800024 -48.399954)
		(width 0.3556)
		(layer "F.Cu")
		(net "GND")
	)
	(segment
		(start 180.599842 -31.199836)
		(end 180.999892 -31.599886)
		(width 0.3048)
		(layer "F.Cu")
		(net "GND")
	)
	(segment
		(start 178.599846 -42.800016)
		(end 178.199796 -42.399966)
		(width 0.3556)
		(layer "F.Cu")
		(net "GND")
	)
	(segment
		(start 112.499902 -65.499996)
		(end 111.999776 -66.000122)
		(width 0.4064)
		(layer "F.Cu")
		(net "GND")
	)
	(segment
		(start 172.199808 -35.599878)
		(end 172.199808 -35.59937)
		(width 0.3556)
		(layer "F.Cu")
		(net "GND")
	)
	(segment
		(start 171.399962 -36.399978)
		(end 171.3992 -36.399978)
		(width 0.3556)
		(layer "F.Cu")
		(net "GND")
	)
	(segment
		(start 175.400208 -47.599854)
		(end 175.800004 -47.200058)
		(width 0.3556)
		(layer "F.Cu")
		(net "GND")
	)
	(segment
		(start 168.999916 -42.800016)
		(end 168.999408 -42.800016)
		(width 0.3556)
		(layer "F.Cu")
		(net "GND")
	)
	(segment
		(start 180.999892 -42.800016)
		(end 181.799992 -42.800016)
		(width 0.3556)
		(layer "F.Cu")
		(net "GND")
	)
	(segment
		(start 163.2966 -100.1014)
		(end 163.43884 -99.95916)
		(width 0.508)
		(layer "F.Cu")
		(net "GND")
	)
	(segment
		(start 184.570624 -58.914792)
		(end 184.570624 -59.751976)
		(width 0.508)
		(layer "F.Cu")
		(net "GND")
	)
	(segment
		(start 170.599862 -33.199832)
		(end 170.599862 -33.209484)
		(width 0.3556)
		(layer "F.Cu")
		(net "GND")
	)
	(segment
		(start 126.500128 -80.50022)
		(end 127 -81.000092)
		(width 0.4572)
		(layer "F.Cu")
		(net "GND")
	)
	(segment
		(start 179.399946 -37.200078)
		(end 179.799742 -37.599874)
		(width 0.3556)
		(layer "F.Cu")
		(net "GND")
	)
	(segment
		(start 118.000018 -61.000132)
		(end 118.49989 -61.500004)
		(width 0.4572)
		(layer "F.Cu")
		(net "GND")
	)
	(segment
		(start 170.599862 -37.199824)
		(end 170.599862 -37.200078)
		(width 0.3556)
		(layer "F.Cu")
		(net "GND")
	)
	(segment
		(start 170.599862 -46.00067)
		(end 170.20032 -46.400212)
		(width 0.3556)
		(layer "F.Cu")
		(net "GND")
	)
	(segment
		(start 128.500124 -52.500022)
		(end 128.999996 -52.00015)
		(width 0.508)
		(layer "F.Cu")
		(net "GND")
	)
	(segment
		(start 165.800024 -45.199554)
		(end 166.19982 -44.799758)
		(width 0.3556)
		(layer "F.Cu")
		(net "GND")
	)
	(segment
		(start 169.799254 -34.800032)
		(end 169.399712 -35.199574)
		(width 0.3556)
		(layer "F.Cu")
		(net "GND")
	)
	(segment
		(start 182.599838 -33.199832)
		(end 182.199788 -32.799782)
		(width 0.3556)
		(layer "F.Cu")
		(net "GND")
	)
	(segment
		(start 175.399954 -45.199808)
		(end 175.800004 -45.599858)
		(width 0.3048)
		(layer "F.Cu")
		(net "GND")
	)
	(segment
		(start 101.499924 -78.500224)
		(end 101.000052 -79.000096)
		(width 0.4572)
		(layer "F.Cu")
		(net "GND")
	)
	(segment
		(start 108.49991 -58.50001)
		(end 109.499908 -57.500012)
		(width 0.4572)
		(layer "F.Cu")
		(net "GND")
	)
	(segment
		(start 178.599846 -45.199808)
		(end 178.599846 -45.200062)
		(width 0.3556)
		(layer "F.Cu")
		(net "GND")
	)
	(segment
		(start 164.606478 -35.997134)
		(end 164.203634 -36.399978)
		(width 0.3048)
		(layer "F.Cu")
		(net "GND")
	)
	(segment
		(start 69.6595 -10.795)
		(end 68.58 -10.795)
		(width 0.508)
		(layer "F.Cu")
		(net "GND")
	)
	(segment
		(start 112.499902 -60.500006)
		(end 112.499902 -60.50026)
		(width 0.4572)
		(layer "F.Cu")
		(net "GND")
	)
	(segment
		(start 126.500128 -52.500022)
		(end 127 -52.00015)
		(width 0.4572)
		(layer "F.Cu")
		(net "GND")
	)
	(segment
		(start 123.500134 -51.500024)
		(end 124.000006 -51.000152)
		(width 0.4572)
		(layer "F.Cu")
		(net "GND")
	)
	(segment
		(start 171.399962 -40.39997)
		(end 170.999658 -39.999666)
		(width 0.3556)
		(layer "F.Cu")
		(net "GND")
	)
	(segment
		(start 176.47031 -104.52608)
		(end 176.47031 -103.35641)
		(width 0.508)
		(layer "F.Cu")
		(net "GND")
	)
	(segment
		(start 122.0978 -88.155272)
		(end 122.265186 -88.322658)
		(width 0.508)
		(layer "F.Cu")
		(net "GND")
	)
	(segment
		(start 179.399946 -41.999916)
		(end 179.399946 -42.00017)
		(width 0.3556)
		(layer "F.Cu")
		(net "GND")
	)
	(segment
		(start 126.500128 -77.500226)
		(end 126.499874 -77.500226)
		(width 0.4572)
		(layer "F.Cu")
		(net "GND")
	)
	(segment
		(start 99.499928 -64.499998)
		(end 99.000056 -64.000126)
		(width 0.4572)
		(layer "F.Cu")
		(net "GND")
	)
	(segment
		(start 162.954716 -41.999916)
		(end 162.333432 -42.6212)
		(width 0.3048)
		(layer "F.Cu")
		(net "GND")
	)
	(segment
		(start 182.599838 -33.999932)
		(end 182.999888 -34.399982)
		(width 0.3556)
		(layer "F.Cu")
		(net "GND")
	)
	(segment
		(start 114.499898 -54.500018)
		(end 114.000026 -54.000146)
		(width 0.4572)
		(layer "F.Cu")
		(net "GND")
	)
	(segment
		(start 180.999892 -34.800032)
		(end 180.999638 -34.800032)
		(width 0.3556)
		(layer "F.Cu")
		(net "GND")
	)
	(segment
		(start 123.500134 -62.500256)
		(end 123.500134 -62.500002)
		(width 0.4572)
		(layer "F.Cu")
		(net "GND")
	)
	(segment
		(start 172.999908 -45.199808)
		(end 173.399704 -45.599604)
		(width 0.3556)
		(layer "F.Cu")
		(net "GND")
	)
	(segment
		(start 164.999924 -37.999924)
		(end 164.999924 -37.199824)
		(width 0.3556)
		(layer "F.Cu")
		(net "GND")
	)
	(segment
		(start 172.999908 -33.999932)
		(end 173.400466 -34.40049)
		(width 0.3556)
		(layer "F.Cu")
		(net "GND")
	)
	(segment
		(start 122.499882 -63.5)
		(end 122.500136 -63.5)
		(width 0.4572)
		(layer "F.Cu")
		(net "GND")
	)
	(segment
		(start 166.59987 -36.399978)
		(end 166.600124 -36.399978)
		(width 0.3048)
		(layer "F.Cu")
		(net "GND")
	)
	(segment
		(start 155.5242 -90.6399)
		(end 155.5242 -89.7636)
		(width 0.508)
		(layer "F.Cu")
		(net "GND")
	)
	(segment
		(start 9.1059 -76.6445)
		(end 9.410446 -76.949046)
		(width 0.508)
		(layer "F.Cu")
		(net "GND")
	)
	(segment
		(start 130.50012 -77.500226)
		(end 130.999992 -78.000098)
		(width 0.4572)
		(layer "F.Cu")
		(net "GND")
	)
	(segment
		(start 180.999892 -45.999908)
		(end 180.999384 -45.999908)
		(width 0.3556)
		(layer "F.Cu")
		(net "GND")
	)
	(segment
		(start 101.499924 -66.499994)
		(end 101.000052 -66.000122)
		(width 0.4572)
		(layer "F.Cu")
		(net "GND")
	)
	(segment
		(start 184.199784 -42.800016)
		(end 184.59958 -42.40022)
		(width 0.3556)
		(layer "F.Cu")
		(net "GND")
	)
	(segment
		(start 199.78624 -82.46872)
		(end 199.78624 -81.63306)
		(width 0.508)
		(layer "F.Cu")
		(net "GND")
	)
	(segment
		(start 169.800016 -34.800032)
		(end 169.799254 -34.800032)
		(width 0.3556)
		(layer "F.Cu")
		(net "GND")
	)
	(segment
		(start 115.50015 -71.500238)
		(end 115.000278 -71.000366)
		(width 0.3556)
		(layer "F.Cu")
		(net "GND")
	)
	(segment
		(start 111.999776 -66.000122)
		(end 111.499904 -66.499994)
		(width 0.4064)
		(layer "F.Cu")
		(net "GND")
	)
	(segment
		(start 169.00017 -48.399954)
		(end 169.399966 -48.79975)
		(width 0.3556)
		(layer "F.Cu")
		(net "GND")
	)
	(segment
		(start 101.499924 -72.500236)
		(end 101.000052 -73.000108)
		(width 0.4572)
		(layer "F.Cu")
		(net "GND")
	)
	(segment
		(start 56.894476 -16.95196)
		(end 56.894476 -16.05915)
		(width 0.508)
		(layer "F.Cu")
		(net "GND")
	)
	(segment
		(start 168.999408 -38.800024)
		(end 168.599612 -39.19982)
		(width 0.3556)
		(layer "F.Cu")
		(net "GND")
	)
	(segment
		(start 164.999924 -40.39997)
		(end 165.399974 -39.99992)
		(width 0.3048)
		(layer "F.Cu")
		(net "GND")
	)
	(segment
		(start 165.800024 -45.199808)
		(end 165.800024 -45.199554)
		(width 0.3556)
		(layer "F.Cu")
		(net "GND")
	)
	(segment
		(start 159.0802 -118.0846)
		(end 159.0802 -117.54104)
		(width 0.508)
		(layer "F.Cu")
		(net "GND")
	)
	(via
		(at 20.547584 -72.82053)
		(size 0.508)
		(drill 0.254)
		(layers "F.Cu" "B.Cu")
		(net "GND")
	)
	(via
		(at 106.000042 -81.000092)
		(size 0.4572)
		(drill 0.2032)
		(layers "F.Cu" "B.Cu")
		(net "GND")
	)
	(via
		(at 167.634158 -88.158828)
		(size 0.7112)
		(drill 0.4064)
		(layers "F.Cu" "B.Cu")
		(net "GND")
	)
	(via
		(at 165.467284 -1.66243)
		(size 0.7112)
		(drill 0.4064)
		(layers "F.Cu" "B.Cu")
		(net "GND")
	)
	(via
		(at 162.796474 -45.999908)
		(size 0.508)
		(drill 0.254)
		(layers "F.Cu" "B.Cu")
		(net "GND")
	)
	(via
		(at 120.000014 -77.0001)
		(size 0.4572)
		(drill 0.2032)
		(layers "F.Cu" "B.Cu")
		(net "GND")
	)
	(via
		(at 116.642134 -90.218006)
		(size 0.6604)
		(drill 0.3302)
		(layers "F.Cu" "B.Cu")
		(net "GND")
	)
	(via
		(at 193.42608 -86.13394)
		(size 0.508)
		(drill 0.254)
		(layers "F.Cu" "B.Cu")
		(net "GND")
	)
	(via
		(at 5.147564 -143.602964)
		(size 0.7112)
		(drill 0.4064)
		(layers "F.Cu" "B.Cu")
		(net "GND")
	)
	(via
		(at 57.785 -36.703)
		(size 0.7112)
		(drill 0.4064)
		(layers "F.Cu" "B.Cu")
		(net "GND")
	)
	(via
		(at 89.600024 -2.705354)
		(size 0.6604)
		(drill 0.3556)
		(layers "F.Cu" "B.Cu")
		(net "GND")
	)
	(via
		(at 184.59958 -48.800004)
		(size 0.508)
		(drill 0.254)
		(layers "F.Cu" "B.Cu")
		(net "GND")
	)
	(via
		(at 171.799758 -51.999642)
		(size 0.508)
		(drill 0.254)
		(layers "F.Cu" "B.Cu")
		(net "GND")
	)
	(via
		(at 182.999888 -34.399982)
		(size 0.508)
		(drill 0.254)
		(layers "F.Cu" "B.Cu")
		(net "GND")
	)
	(via
		(at 174.999904 -43.999912)
		(size 0.508)
		(drill 0.254)
		(layers "F.Cu" "B.Cu")
		(net "GND")
	)
	(via
		(at 167.799766 -48.79975)
		(size 0.508)
		(drill 0.254)
		(layers "F.Cu" "B.Cu")
		(net "GND")
	)
	(via
		(at 51.1556 -47.5742)
		(size 0.5588)
		(drill 0.3048)
		(layers "F.Cu" "B.Cu")
		(net "GND")
	)
	(via
		(at 1.397 -138.527536)
		(size 0.7112)
		(drill 0.4064)
		(layers "F.Cu" "B.Cu")
		(net "GND")
	)
	(via
		(at 1.397 -12.797536)
		(size 0.7112)
		(drill 0.4064)
		(layers "F.Cu" "B.Cu")
		(net "GND")
	)
	(via
		(at 104.000046 -62.00013)
		(size 0.4572)
		(drill 0.2032)
		(layers "F.Cu" "B.Cu")
		(net "GND")
	)
	(via
		(at 146.6977 -143.602964)
		(size 0.7112)
		(drill 0.4064)
		(layers "F.Cu" "B.Cu")
		(net "GND")
	)
	(via
		(at 154.7876 -114.4143)
		(size 0.5588)
		(drill 0.3048)
		(layers "F.Cu" "B.Cu")
		(net "GND")
	)
	(via
		(at 1.397 -123.287536)
		(size 0.7112)
		(drill 0.4064)
		(layers "F.Cu" "B.Cu")
		(net "GND")
	)
	(via
		(at 100.000054 -54.000146)
		(size 0.4572)
		(drill 0.2032)
		(layers "F.Cu" "B.Cu")
		(net "GND")
	)
	(via
		(at 122.00001 -71.000112)
		(size 0.4572)
		(drill 0.2032)
		(layers "F.Cu" "B.Cu")
		(net "GND")
	)
	(via
		(at 128.999996 -52.00015)
		(size 0.4572)
		(drill 0.2032)
		(layers "F.Cu" "B.Cu")
		(net "GND")
	)
	(via
		(at 100.000054 -58.000138)
		(size 0.4572)
		(drill 0.2032)
		(layers "F.Cu" "B.Cu")
		(net "GND")
	)
	(via
		(at 124.000006 -51.000152)
		(size 0.4572)
		(drill 0.2032)
		(layers "F.Cu" "B.Cu")
		(net "GND")
	)
	(via
		(at 81.249774 -65.791842)
		(size 0.508)
		(drill 0.254)
		(layers "F.Cu" "B.Cu")
		(net "GND")
	)
	(via
		(at 154.037284 -1.66243)
		(size 0.7112)
		(drill 0.4064)
		(layers "F.Cu" "B.Cu")
		(net "GND")
	)
	(via
		(at 132.827268 -109.850174)
		(size 0.7112)
		(drill 0.4064)
		(layers "F.Cu" "B.Cu")
		(net "GND")
	)
	(via
		(at 1.397 -115.667536)
		(size 0.7112)
		(drill 0.4064)
		(layers "F.Cu" "B.Cu")
		(net "GND")
	)
	(via
		(at 1.397 -119.477536)
		(size 0.7112)
		(drill 0.4064)
		(layers "F.Cu" "B.Cu")
		(net "GND")
	)
	(via
		(at 127.7239 -93.599)
		(size 0.508)
		(drill 0.254)
		(layers "F.Cu" "B.Cu")
		(net "GND")
	)
	(via
		(at 175.805592 -32.796226)
		(size 0.508)
		(drill 0.254)
		(layers "F.Cu" "B.Cu")
		(net "GND")
	)
	(via
		(at 40.9194 -52.07)
		(size 0.7112)
		(drill 0.4064)
		(layers "F.Cu" "B.Cu")
		(net "GND")
	)
	(via
		(at 121.000012 -54.000146)
		(size 0.4572)
		(drill 0.2032)
		(layers "F.Cu" "B.Cu")
		(net "GND")
	)
	(via
		(at 43.4086 -52.07)
		(size 0.7112)
		(drill 0.4064)
		(layers "F.Cu" "B.Cu")
		(net "GND")
	)
	(via
		(at 8.982456 -1.397)
		(size 0.7112)
		(drill 0.4064)
		(layers "F.Cu" "B.Cu")
		(net "GND")
	)
	(via
		(at 208.603088 -109.05236)
		(size 0.7112)
		(drill 0.4064)
		(layers "F.Cu" "B.Cu")
		(net "GND")
	)
	(via
		(at 83.605624 -139.824968)
		(size 0.7112)
		(drill 0.4064)
		(layers "F.Cu" "B.Cu")
		(net "GND")
	)
	(via
		(at 63.45428 -99.23018)
		(size 0.5588)
		(drill 0.3048)
		(layers "F.Cu" "B.Cu")
		(net "GND")
	)
	(via
		(at 116.000022 -51.000152)
		(size 0.4572)
		(drill 0.2032)
		(layers "F.Cu" "B.Cu")
		(net "GND")
	)
	(via
		(at 127 -81.000092)
		(size 0.4572)
		(drill 0.2032)
		(layers "F.Cu" "B.Cu")
		(net "GND")
	)
	(via
		(at 1.397 -8.987536)
		(size 0.7112)
		(drill 0.4064)
		(layers "F.Cu" "B.Cu")
		(net "GND")
	)
	(via
		(at 40.707564 -143.602964)
		(size 0.7112)
		(drill 0.4064)
		(layers "F.Cu" "B.Cu")
		(net "GND")
	)
	(via
		(at 171.800266 -46.400212)
		(size 0.508)
		(drill 0.254)
		(layers "F.Cu" "B.Cu")
		(net "GND")
	)
	(via
		(at 134.046468 -109.850174)
		(size 0.7112)
		(drill 0.4064)
		(layers "F.Cu" "B.Cu")
		(net "GND")
	)
	(via
		(at 178.84521 -105.274364)
		(size 0.7112)
		(drill 0.4064)
		(layers "F.Cu" "B.Cu")
		(net "GND")
	)
	(via
		(at 151.497284 -1.66243)
		(size 0.7112)
		(drill 0.4064)
		(layers "F.Cu" "B.Cu")
		(net "GND")
	)
	(via
		(at 152.273762 -114.483642)
		(size 0.5588)
		(drill 0.3048)
		(layers "F.Cu" "B.Cu")
		(net "GND")
	)
	(via
		(at 101.000052 -75.000104)
		(size 0.4572)
		(drill 0.2032)
		(layers "F.Cu" "B.Cu")
		(net "GND")
	)
	(via
		(at 164.644578 -17.9705)
		(size 0.508)
		(drill 0.254)
		(layers "F.Cu" "B.Cu")
		(net "GND")
	)
	(via
		(at 78.807564 -143.602964)
		(size 0.7112)
		(drill 0.4064)
		(layers "F.Cu" "B.Cu")
		(net "GND")
	)
	(via
		(at 208.603088 -139.53236)
		(size 0.7112)
		(drill 0.4064)
		(layers "F.Cu" "B.Cu")
		(net "GND")
	)
	(via
		(at 162.333432 -42.6212)
		(size 0.508)
		(drill 0.254)
		(layers "F.Cu" "B.Cu")
		(net "GND")
	)
	(via
		(at 1.397 -17.877536)
		(size 0.7112)
		(drill 0.4064)
		(layers "F.Cu" "B.Cu")
		(net "GND")
	)
	(via
		(at 23.999952 -124.431552)
		(size 0.508)
		(drill 0.254)
		(layers "F.Cu" "B.Cu")
		(net "GND")
	)
	(via
		(at 169.523156 -109.716824)
		(size 0.508)
		(drill 0.254)
		(layers "F.Cu" "B.Cu")
		(net "GND")
	)
	(via
		(at 79.46136 -10.769092)
		(size 0.508)
		(drill 0.254)
		(layers "F.Cu" "B.Cu")
		(net "GND")
	)
	(via
		(at 99.000056 -64.000126)
		(size 0.4572)
		(drill 0.2032)
		(layers "F.Cu" "B.Cu")
		(net "GND")
	)
	(via
		(at 159.117284 -1.66243)
		(size 0.7112)
		(drill 0.4064)
		(layers "F.Cu" "B.Cu")
		(net "GND")
	)
	(via
		(at 17.847564 -143.602964)
		(size 0.7112)
		(drill 0.4064)
		(layers "F.Cu" "B.Cu")
		(net "GND")
	)
	(via
		(at 180.9877 -143.602964)
		(size 0.7112)
		(drill 0.4064)
		(layers "F.Cu" "B.Cu")
		(net "GND")
	)
	(via
		(at 99.000056 -58.000138)
		(size 0.4572)
		(drill 0.2032)
		(layers "F.Cu" "B.Cu")
		(net "GND")
	)
	(via
		(at 198.7677 -143.602964)
		(size 0.7112)
		(drill 0.4064)
		(layers "F.Cu" "B.Cu")
		(net "GND")
	)
	(via
		(at 184.59958 -42.40022)
		(size 0.508)
		(drill 0.254)
		(layers "F.Cu" "B.Cu")
		(net "GND")
	)
	(via
		(at 31.817564 -143.602964)
		(size 0.7112)
		(drill 0.4064)
		(layers "F.Cu" "B.Cu")
		(net "GND")
	)
	(via
		(at 170.199812 -42.399712)
		(size 0.508)
		(drill 0.254)
		(layers "F.Cu" "B.Cu")
		(net "GND")
	)
	(via
		(at 163.2077 -143.602964)
		(size 0.7112)
		(drill 0.4064)
		(layers "F.Cu" "B.Cu")
		(net "GND")
	)
	(via
		(at 113.000028 -51.000152)
		(size 0.4572)
		(drill 0.2032)
		(layers "F.Cu" "B.Cu")
		(net "GND")
	)
	(via
		(at 62.322456 -1.397)
		(size 0.7112)
		(drill 0.4064)
		(layers "F.Cu" "B.Cu")
		(net "GND")
	)
	(via
		(at 100.000054 -64.000126)
		(size 0.4572)
		(drill 0.2032)
		(layers "F.Cu" "B.Cu")
		(net "GND")
	)
	(via
		(at 166.19982 -43.199812)
		(size 0.508)
		(drill 0.254)
		(layers "F.Cu" "B.Cu")
		(net "GND")
	)
	(via
		(at 164.247322 -24.856186)
		(size 0.508)
		(drill 0.254)
		(layers "F.Cu" "B.Cu")
		(net "GND")
	)
	(via
		(at 48.97882 -40.8686)
		(size 0.7112)
		(drill 0.4064)
		(layers "F.Cu" "B.Cu")
		(net "GND")
	)
	(via
		(at 63.034926 -18.911316)
		(size 0.508)
		(drill 0.254)
		(layers "F.Cu" "B.Cu")
		(net "GND")
	)
	(via
		(at 152.273762 -118.141242)
		(size 0.5588)
		(drill 0.3048)
		(layers "F.Cu" "B.Cu")
		(net "GND")
	)
	(via
		(at 160.02 -59.4868)
		(size 0.508)
		(drill 0.254)
		(layers "F.Cu" "B.Cu")
		(net "GND")
	)
	(via
		(at 22.83333 -96.120204)
		(size 0.508)
		(drill 0.254)
		(layers "F.Cu" "B.Cu")
		(net "GND")
	)
	(via
		(at 15.332456 -1.397)
		(size 0.7112)
		(drill 0.4064)
		(layers "F.Cu" "B.Cu")
		(net "GND")
	)
	(via
		(at 1.397 -111.857536)
		(size 0.7112)
		(drill 0.4064)
		(layers "F.Cu" "B.Cu")
		(net "GND")
	)
	(via
		(at 12.792456 -1.397)
		(size 0.7112)
		(drill 0.4064)
		(layers "F.Cu" "B.Cu")
		(net "GND")
	)
	(via
		(at 39.7002 -52.07)
		(size 0.7112)
		(drill 0.4064)
		(layers "F.Cu" "B.Cu")
		(net "GND")
	)
	(via
		(at 164.4777 -143.602964)
		(size 0.7112)
		(drill 0.4064)
		(layers "F.Cu" "B.Cu")
		(net "GND")
	)
	(via
		(at 152.273762 -117.226842)
		(size 0.5588)
		(drill 0.3048)
		(layers "F.Cu" "B.Cu")
		(net "GND")
	)
	(via
		(at 188.6077 -143.602964)
		(size 0.7112)
		(drill 0.4064)
		(layers "F.Cu" "B.Cu")
		(net "GND")
	)
	(via
		(at 176.5173 -120.1547)
		(size 0.7112)
		(drill 0.4064)
		(layers "F.Cu" "B.Cu")
		(net "GND")
	)
	(via
		(at 208.603088 -79.84236)
		(size 0.7112)
		(drill 0.4064)
		(layers "F.Cu" "B.Cu")
		(net "GND")
	)
	(via
		(at 1.397 -26.767536)
		(size 0.7112)
		(drill 0.4064)
		(layers "F.Cu" "B.Cu")
		(net "GND")
	)
	(via
		(at 101.000052 -79.000096)
		(size 0.4572)
		(drill 0.2032)
		(layers "F.Cu" "B.Cu")
		(net "GND")
	)
	(via
		(at 176.47031 -103.35641)
		(size 0.508)
		(drill 0.254)
		(layers "F.Cu" "B.Cu")
		(net "GND")
	)
	(via
		(at 1.397 -54.707536)
		(size 0.7112)
		(drill 0.4064)
		(layers "F.Cu" "B.Cu")
		(net "GND")
	)
	(via
		(at 178.199796 -35.199828)
		(size 0.508)
		(drill 0.254)
		(layers "F.Cu" "B.Cu")
		(net "GND")
	)
	(via
		(at 163.800028 -39.99992)
		(size 0.508)
		(drill 0.254)
		(layers "F.Cu" "B.Cu")
		(net "GND")
	)
	(via
		(at 176.59985 -37.599874)
		(size 0.508)
		(drill 0.254)
		(layers "F.Cu" "B.Cu")
		(net "GND")
	)
	(via
		(at 167.0177 -143.602964)
		(size 0.7112)
		(drill 0.4064)
		(layers "F.Cu" "B.Cu")
		(net "GND")
	)
	(via
		(at 124.46 -92.3798)
		(size 0.508)
		(drill 0.254)
		(layers "F.Cu" "B.Cu")
		(net "GND")
	)
	(via
		(at 55.972456 -1.397)
		(size 0.7112)
		(drill 0.4064)
		(layers "F.Cu" "B.Cu")
		(net "GND")
	)
	(via
		(at 44.6532 -32.893)
		(size 0.5588)
		(drill 0.3048)
		(layers "F.Cu" "B.Cu")
		(net "GND")
	)
	(via
		(at 152.0444 -64.2874)
		(size 0.508)
		(drill 0.254)
		(layers "F.Cu" "B.Cu")
		(net "GND")
	)
	(via
		(at 120.000014 -66.000122)
		(size 0.4572)
		(drill 0.2032)
		(layers "F.Cu" "B.Cu")
		(net "GND")
	)
	(via
		(at 145.1102 -105.3592)
		(size 0.7112)
		(drill 0.4064)
		(layers "F.Cu" "B.Cu")
		(net "GND")
	)
	(via
		(at 156.8577 -143.602964)
		(size 0.7112)
		(drill 0.4064)
		(layers "F.Cu" "B.Cu")
		(net "GND")
	)
	(via
		(at 180.600096 -48.79975)
		(size 0.508)
		(drill 0.254)
		(layers "F.Cu" "B.Cu")
		(net "GND")
	)
	(via
		(at 162.708336 -49.308258)
		(size 0.508)
		(drill 0.254)
		(layers "F.Cu" "B.Cu")
		(net "GND")
	)
	(via
		(at 39.437564 -143.602964)
		(size 0.7112)
		(drill 0.4064)
		(layers "F.Cu" "B.Cu")
		(net "GND")
	)
	(via
		(at 208.603088 -90.00236)
		(size 0.7112)
		(drill 0.4064)
		(layers "F.Cu" "B.Cu")
		(net "GND")
	)
	(via
		(at 100.000054 -56.000142)
		(size 0.4572)
		(drill 0.2032)
		(layers "F.Cu" "B.Cu")
		(net "GND")
	)
	(via
		(at 73.7362 -33.1216)
		(size 0.7112)
		(drill 0.4064)
		(layers "F.Cu" "B.Cu")
		(net "GND")
	)
	(via
		(at 160.387284 -1.66243)
		(size 0.7112)
		(drill 0.4064)
		(layers "F.Cu" "B.Cu")
		(net "GND")
	)
	(via
		(at 167.80002 -50.39995)
		(size 0.508)
		(drill 0.254)
		(layers "F.Cu" "B.Cu")
		(net "GND")
	)
	(via
		(at 124.000006 -61.000132)
		(size 0.4572)
		(drill 0.2032)
		(layers "F.Cu" "B.Cu")
		(net "GND")
	)
	(via
		(at 174.999904 -37.599874)
		(size 0.508)
		(drill 0.254)
		(layers "F.Cu" "B.Cu")
		(net "GND")
	)
	(via
		(at 68.58 -10.795)
		(size 0.508)
		(drill 0.254)
		(layers "F.Cu" "B.Cu")
		(net "GND")
	)
	(via
		(at 1.397 -47.087536)
		(size 0.7112)
		(drill 0.4064)
		(layers "F.Cu" "B.Cu")
		(net "GND")
	)
	(via
		(at 75.022456 -1.397)
		(size 0.7112)
		(drill 0.4064)
		(layers "F.Cu" "B.Cu")
		(net "GND")
	)
	(via
		(at 171.000166 -32.00019)
		(size 0.508)
		(drill 0.254)
		(layers "F.Cu" "B.Cu")
		(net "GND")
	)
	(via
		(at 177.546 -115.0493)
		(size 0.5588)
		(drill 0.3048)
		(layers "F.Cu" "B.Cu")
		(net "GND")
	)
	(via
		(at 168.225724 -92.831158)
		(size 0.508)
		(drill 0.254)
		(layers "F.Cu" "B.Cu")
		(net "GND")
	)
	(via
		(at 1.397 -104.237536)
		(size 0.7112)
		(drill 0.4064)
		(layers "F.Cu" "B.Cu")
		(net "GND")
	)
	(via
		(at 164.600128 -32.800036)
		(size 0.508)
		(drill 0.254)
		(layers "F.Cu" "B.Cu")
		(net "GND")
	)
	(via
		(at 61.75248 -100.37318)
		(size 0.5588)
		(drill 0.3048)
		(layers "F.Cu" "B.Cu")
		(net "GND")
	)
	(via
		(at 186.83478 -107.88904)
		(size 0.508)
		(drill 0.254)
		(layers "F.Cu" "B.Cu")
		(net "GND")
	)
	(via
		(at 160.7185 -75.092814)
		(size 0.508)
		(drill 0.254)
		(layers "F.Cu" "B.Cu")
		(net "GND")
	)
	(via
		(at 108.000038 -54.000146)
		(size 0.4572)
		(drill 0.2032)
		(layers "F.Cu" "B.Cu")
		(net "GND")
	)
	(via
		(at 125.000004 -72.00011)
		(size 0.4572)
		(drill 0.2032)
		(layers "F.Cu" "B.Cu")
		(net "GND")
	)
	(via
		(at 173.4058 -61.049916)
		(size 0.508)
		(drill 0.254)
		(layers "F.Cu" "B.Cu")
		(net "GND")
	)
	(via
		(at 114.321082 -124.87656)
		(size 0.7112)
		(drill 0.4064)
		(layers "F.Cu" "B.Cu")
		(net "GND")
	)
	(via
		(at 116.000022 -71.000112)
		(size 0.4572)
		(drill 0.2032)
		(layers "F.Cu" "B.Cu")
		(net "GND")
	)
	(via
		(at 208.603088 -88.73236)
		(size 0.7112)
		(drill 0.4064)
		(layers "F.Cu" "B.Cu")
		(net "GND")
	)
	(via
		(at 164.606986 -38.402514)
		(size 0.508)
		(drill 0.254)
		(layers "F.Cu" "B.Cu")
		(net "GND")
	)
	(via
		(at 147.199858 -2.705354)
		(size 0.6604)
		(drill 0.3556)
		(layers "F.Cu" "B.Cu")
		(net "GND")
	)
	(via
		(at 208.603088 -70.95236)
		(size 0.7112)
		(drill 0.4064)
		(layers "F.Cu" "B.Cu")
		(net "GND")
	)
	(via
		(at 92.962984 -69.301614)
		(size 0.508)
		(drill 0.254)
		(layers "F.Cu" "B.Cu")
		(net "GND")
	)
	(via
		(at 22.927564 -143.602964)
		(size 0.7112)
		(drill 0.4064)
		(layers "F.Cu" "B.Cu")
		(net "GND")
	)
	(via
		(at 19.142456 -1.397)
		(size 0.7112)
		(drill 0.4064)
		(layers "F.Cu" "B.Cu")
		(net "GND")
	)
	(via
		(at 208.603088 -81.11236)
		(size 0.7112)
		(drill 0.4064)
		(layers "F.Cu" "B.Cu")
		(net "GND")
	)
	(via
		(at 194.402456 -1.397)
		(size 0.7112)
		(drill 0.4064)
		(layers "F.Cu" "B.Cu")
		(net "GND")
	)
	(via
		(at 50.892456 -1.397)
		(size 0.7112)
		(drill 0.4064)
		(layers "F.Cu" "B.Cu")
		(net "GND")
	)
	(via
		(at 118.000018 -59.000136)
		(size 0.4572)
		(drill 0.2032)
		(layers "F.Cu" "B.Cu")
		(net "GND")
	)
	(via
		(at 1.397 -62.327536)
		(size 0.7112)
		(drill 0.4064)
		(layers "F.Cu" "B.Cu")
		(net "GND")
	)
	(via
		(at 184.570624 -59.751976)
		(size 0.508)
		(drill 0.254)
		(layers "F.Cu" "B.Cu")
		(net "GND")
	)
	(via
		(at 1.397 -142.337536)
		(size 0.7112)
		(drill 0.4064)
		(layers "F.Cu" "B.Cu")
		(net "GND")
	)
	(via
		(at 126.399544 -138.565128)
		(size 0.7112)
		(drill 0.4064)
		(layers "F.Cu" "B.Cu")
		(net "GND")
	)
	(via
		(at 104.000046 -54.000146)
		(size 0.4572)
		(drill 0.2032)
		(layers "F.Cu" "B.Cu")
		(net "GND")
	)
	(via
		(at 169.399966 -48.79975)
		(size 0.508)
		(drill 0.254)
		(layers "F.Cu" "B.Cu")
		(net "GND")
	)
	(via
		(at 208.603088 -67.14236)
		(size 0.7112)
		(drill 0.4064)
		(layers "F.Cu" "B.Cu")
		(net "GND")
	)
	(via
		(at 170.999658 -39.999666)
		(size 0.508)
		(drill 0.254)
		(layers "F.Cu" "B.Cu")
		(net "GND")
	)
	(via
		(at 173.087284 -1.66243)
		(size 0.7112)
		(drill 0.4064)
		(layers "F.Cu" "B.Cu")
		(net "GND")
	)
	(via
		(at 64.36868 -99.23018)
		(size 0.5588)
		(drill 0.3048)
		(layers "F.Cu" "B.Cu")
		(net "GND")
	)
	(via
		(at 1.397 -127.097536)
		(size 0.7112)
		(drill 0.4064)
		(layers "F.Cu" "B.Cu")
		(net "GND")
	)
	(via
		(at 57.785 -37.9222)
		(size 0.7112)
		(drill 0.4064)
		(layers "F.Cu" "B.Cu")
		(net "GND")
	)
	(via
		(at 206.3877 -143.602964)
		(size 0.7112)
		(drill 0.4064)
		(layers "F.Cu" "B.Cu")
		(net "GND")
	)
	(via
		(at 155.883102 -108.868718)
		(size 0.7112)
		(drill 0.4064)
		(layers "F.Cu" "B.Cu")
		(net "GND")
	)
	(via
		(at 96.800162 -2.705354)
		(size 0.6604)
		(drill 0.3556)
		(layers "F.Cu" "B.Cu")
		(net "GND")
	)
	(via
		(at 116.000022 -63.000128)
		(size 0.4572)
		(drill 0.2032)
		(layers "F.Cu" "B.Cu")
		(net "GND")
	)
	(via
		(at 171.000166 -42.399966)
		(size 0.508)
		(drill 0.254)
		(layers "F.Cu" "B.Cu")
		(net "GND")
	)
	(via
		(at 179.7177 -143.602964)
		(size 0.7112)
		(drill 0.4064)
		(layers "F.Cu" "B.Cu")
		(net "GND")
	)
	(via
		(at 208.603088 -7.45236)
		(size 0.7112)
		(drill 0.4064)
		(layers "F.Cu" "B.Cu")
		(net "GND")
	)
	(via
		(at 191.1477 -143.602964)
		(size 0.7112)
		(drill 0.4064)
		(layers "F.Cu" "B.Cu")
		(net "GND")
	)
	(via
		(at 51.1556 -45.3898)
		(size 0.5588)
		(drill 0.3048)
		(layers "F.Cu" "B.Cu")
		(net "GND")
	)
	(via
		(at 208.603088 -101.43236)
		(size 0.7112)
		(drill 0.4064)
		(layers "F.Cu" "B.Cu")
		(net "GND")
	)
	(via
		(at 61.62548 -99.23018)
		(size 0.5588)
		(drill 0.3048)
		(layers "F.Cu" "B.Cu")
		(net "GND")
	)
	(via
		(at 14.062456 -1.397)
		(size 0.7112)
		(drill 0.4064)
		(layers "F.Cu" "B.Cu")
		(net "GND")
	)
	(via
		(at 1.397 -6.447536)
		(size 0.7112)
		(drill 0.4064)
		(layers "F.Cu" "B.Cu")
		(net "GND")
	)
	(via
		(at 58.166 -24.13)
		(size 0.508)
		(drill 0.254)
		(layers "F.Cu" "B.Cu")
		(net "GND")
	)
	(via
		(at 179.799996 -35.999928)
		(size 0.508)
		(drill 0.254)
		(layers "F.Cu" "B.Cu")
		(net "GND")
	)
	(via
		(at 158.321502 -108.868718)
		(size 0.7112)
		(drill 0.4064)
		(layers "F.Cu" "B.Cu")
		(net "GND")
	)
	(via
		(at 66.19748 -100.37318)
		(size 0.5588)
		(drill 0.3048)
		(layers "F.Cu" "B.Cu")
		(net "GND")
	)
	(via
		(at 7.93496 -99.93376)
		(size 0.508)
		(drill 0.254)
		(layers "F.Cu" "B.Cu")
		(net "GND")
	)
	(via
		(at 83.605624 -133.474968)
		(size 0.7112)
		(drill 0.4064)
		(layers "F.Cu" "B.Cu")
		(net "GND")
	)
	(via
		(at 208.603088 -31.58236)
		(size 0.7112)
		(drill 0.4064)
		(layers "F.Cu" "B.Cu")
		(net "GND")
	)
	(via
		(at 91.946984 -69.301614)
		(size 0.508)
		(drill 0.254)
		(layers "F.Cu" "B.Cu")
		(net "GND")
	)
	(via
		(at 62.53988 -99.23018)
		(size 0.5588)
		(drill 0.3048)
		(layers "F.Cu" "B.Cu")
		(net "GND")
	)
	(via
		(at 104.199944 -110.300008)
		(size 0.6604)
		(drill 0.3556)
		(layers "F.Cu" "B.Cu")
		(net "GND")
	)
	(via
		(at 1.397 -34.387536)
		(size 0.7112)
		(drill 0.4064)
		(layers "F.Cu" "B.Cu")
		(net "GND")
	)
	(via
		(at 49.6316 -37.3888)
		(size 0.508)
		(drill 0.254)
		(layers "F.Cu" "B.Cu")
		(net "GND")
	)
	(via
		(at 127.999998 -66.000122)
		(size 0.4572)
		(drill 0.2032)
		(layers "F.Cu" "B.Cu")
		(net "GND")
	)
	(via
		(at 182.2577 -143.602964)
		(size 0.7112)
		(drill 0.4064)
		(layers "F.Cu" "B.Cu")
		(net "GND")
	)
	(via
		(at 156.8704 -34.1376)
		(size 0.508)
		(drill 0.254)
		(layers "F.Cu" "B.Cu")
		(net "GND")
	)
	(via
		(at 62.4332 -70.9168)
		(size 0.508)
		(drill 0.254)
		(layers "F.Cu" "B.Cu")
		(net "GND")
	)
	(via
		(at 127.999998 -64.000126)
		(size 0.4572)
		(drill 0.2032)
		(layers "F.Cu" "B.Cu")
		(net "GND")
	)
	(via
		(at 68.58 -8.509)
		(size 0.508)
		(drill 0.254)
		(layers "F.Cu" "B.Cu")
		(net "GND")
	)
	(via
		(at 1.397 -92.807536)
		(size 0.7112)
		(drill 0.4064)
		(layers "F.Cu" "B.Cu")
		(net "GND")
	)
	(via
		(at 1.397 -29.307536)
		(size 0.7112)
		(drill 0.4064)
		(layers "F.Cu" "B.Cu")
		(net "GND")
	)
	(via
		(at 129.999994 -78.000098)
		(size 0.4572)
		(drill 0.2032)
		(layers "F.Cu" "B.Cu")
		(net "GND")
	)
	(via
		(at 20.604226 -28.236164)
		(size 0.7112)
		(drill 0.4064)
		(layers "F.Cu" "B.Cu")
		(net "GND")
	)
	(via
		(at 171.000166 -43.999912)
		(size 0.508)
		(drill 0.254)
		(layers "F.Cu" "B.Cu")
		(net "GND")
	)
	(via
		(at 6.417564 -143.602964)
		(size 0.7112)
		(drill 0.4064)
		(layers "F.Cu" "B.Cu")
		(net "GND")
	)
	(via
		(at 174.999904 -28.79979)
		(size 0.508)
		(drill 0.254)
		(layers "F.Cu" "B.Cu")
		(net "GND")
	)
	(via
		(at 120.000014 -70.000114)
		(size 0.4572)
		(drill 0.2032)
		(layers "F.Cu" "B.Cu")
		(net "GND")
	)
	(via
		(at 196.2277 -143.602964)
		(size 0.7112)
		(drill 0.4064)
		(layers "F.Cu" "B.Cu")
		(net "GND")
	)
	(via
		(at 112.00003 -63.000128)
		(size 0.4572)
		(drill 0.2032)
		(layers "F.Cu" "B.Cu")
		(net "GND")
	)
	(via
		(at 128.697736 -115.791742)
		(size 0.6096)
		(drill 0.3048)
		(layers "F.Cu" "B.Cu")
		(net "GND")
	)
	(via
		(at 1.397 -82.647536)
		(size 0.7112)
		(drill 0.4064)
		(layers "F.Cu" "B.Cu")
		(net "GND")
	)
	(via
		(at 119.337328 -125.678946)
		(size 0.7112)
		(drill 0.4064)
		(layers "F.Cu" "B.Cu")
		(net "GND")
	)
	(via
		(at 20.387564 -143.602964)
		(size 0.7112)
		(drill 0.4064)
		(layers "F.Cu" "B.Cu")
		(net "GND")
	)
	(via
		(at 127.999998 -71.000112)
		(size 0.4572)
		(drill 0.2032)
		(layers "F.Cu" "B.Cu")
		(net "GND")
	)
	(via
		(at 208.603088 -39.20236)
		(size 0.7112)
		(drill 0.4064)
		(layers "F.Cu" "B.Cu")
		(net "GND")
	)
	(via
		(at 178.84521 -104.055164)
		(size 0.7112)
		(drill 0.4064)
		(layers "F.Cu" "B.Cu")
		(net "GND")
	)
	(via
		(at 145.4277 -143.602964)
		(size 0.7112)
		(drill 0.4064)
		(layers "F.Cu" "B.Cu")
		(net "GND")
	)
	(via
		(at 1.397 -68.677536)
		(size 0.7112)
		(drill 0.4064)
		(layers "F.Cu" "B.Cu")
		(net "GND")
	)
	(via
		(at 7.22757 -47.692818)
		(size 0.508)
		(drill 0.254)
		(layers "F.Cu" "B.Cu")
		(net "GND")
	)
	(via
		(at 180.600096 -47.999904)
		(size 0.508)
		(drill 0.254)
		(layers "F.Cu" "B.Cu")
		(net "GND")
	)
	(via
		(at 42.1386 -52.07)
		(size 0.7112)
		(drill 0.4064)
		(layers "F.Cu" "B.Cu")
		(net "GND")
	)
	(via
		(at 114.000026 -57.00014)
		(size 0.4572)
		(drill 0.2032)
		(layers "F.Cu" "B.Cu")
		(net "GND")
	)
	(via
		(at 5.8674 -73.0758)
		(size 0.508)
		(drill 0.254)
		(layers "F.Cu" "B.Cu")
		(net "GND")
	)
	(via
		(at 54.2798 -113.9063)
		(size 0.7112)
		(drill 0.4064)
		(layers "F.Cu" "B.Cu")
		(net "GND")
	)
	(via
		(at 203.292456 -1.397)
		(size 0.7112)
		(drill 0.4064)
		(layers "F.Cu" "B.Cu")
		(net "GND")
	)
	(via
		(at 157.0482 -73.34123)
		(size 0.508)
		(drill 0.254)
		(layers "F.Cu" "B.Cu")
		(net "GND")
	)
	(via
		(at 24.222456 -1.397)
		(size 0.7112)
		(drill 0.4064)
		(layers "F.Cu" "B.Cu")
		(net "GND")
	)
	(via
		(at 170.20032 -46.400212)
		(size 0.508)
		(drill 0.254)
		(layers "F.Cu" "B.Cu")
		(net "GND")
	)
	(via
		(at 98.947986 -85.624162)
		(size 0.508)
		(drill 0.254)
		(layers "F.Cu" "B.Cu")
		(net "GND")
	)
	(via
		(at 105.000044 -78.000098)
		(size 0.4572)
		(drill 0.2032)
		(layers "F.Cu" "B.Cu")
		(net "GND")
	)
	(via
		(at 208.603088 -3.64236)
		(size 0.7112)
		(drill 0.4064)
		(layers "F.Cu" "B.Cu")
		(net "GND")
	)
	(via
		(at 22.952456 -1.397)
		(size 0.7112)
		(drill 0.4064)
		(layers "F.Cu" "B.Cu")
		(net "GND")
	)
	(via
		(at 208.603088 -103.97236)
		(size 0.7112)
		(drill 0.4064)
		(layers "F.Cu" "B.Cu")
		(net "GND")
	)
	(via
		(at 53.099208 -119.430292)
		(size 0.7112)
		(drill 0.4064)
		(layers "F.Cu" "B.Cu")
		(net "GND")
	)
	(via
		(at 130.999992 -72.00011)
		(size 0.4572)
		(drill 0.2032)
		(layers "F.Cu" "B.Cu")
		(net "GND")
	)
	(via
		(at 103.000048 -75.000104)
		(size 0.4572)
		(drill 0.2032)
		(layers "F.Cu" "B.Cu")
		(net "GND")
	)
	(via
		(at 36.7792 -52.0573)
		(size 0.7112)
		(drill 0.4064)
		(layers "F.Cu" "B.Cu")
		(net "GND")
	)
	(via
		(at 188.5188 -86.5632)
		(size 0.7112)
		(drill 0.4064)
		(layers "F.Cu" "B.Cu")
		(net "GND")
	)
	(via
		(at 1.397 -48.357536)
		(size 0.7112)
		(drill 0.4064)
		(layers "F.Cu" "B.Cu")
		(net "GND")
	)
	(via
		(at 5.8674 -80.899)
		(size 0.508)
		(drill 0.254)
		(layers "F.Cu" "B.Cu")
		(net "GND")
	)
	(via
		(at 199.7202 -78.7146)
		(size 0.508)
		(drill 0.254)
		(layers "F.Cu" "B.Cu")
		(net "GND")
	)
	(via
		(at 122.00001 -61.000132)
		(size 0.4572)
		(drill 0.2032)
		(layers "F.Cu" "B.Cu")
		(net "GND")
	)
	(via
		(at 1.397 -129.637536)
		(size 0.7112)
		(drill 0.4064)
		(layers "F.Cu" "B.Cu")
		(net "GND")
	)
	(via
		(at 179.799742 -42.399966)
		(size 0.508)
		(drill 0.254)
		(layers "F.Cu" "B.Cu")
		(net "GND")
	)
	(via
		(at 72.262492 -76.193904)
		(size 0.508)
		(drill 0.254)
		(layers "F.Cu" "B.Cu")
		(net "GND")
	)
	(via
		(at 196.115178 -21.093684)
		(size 0.508)
		(drill 0.254)
		(layers "F.Cu" "B.Cu")
		(net "GND")
	)
	(via
		(at 118.6434 -90.805)
		(size 0.508)
		(drill 0.254)
		(layers "F.Cu" "B.Cu")
		(net "GND")
	)
	(via
		(at 208.603088 -111.59236)
		(size 0.7112)
		(drill 0.4064)
		(layers "F.Cu" "B.Cu")
		(net "GND")
	)
	(via
		(at 17.872456 -1.397)
		(size 0.7112)
		(drill 0.4064)
		(layers "F.Cu" "B.Cu")
		(net "GND")
	)
	(via
		(at 118.000018 -71.000366)
		(size 0.4572)
		(drill 0.2032)
		(layers "F.Cu" "B.Cu")
		(net "GND")
	)
	(via
		(at 186.0804 -85.344)
		(size 0.7112)
		(drill 0.4064)
		(layers "F.Cu" "B.Cu")
		(net "GND")
	)
	(via
		(at 166.99992 -32.800036)
		(size 0.508)
		(drill 0.254)
		(layers "F.Cu" "B.Cu")
		(net "GND")
	)
	(via
		(at 82.642456 -1.397)
		(size 0.7112)
		(drill 0.4064)
		(layers "F.Cu" "B.Cu")
		(net "GND")
	)
	(via
		(at 118.814596 -91.986354)
		(size 0.508)
		(drill 0.254)
		(layers "F.Cu" "B.Cu")
		(net "GND")
	)
	(via
		(at 178.20005 -34.399982)
		(size 0.508)
		(drill 0.254)
		(layers "F.Cu" "B.Cu")
		(net "GND")
	)
	(via
		(at 67.6402 -104.6734)
		(size 0.508)
		(drill 0.254)
		(layers "F.Cu" "B.Cu")
		(net "GND")
	)
	(via
		(at 183.9976 -120.8024)
		(size 0.7112)
		(drill 0.4064)
		(layers "F.Cu" "B.Cu")
		(net "GND")
	)
	(via
		(at 149.8727 -85.8393)
		(size 0.508)
		(drill 0.254)
		(layers "F.Cu" "B.Cu")
		(net "GND")
	)
	(via
		(at 49.597564 -143.602964)
		(size 0.7112)
		(drill 0.4064)
		(layers "F.Cu" "B.Cu")
		(net "GND")
	)
	(via
		(at 125.000004 -81.000092)
		(size 0.4572)
		(drill 0.2032)
		(layers "F.Cu" "B.Cu")
		(net "GND")
	)
	(via
		(at 56.323738 -97.633536)
		(size 0.6604)
		(drill 0.3302)
		(layers "F.Cu" "B.Cu")
		(net "GND")
	)
	(via
		(at 176.3776 -115.0366)
		(size 0.5588)
		(drill 0.3048)
		(layers "F.Cu" "B.Cu")
		(net "GND")
	)
	(via
		(at 36.897564 -143.602964)
		(size 0.7112)
		(drill 0.4064)
		(layers "F.Cu" "B.Cu")
		(net "GND")
	)
	(via
		(at 161.0614 -64.008)
		(size 0.508)
		(drill 0.254)
		(layers "F.Cu" "B.Cu")
		(net "GND")
	)
	(via
		(at 64.837564 -143.602964)
		(size 0.7112)
		(drill 0.4064)
		(layers "F.Cu" "B.Cu")
		(net "GND")
	)
	(via
		(at 159.972502 -7.025894)
		(size 0.508)
		(drill 0.254)
		(layers "F.Cu" "B.Cu")
		(net "GND")
	)
	(via
		(at 1.397 -69.947536)
		(size 0.7112)
		(drill 0.4064)
		(layers "F.Cu" "B.Cu")
		(net "GND")
	)
	(via
		(at 1.397 -10.257536)
		(size 0.7112)
		(drill 0.4064)
		(layers "F.Cu" "B.Cu")
		(net "GND")
	)
	(via
		(at 40.7416 -108.6358)
		(size 0.7112)
		(drill 0.4064)
		(layers "F.Cu" "B.Cu")
		(net "GND")
	)
	(via
		(at 60.3504 -99.187)
		(size 0.508)
		(drill 0.254)
		(layers "F.Cu" "B.Cu")
		(net "GND")
	)
	(via
		(at 208.603088 -121.75236)
		(size 0.7112)
		(drill 0.4064)
		(layers "F.Cu" "B.Cu")
		(net "GND")
	)
	(via
		(at 68.647564 -143.602964)
		(size 0.7112)
		(drill 0.4064)
		(layers "F.Cu" "B.Cu")
		(net "GND")
	)
	(via
		(at 160.7566 -87.6173)
		(size 0.508)
		(drill 0.254)
		(layers "F.Cu" "B.Cu")
		(net "GND")
	)
	(via
		(at 177.400204 -31.20009)
		(size 0.508)
		(drill 0.254)
		(layers "F.Cu" "B.Cu")
		(net "GND")
	)
	(via
		(at 50.0126 -53.467)
		(size 0.7112)
		(drill 0.4064)
		(layers "F.Cu" "B.Cu")
		(net "GND")
	)
	(via
		(at 178.20005 -47.200058)
		(size 0.508)
		(drill 0.254)
		(layers "F.Cu" "B.Cu")
		(net "GND")
	)
	(via
		(at 153.707592 -111.973868)
		(size 0.6096)
		(drill 0.3048)
		(layers "F.Cu" "B.Cu")
		(net "GND")
	)
	(via
		(at 86.806278 -53.608224)
		(size 0.508)
		(drill 0.254)
		(layers "F.Cu" "B.Cu")
		(net "GND")
	)
	(via
		(at 1.397 -87.727536)
		(size 0.7112)
		(drill 0.4064)
		(layers "F.Cu" "B.Cu")
		(net "GND")
	)
	(via
		(at 131.318 -55.499)
		(size 0.4572)
		(drill 0.2032)
		(layers "F.Cu" "B.Cu")
		(net "GND")
	)
	(via
		(at 124.000006 -57.00014)
		(size 0.4572)
		(drill 0.2032)
		(layers "F.Cu" "B.Cu")
		(net "GND")
	)
	(via
		(at 56.5912 -51.9684)
		(size 0.7112)
		(drill 0.4064)
		(layers "F.Cu" "B.Cu")
		(net "GND")
	)
	(via
		(at 69.917564 -143.602964)
		(size 0.7112)
		(drill 0.4064)
		(layers "F.Cu" "B.Cu")
		(net "GND")
	)
	(via
		(at 66.319908 -19.7866)
		(size 0.508)
		(drill 0.254)
		(layers "F.Cu" "B.Cu")
		(net "GND")
	)
	(via
		(at 17.562322 -84.987892)
		(size 0.508)
		(drill 0.254)
		(layers "F.Cu" "B.Cu")
		(net "GND")
	)
	(via
		(at 103.000048 -73.000108)
		(size 0.4572)
		(drill 0.2032)
		(layers "F.Cu" "B.Cu")
		(net "GND")
	)
	(via
		(at 40.9194 -40.767)
		(size 0.7112)
		(drill 0.4064)
		(layers "F.Cu" "B.Cu")
		(net "GND")
	)
	(via
		(at 178.08448 -109.37748)
		(size 0.508)
		(drill 0.254)
		(layers "F.Cu" "B.Cu")
		(net "GND")
	)
	(via
		(at 167.634158 -85.720428)
		(size 0.7112)
		(drill 0.4064)
		(layers "F.Cu" "B.Cu")
		(net "GND")
	)
	(via
		(at 116.000022 -68.000372)
		(size 0.4572)
		(drill 0.2032)
		(layers "F.Cu" "B.Cu")
		(net "GND")
	)
	(via
		(at 122.00001 -77.0001)
		(size 0.4572)
		(drill 0.2032)
		(layers "F.Cu" "B.Cu")
		(net "GND")
	)
	(via
		(at 170.999658 -35.199574)
		(size 0.508)
		(drill 0.254)
		(layers "F.Cu" "B.Cu")
		(net "GND")
	)
	(via
		(at 169.399712 -36.79952)
		(size 0.4572)
		(drill 0.2032)
		(layers "F.Cu" "B.Cu")
		(net "GND")
	)
	(via
		(at 30.547564 -143.602964)
		(size 0.7112)
		(drill 0.4064)
		(layers "F.Cu" "B.Cu")
		(net "GND")
	)
	(via
		(at 120.000014 -75.000104)
		(size 0.4572)
		(drill 0.2032)
		(layers "F.Cu" "B.Cu")
		(net "GND")
	)
	(via
		(at 189.8777 -143.602964)
		(size 0.7112)
		(drill 0.4064)
		(layers "F.Cu" "B.Cu")
		(net "GND")
	)
	(via
		(at 122.00001 -62.00013)
		(size 0.4572)
		(drill 0.2032)
		(layers "F.Cu" "B.Cu")
		(net "GND")
	)
	(via
		(at 208.603088 -107.78236)
		(size 0.7112)
		(drill 0.4064)
		(layers "F.Cu" "B.Cu")
		(net "GND")
	)
	(via
		(at 7.687564 -143.602964)
		(size 0.7112)
		(drill 0.4064)
		(layers "F.Cu" "B.Cu")
		(net "GND")
	)
	(via
		(at 94.06509 -125.134624)
		(size 0.7112)
		(drill 0.4064)
		(layers "F.Cu" "B.Cu")
		(net "GND")
	)
	(via
		(at 188.7728 -57.8866)
		(size 0.508)
		(drill 0.254)
		(layers "F.Cu" "B.Cu")
		(net "GND")
	)
	(via
		(at 35.56 -52.0573)
		(size 0.7112)
		(drill 0.4064)
		(layers "F.Cu" "B.Cu")
		(net "GND")
	)
	(via
		(at 208.603088 -69.68236)
		(size 0.7112)
		(drill 0.4064)
		(layers "F.Cu" "B.Cu")
		(net "GND")
	)
	(via
		(at 208.603088 -106.51236)
		(size 0.7112)
		(drill 0.4064)
		(layers "F.Cu" "B.Cu")
		(net "GND")
	)
	(via
		(at 11.522456 -1.397)
		(size 0.7112)
		(drill 0.4064)
		(layers "F.Cu" "B.Cu")
		(net "GND")
	)
	(via
		(at 63.97498 -100.37318)
		(size 0.5588)
		(drill 0.3048)
		(layers "F.Cu" "B.Cu")
		(net "GND")
	)
	(via
		(at 1.397 -116.937536)
		(size 0.7112)
		(drill 0.4064)
		(layers "F.Cu" "B.Cu")
		(net "GND")
	)
	(via
		(at 175.2346 -115.0493)
		(size 0.5588)
		(drill 0.3048)
		(layers "F.Cu" "B.Cu")
		(net "GND")
	)
	(via
		(at 204.320648 -47.074328)
		(size 0.508)
		(drill 0.254)
		(layers "F.Cu" "B.Cu")
		(net "GND")
	)
	(via
		(at 176.149 -94.8182)
		(size 0.508)
		(drill 0.254)
		(layers "F.Cu" "B.Cu")
		(net "GND")
	)
	(via
		(at 93.653356 -66.328036)
		(size 0.508)
		(drill 0.254)
		(layers "F.Cu" "B.Cu")
		(net "GND")
	)
	(via
		(at 208.603088 -102.70236)
		(size 0.7112)
		(drill 0.4064)
		(layers "F.Cu" "B.Cu")
		(net "GND")
	)
	(via
		(at 1.397 -39.467536)
		(size 0.7112)
		(drill 0.4064)
		(layers "F.Cu" "B.Cu")
		(net "GND")
	)
	(via
		(at 208.603088 -65.87236)
		(size 0.7112)
		(drill 0.4064)
		(layers "F.Cu" "B.Cu")
		(net "GND")
	)
	(via
		(at 1.397 -120.747536)
		(size 0.7112)
		(drill 0.4064)
		(layers "F.Cu" "B.Cu")
		(net "GND")
	)
	(via
		(at 127.6477 -143.602964)
		(size 0.7112)
		(drill 0.4064)
		(layers "F.Cu" "B.Cu")
		(net "GND")
	)
	(via
		(at 181.399688 -41.599612)
		(size 0.508)
		(drill 0.254)
		(layers "F.Cu" "B.Cu")
		(net "GND")
	)
	(via
		(at 48.327564 -143.602964)
		(size 0.7112)
		(drill 0.4064)
		(layers "F.Cu" "B.Cu")
		(net "GND")
	)
	(via
		(at 1.397 -66.137536)
		(size 0.7112)
		(drill 0.4064)
		(layers "F.Cu" "B.Cu")
		(net "GND")
	)
	(via
		(at 38.481 -40.767)
		(size 0.7112)
		(drill 0.4064)
		(layers "F.Cu" "B.Cu")
		(net "GND")
	)
	(via
		(at 57.217564 -143.602964)
		(size 0.7112)
		(drill 0.4064)
		(layers "F.Cu" "B.Cu")
		(net "GND")
	)
	(via
		(at 66.19748 -99.23018)
		(size 0.5588)
		(drill 0.3048)
		(layers "F.Cu" "B.Cu")
		(net "GND")
	)
	(via
		(at 62.609222 -101.490018)
		(size 0.5588)
		(drill 0.3048)
		(layers "F.Cu" "B.Cu")
		(net "GND")
	)
	(via
		(at 165.399974 -47.999904)
		(size 0.508)
		(drill 0.254)
		(layers "F.Cu" "B.Cu")
		(net "GND")
	)
	(via
		(at 23.779226 -28.236164)
		(size 0.7112)
		(drill 0.4064)
		(layers "F.Cu" "B.Cu")
		(net "GND")
	)
	(via
		(at 126.399544 -136.025128)
		(size 0.7112)
		(drill 0.4064)
		(layers "F.Cu" "B.Cu")
		(net "GND")
	)
	(via
		(at 77.562456 -1.397)
		(size 0.7112)
		(drill 0.4064)
		(layers "F.Cu" "B.Cu")
		(net "GND")
	)
	(via
		(at 175.2346 -116.1796)
		(size 0.5588)
		(drill 0.3048)
		(layers "F.Cu" "B.Cu")
		(net "GND")
	)
	(via
		(at 69.38391 -81.369154)
		(size 0.508)
		(drill 0.254)
		(layers "F.Cu" "B.Cu")
		(net "GND")
	)
	(via
		(at 208.603088 -86.19236)
		(size 0.7112)
		(drill 0.4064)
		(layers "F.Cu" "B.Cu")
		(net "GND")
	)
	(via
		(at 178.199796 -39.19982)
		(size 0.508)
		(drill 0.254)
		(layers "F.Cu" "B.Cu")
		(net "GND")
	)
	(via
		(at 182.39994 -112.51184)
		(size 0.508)
		(drill 0.254)
		(layers "F.Cu" "B.Cu")
		(net "GND")
	)
	(via
		(at 166.19982 -28.79979)
		(size 0.508)
		(drill 0.254)
		(layers "F.Cu" "B.Cu")
		(net "GND")
	)
	(via
		(at 16.577564 -143.602964)
		(size 0.7112)
		(drill 0.4064)
		(layers "F.Cu" "B.Cu")
		(net "GND")
	)
	(via
		(at 109.99978 -59.000136)
		(size 0.4572)
		(drill 0.2032)
		(layers "F.Cu" "B.Cu")
		(net "GND")
	)
	(via
		(at 28.701238 -29.777436)
		(size 0.6604)
		(drill 0.3302)
		(layers "F.Cu" "B.Cu")
		(net "GND")
	)
	(via
		(at 173.399704 -47.99965)
		(size 0.508)
		(drill 0.254)
		(layers "F.Cu" "B.Cu")
		(net "GND")
	)
	(via
		(at 110.000034 -57.00014)
		(size 0.4572)
		(drill 0.2032)
		(layers "F.Cu" "B.Cu")
		(net "GND")
	)
	(via
		(at 130.999992 -61.000132)
		(size 0.4572)
		(drill 0.2032)
		(layers "F.Cu" "B.Cu")
		(net "GND")
	)
	(via
		(at 57.8104 -53.1876)
		(size 0.7112)
		(drill 0.4064)
		(layers "F.Cu" "B.Cu")
		(net "GND")
	)
	(via
		(at 154.7876 -116.2431)
		(size 0.5588)
		(drill 0.3048)
		(layers "F.Cu" "B.Cu")
		(net "GND")
	)
	(via
		(at 64.438022 -101.490018)
		(size 0.5588)
		(drill 0.3048)
		(layers "F.Cu" "B.Cu")
		(net "GND")
	)
	(via
		(at 111.200184 -2.705354)
		(size 0.6604)
		(drill 0.3556)
		(layers "F.Cu" "B.Cu")
		(net "GND")
	)
	(via
		(at 56.5658 -39.1414)
		(size 0.7112)
		(drill 0.4064)
		(layers "F.Cu" "B.Cu")
		(net "GND")
	)
	(via
		(at 110.000034 -67.000374)
		(size 0.4572)
		(drill 0.2032)
		(layers "F.Cu" "B.Cu")
		(net "GND")
	)
	(via
		(at 182.999888 -48.79975)
		(size 0.508)
		(drill 0.254)
		(layers "F.Cu" "B.Cu")
		(net "GND")
	)
	(via
		(at 68.58 -9.652)
		(size 0.508)
		(drill 0.254)
		(layers "F.Cu" "B.Cu")
		(net "GND")
	)
	(via
		(at 208.603088 -20.15236)
		(size 0.7112)
		(drill 0.4064)
		(layers "F.Cu" "B.Cu")
		(net "GND")
	)
	(via
		(at 158.1277 -143.602964)
		(size 0.7112)
		(drill 0.4064)
		(layers "F.Cu" "B.Cu")
		(net "GND")
	)
	(via
		(at 208.603088 -37.93236)
		(size 0.7112)
		(drill 0.4064)
		(layers "F.Cu" "B.Cu")
		(net "GND")
	)
	(via
		(at 1.397 -75.027536)
		(size 0.7112)
		(drill 0.4064)
		(layers "F.Cu" "B.Cu")
		(net "GND")
	)
	(via
		(at 99.000056 -52.00015)
		(size 0.4572)
		(drill 0.2032)
		(layers "F.Cu" "B.Cu")
		(net "GND")
	)
	(via
		(at 1.397 -14.067536)
		(size 0.7112)
		(drill 0.4064)
		(layers "F.Cu" "B.Cu")
		(net "GND")
	)
	(via
		(at 122.00001 -57.00014)
		(size 0.4572)
		(drill 0.2032)
		(layers "F.Cu" "B.Cu")
		(net "GND")
	)
	(via
		(at 143.599916 -2.705354)
		(size 0.6604)
		(drill 0.3556)
		(layers "F.Cu" "B.Cu")
		(net "GND")
	)
	(via
		(at 180.599588 -46.399704)
		(size 0.508)
		(drill 0.254)
		(layers "F.Cu" "B.Cu")
		(net "GND")
	)
	(via
		(at 71.187564 -143.602964)
		(size 0.7112)
		(drill 0.4064)
		(layers "F.Cu" "B.Cu")
		(net "GND")
	)
	(via
		(at 75.153266 -64.90716)
		(size 0.7112)
		(drill 0.4064)
		(layers "F.Cu" "B.Cu")
		(net "GND")
	)
	(via
		(at 97.832926 -124.603002)
		(size 0.7112)
		(drill 0.4064)
		(layers "F.Cu" "B.Cu")
		(net "GND")
	)
	(via
		(at 107.992926 -124.603002)
		(size 0.7112)
		(drill 0.4064)
		(layers "F.Cu" "B.Cu")
		(net "GND")
	)
	(via
		(at 166.99992 -31.199836)
		(size 0.508)
		(drill 0.254)
		(layers "F.Cu" "B.Cu")
		(net "GND")
	)
	(via
		(at 159.0802 -118.0846)
		(size 0.508)
		(drill 0.254)
		(layers "F.Cu" "B.Cu")
		(net "GND")
	)
	(via
		(at 171.799758 -51.199796)
		(size 0.508)
		(drill 0.254)
		(layers "F.Cu" "B.Cu")
		(net "GND")
	)
	(via
		(at 202.5777 -143.602964)
		(size 0.7112)
		(drill 0.4064)
		(layers "F.Cu" "B.Cu")
		(net "GND")
	)
	(via
		(at 208.603088 -110.32236)
		(size 0.7112)
		(drill 0.4064)
		(layers "F.Cu" "B.Cu")
		(net "GND")
	)
	(via
		(at 208.603088 -73.49236)
		(size 0.7112)
		(drill 0.4064)
		(layers "F.Cu" "B.Cu")
		(net "GND")
	)
	(via
		(at 126.399544 -133.485128)
		(size 0.7112)
		(drill 0.4064)
		(layers "F.Cu" "B.Cu")
		(net "GND")
	)
	(via
		(at 127.999998 -54.000146)
		(size 0.4572)
		(drill 0.2032)
		(layers "F.Cu" "B.Cu")
		(net "GND")
	)
	(via
		(at 75.133454 -53.414676)
		(size 0.7112)
		(drill 0.4064)
		(layers "F.Cu" "B.Cu")
		(net "GND")
	)
	(via
		(at 101.000052 -51.000152)
		(size 0.4572)
		(drill 0.2032)
		(layers "F.Cu" "B.Cu")
		(net "GND")
	)
	(via
		(at 69.942456 -1.397)
		(size 0.7112)
		(drill 0.4064)
		(layers "F.Cu" "B.Cu")
		(net "GND")
	)
	(via
		(at 152.3746 -111.3282)
		(size 0.508)
		(drill 0.254)
		(layers "F.Cu" "B.Cu")
		(net "GND")
	)
	(via
		(at 132.7277 -143.602964)
		(size 0.7112)
		(drill 0.4064)
		(layers "F.Cu" "B.Cu")
		(net "GND")
	)
	(via
		(at 1.397 -132.177536)
		(size 0.7112)
		(drill 0.4064)
		(layers "F.Cu" "B.Cu")
		(net "GND")
	)
	(via
		(at 106.999532 -58.999882)
		(size 0.4572)
		(drill 0.2032)
		(layers "F.Cu" "B.Cu")
		(net "GND")
	)
	(via
		(at 167.799766 -35.999928)
		(size 0.508)
		(drill 0.254)
		(layers "F.Cu" "B.Cu")
		(net "GND")
	)
	(via
		(at 208.603088 -63.33236)
		(size 0.7112)
		(drill 0.4064)
		(layers "F.Cu" "B.Cu")
		(net "GND")
	)
	(via
		(at 178.199796 -42.399966)
		(size 0.508)
		(drill 0.254)
		(layers "F.Cu" "B.Cu")
		(net "GND")
	)
	(via
		(at 164.197284 -1.66243)
		(size 0.7112)
		(drill 0.4064)
		(layers "F.Cu" "B.Cu")
		(net "GND")
	)
	(via
		(at 56.5912 -53.1876)
		(size 0.7112)
		(drill 0.4064)
		(layers "F.Cu" "B.Cu")
		(net "GND")
	)
	(via
		(at 170.8277 -143.602964)
		(size 0.7112)
		(drill 0.4064)
		(layers "F.Cu" "B.Cu")
		(net "GND")
	)
	(via
		(at 208.603088 -140.80236)
		(size 0.7112)
		(drill 0.4064)
		(layers "F.Cu" "B.Cu")
		(net "GND")
	)
	(via
		(at 182.999888 -43.999912)
		(size 0.508)
		(drill 0.254)
		(layers "F.Cu" "B.Cu")
		(net "GND")
	)
	(via
		(at 5.7277 -39.8145)
		(size 0.508)
		(drill 0.254)
		(layers "F.Cu" "B.Cu")
		(net "GND")
	)
	(via
		(at 149.32406 -108.38688)
		(size 0.508)
		(drill 0.254)
		(layers "F.Cu" "B.Cu")
		(net "GND")
	)
	(via
		(at 51.41722 -43.307)
		(size 0.7112)
		(drill 0.4064)
		(layers "F.Cu" "B.Cu")
		(net "GND")
	)
	(via
		(at 208.603088 -13.80236)
		(size 0.7112)
		(drill 0.4064)
		(layers "F.Cu" "B.Cu")
		(net "GND")
	)
	(via
		(at 116.000022 -61.000132)
		(size 0.4572)
		(drill 0.2032)
		(layers "F.Cu" "B.Cu")
		(net "GND")
	)
	(via
		(at 9.60882 -69.64172)
		(size 0.508)
		(drill 0.254)
		(layers "F.Cu" "B.Cu")
		(net "GND")
	)
	(via
		(at 125.000004 -51.000152)
		(size 0.4572)
		(drill 0.2032)
		(layers "F.Cu" "B.Cu")
		(net "GND")
	)
	(via
		(at 129.413 -113.284)
		(size 0.7112)
		(drill 0.4064)
		(layers "F.Cu" "B.Cu")
		(net "GND")
	)
	(via
		(at 19.080226 -28.236164)
		(size 0.7112)
		(drill 0.4064)
		(layers "F.Cu" "B.Cu")
		(net "GND")
	)
	(via
		(at 124.000006 -65.000124)
		(size 0.4572)
		(drill 0.2032)
		(layers "F.Cu" "B.Cu")
		(net "GND")
	)
	(via
		(at 83.605624 -136.014968)
		(size 0.7112)
		(drill 0.4064)
		(layers "F.Cu" "B.Cu")
		(net "GND")
	)
	(via
		(at 56.51246 -59.784742)
		(size 0.7112)
		(drill 0.4064)
		(layers "F.Cu" "B.Cu")
		(net "GND")
	)
	(via
		(at 160.7185 -74.21753)
		(size 0.508)
		(drill 0.254)
		(layers "F.Cu" "B.Cu")
		(net "GND")
	)
	(via
		(at 122.00001 -72.00011)
		(size 0.4572)
		(drill 0.2032)
		(layers "F.Cu" "B.Cu")
		(net "GND")
	)
	(via
		(at 159.540702 -108.868718)
		(size 0.7112)
		(drill 0.4064)
		(layers "F.Cu" "B.Cu")
		(net "GND")
	)
	(via
		(at 124.000006 -73.000108)
		(size 0.4572)
		(drill 0.2032)
		(layers "F.Cu" "B.Cu")
		(net "GND")
	)
	(via
		(at 95.319088 -124.933964)
		(size 0.7112)
		(drill 0.4064)
		(layers "F.Cu" "B.Cu")
		(net "GND")
	)
	(via
		(at 208.603088 -27.77236)
		(size 0.7112)
		(drill 0.4064)
		(layers "F.Cu" "B.Cu")
		(net "GND")
	)
	(via
		(at 106.000042 -77.0001)
		(size 0.4572)
		(drill 0.2032)
		(layers "F.Cu" "B.Cu")
		(net "GND")
	)
	(via
		(at 178.167284 -1.66243)
		(size 0.7112)
		(drill 0.4064)
		(layers "F.Cu" "B.Cu")
		(net "GND")
	)
	(via
		(at 117.00002 -81.000092)
		(size 0.4572)
		(drill 0.2032)
		(layers "F.Cu" "B.Cu")
		(net "GND")
	)
	(via
		(at 166.7383 -7.112)
		(size 0.508)
		(drill 0.254)
		(layers "F.Cu" "B.Cu")
		(net "GND")
	)
	(via
		(at 14.037564 -143.602964)
		(size 0.7112)
		(drill 0.4064)
		(layers "F.Cu" "B.Cu")
		(net "GND")
	)
	(via
		(at 173.399958 -42.399966)
		(size 0.508)
		(drill 0.254)
		(layers "F.Cu" "B.Cu")
		(net "GND")
	)
	(via
		(at 161.036 -59.4868)
		(size 0.508)
		(drill 0.254)
		(layers "F.Cu" "B.Cu")
		(net "GND")
	)
	(via
		(at 122.00001 -59.000136)
		(size 0.4572)
		(drill 0.2032)
		(layers "F.Cu" "B.Cu")
		(net "GND")
	)
	(via
		(at 168.007284 -1.66243)
		(size 0.7112)
		(drill 0.4064)
		(layers "F.Cu" "B.Cu")
		(net "GND")
	)
	(via
		(at 208.603088 -18.88236)
		(size 0.7112)
		(drill 0.4064)
		(layers "F.Cu" "B.Cu")
		(net "GND")
	)
	(via
		(at 130.999992 -70.000114)
		(size 0.4572)
		(drill 0.2032)
		(layers "F.Cu" "B.Cu")
		(net "GND")
	)
	(via
		(at 165.747954 -10.341864)
		(size 0.508)
		(drill 0.254)
		(layers "F.Cu" "B.Cu")
		(net "GND")
	)
	(via
		(at 174.999904 -39.19982)
		(size 0.508)
		(drill 0.254)
		(layers "F.Cu" "B.Cu")
		(net "GND")
	)
	(via
		(at 131.608068 -108.072174)
		(size 0.7112)
		(drill 0.4064)
		(layers "F.Cu" "B.Cu")
		(net "GND")
	)
	(via
		(at 107.00004 -74.000106)
		(size 0.4572)
		(drill 0.2032)
		(layers "F.Cu" "B.Cu")
		(net "GND")
	)
	(via
		(at 159.96158 -93.80728)
		(size 0.508)
		(drill 0.254)
		(layers "F.Cu" "B.Cu")
		(net "GND")
	)
	(via
		(at 139.999974 -2.705354)
		(size 0.6604)
		(drill 0.3556)
		(layers "F.Cu" "B.Cu")
		(net "GND")
	)
	(via
		(at 208.603088 -116.67236)
		(size 0.7112)
		(drill 0.4064)
		(layers "F.Cu" "B.Cu")
		(net "GND")
	)
	(via
		(at 14.5669 -98.5012)
		(size 0.508)
		(drill 0.254)
		(layers "F.Cu" "B.Cu")
		(net "GND")
	)
	(via
		(at 179.799742 -43.999912)
		(size 0.508)
		(drill 0.254)
		(layers "F.Cu" "B.Cu")
		(net "GND")
	)
	(via
		(at 118.000018 -61.000132)
		(size 0.4572)
		(drill 0.2032)
		(layers "F.Cu" "B.Cu")
		(net "GND")
	)
	(via
		(at 208.603088 -45.55236)
		(size 0.7112)
		(drill 0.4064)
		(layers "F.Cu" "B.Cu")
		(net "GND")
	)
	(via
		(at 208.603088 -83.65236)
		(size 0.7112)
		(drill 0.4064)
		(layers "F.Cu" "B.Cu")
		(net "GND")
	)
	(via
		(at 70.3961 -84.328)
		(size 0.508)
		(drill 0.254)
		(layers "F.Cu" "B.Cu")
		(net "GND")
	)
	(via
		(at 171.800266 -48.800004)
		(size 0.508)
		(drill 0.254)
		(layers "F.Cu" "B.Cu")
		(net "GND")
	)
	(via
		(at 207.6577 -143.602964)
		(size 0.7112)
		(drill 0.4064)
		(layers "F.Cu" "B.Cu")
		(net "GND")
	)
	(via
		(at 1.397 -114.397536)
		(size 0.7112)
		(drill 0.4064)
		(layers "F.Cu" "B.Cu")
		(net "GND")
	)
	(via
		(at 1.397 -101.697536)
		(size 0.7112)
		(drill 0.4064)
		(layers "F.Cu" "B.Cu")
		(net "GND")
	)
	(via
		(at 184.003188 -117.891306)
		(size 0.7112)
		(drill 0.4064)
		(layers "F.Cu" "B.Cu")
		(net "GND")
	)
	(via
		(at 45.6692 -32.893)
		(size 0.5588)
		(drill 0.3048)
		(layers "F.Cu" "B.Cu")
		(net "GND")
	)
	(via
		(at 34.357564 -143.602964)
		(size 0.7112)
		(drill 0.4064)
		(layers "F.Cu" "B.Cu")
		(net "GND")
	)
	(via
		(at 157.0355 -41.168574)
		(size 0.508)
		(drill 0.254)
		(layers "F.Cu" "B.Cu")
		(net "GND")
	)
	(via
		(at 51.908456 -121.644918)
		(size 0.7112)
		(drill 0.4064)
		(layers "F.Cu" "B.Cu")
		(net "GND")
	)
	(via
		(at 51.1556 -44.2976)
		(size 0.5588)
		(drill 0.3048)
		(layers "F.Cu" "B.Cu")
		(net "GND")
	)
	(via
		(at 111.999776 -66.000122)
		(size 0.4572)
		(drill 0.2032)
		(layers "F.Cu" "B.Cu")
		(net "GND")
	)
	(via
		(at 159.37357 -47.082456)
		(size 0.508)
		(drill 0.254)
		(layers "F.Cu" "B.Cu")
		(net "GND")
	)
	(via
		(at 71.212456 -1.397)
		(size 0.7112)
		(drill 0.4064)
		(layers "F.Cu" "B.Cu")
		(net "GND")
	)
	(via
		(at 151.7777 -143.602964)
		(size 0.7112)
		(drill 0.4064)
		(layers "F.Cu" "B.Cu")
		(net "GND")
	)
	(via
		(at 161.798762 -17.477486)
		(size 0.508)
		(drill 0.254)
		(layers "F.Cu" "B.Cu")
		(net "GND")
	)
	(via
		(at 57.785 -35.4838)
		(size 0.7112)
		(drill 0.4064)
		(layers "F.Cu" "B.Cu")
		(net "GND")
	)
	(via
		(at 118.000018 -51.000152)
		(size 0.4572)
		(drill 0.2032)
		(layers "F.Cu" "B.Cu")
		(net "GND")
	)
	(via
		(at 1.397 -83.917536)
		(size 0.7112)
		(drill 0.4064)
		(layers "F.Cu" "B.Cu")
		(net "GND")
	)
	(via
		(at 168.841674 -83.540346)
		(size 0.7112)
		(drill 0.4064)
		(layers "F.Cu" "B.Cu")
		(net "GND")
	)
	(via
		(at 99.000056 -56.000142)
		(size 0.4572)
		(drill 0.2032)
		(layers "F.Cu" "B.Cu")
		(net "GND")
	)
	(via
		(at 46.098206 -52.985924)
		(size 0.6604)
		(drill 0.3302)
		(layers "F.Cu" "B.Cu")
		(net "GND")
	)
	(via
		(at 146.3294 -105.3592)
		(size 0.7112)
		(drill 0.4064)
		(layers "F.Cu" "B.Cu")
		(net "GND")
	)
	(via
		(at 50.0126 -44.2976)
		(size 0.5588)
		(drill 0.3048)
		(layers "F.Cu" "B.Cu")
		(net "GND")
	)
	(via
		(at 193.6877 -143.602964)
		(size 0.7112)
		(drill 0.4064)
		(layers "F.Cu" "B.Cu")
		(net "GND")
	)
	(via
		(at 153.5176 -116.9289)
		(size 0.5588)
		(drill 0.3048)
		(layers "F.Cu" "B.Cu")
		(net "GND")
	)
	(via
		(at 112.00003 -54.000146)
		(size 0.4572)
		(drill 0.2032)
		(layers "F.Cu" "B.Cu")
		(net "GND")
	)
	(via
		(at 48.97882 -42.0878)
		(size 0.7112)
		(drill 0.4064)
		(layers "F.Cu" "B.Cu")
		(net "GND")
	)
	(via
		(at 173.399958 -39.19982)
		(size 0.508)
		(drill 0.254)
		(layers "F.Cu" "B.Cu")
		(net "GND")
	)
	(via
		(at 179.2986 -79.0194)
		(size 0.7112)
		(drill 0.4064)
		(layers "F.Cu" "B.Cu")
		(net "GND")
	)
	(via
		(at 136.400032 -2.705354)
		(size 0.6604)
		(drill 0.3556)
		(layers "F.Cu" "B.Cu")
		(net "GND")
	)
	(via
		(at 51.41722 -42.0878)
		(size 0.7112)
		(drill 0.4064)
		(layers "F.Cu" "B.Cu")
		(net "GND")
	)
	(via
		(at 71.567294 -19.81581)
		(size 0.508)
		(drill 0.254)
		(layers "F.Cu" "B.Cu")
		(net "GND")
	)
	(via
		(at 168.4274 -64.1858)
		(size 0.508)
		(drill 0.254)
		(layers "F.Cu" "B.Cu")
		(net "GND")
	)
	(via
		(at 208.603088 -53.17236)
		(size 0.7112)
		(drill 0.4064)
		(layers "F.Cu" "B.Cu")
		(net "GND")
	)
	(via
		(at 56.50484 -61.027056)
		(size 0.7112)
		(drill 0.4064)
		(layers "F.Cu" "B.Cu")
		(net "GND")
	)
	(via
		(at 48.8696 -45.3898)
		(size 0.5588)
		(drill 0.3048)
		(layers "F.Cu" "B.Cu")
		(net "GND")
	)
	(via
		(at 108.000038 -66.000122)
		(size 0.4572)
		(drill 0.2032)
		(layers "F.Cu" "B.Cu")
		(net "GND")
	)
	(via
		(at 1.397 -90.267536)
		(size 0.7112)
		(drill 0.4064)
		(layers "F.Cu" "B.Cu")
		(net "GND")
	)
	(via
		(at 127.999998 -58.000138)
		(size 0.4572)
		(drill 0.2032)
		(layers "F.Cu" "B.Cu")
		(net "GND")
	)
	(via
		(at 208.603088 -56.98236)
		(size 0.7112)
		(drill 0.4064)
		(layers "F.Cu" "B.Cu")
		(net "GND")
	)
	(via
		(at 198.53656 -70.77964)
		(size 0.508)
		(drill 0.254)
		(layers "F.Cu" "B.Cu")
		(net "GND")
	)
	(via
		(at 208.603088 -115.40236)
		(size 0.7112)
		(drill 0.4064)
		(layers "F.Cu" "B.Cu")
		(net "GND")
	)
	(via
		(at 114.800126 -2.705354)
		(size 0.6604)
		(drill 0.3556)
		(layers "F.Cu" "B.Cu")
		(net "GND")
	)
	(via
		(at 208.603088 -76.03236)
		(size 0.7112)
		(drill 0.4064)
		(layers "F.Cu" "B.Cu")
		(net "GND")
	)
	(via
		(at 61.62294 -13.643356)
		(size 0.508)
		(drill 0.254)
		(layers "F.Cu" "B.Cu")
		(net "GND")
	)
	(via
		(at 129.999994 -51.000152)
		(size 0.4572)
		(drill 0.2032)
		(layers "F.Cu" "B.Cu")
		(net "GND")
	)
	(via
		(at 177.1777 -143.602964)
		(size 0.7112)
		(drill 0.4064)
		(layers "F.Cu" "B.Cu")
		(net "GND")
	)
	(via
		(at 131.445 -75.493372)
		(size 0.4572)
		(drill 0.2032)
		(layers "F.Cu" "B.Cu")
		(net "GND")
	)
	(via
		(at 182.999888 -39.19982)
		(size 0.508)
		(drill 0.254)
		(layers "F.Cu" "B.Cu")
		(net "GND")
	)
	(via
		(at 104.000046 -60.000134)
		(size 0.4572)
		(drill 0.2032)
		(layers "F.Cu" "B.Cu")
		(net "GND")
	)
	(via
		(at 39.7002 -40.767)
		(size 0.7112)
		(drill 0.4064)
		(layers "F.Cu" "B.Cu")
		(net "GND")
	)
	(via
		(at 165.399974 -39.99992)
		(size 0.508)
		(drill 0.254)
		(layers "F.Cu" "B.Cu")
		(net "GND")
	)
	(via
		(at 128.999996 -81.000092)
		(size 0.4572)
		(drill 0.2032)
		(layers "F.Cu" "B.Cu")
		(net "GND")
	)
	(via
		(at 186.0804 -87.7824)
		(size 0.7112)
		(drill 0.4064)
		(layers "F.Cu" "B.Cu")
		(net "GND")
	)
	(via
		(at 1.397 -139.797536)
		(size 0.7112)
		(drill 0.4064)
		(layers "F.Cu" "B.Cu")
		(net "GND")
	)
	(via
		(at 176.3776 -116.1796)
		(size 0.5588)
		(drill 0.3048)
		(layers "F.Cu" "B.Cu")
		(net "GND")
	)
	(via
		(at 156.577284 -1.66243)
		(size 0.7112)
		(drill 0.4064)
		(layers "F.Cu" "B.Cu")
		(net "GND")
	)
	(via
		(at 168.4528 -60.4774)
		(size 0.508)
		(drill 0.254)
		(layers "F.Cu" "B.Cu")
		(net "GND")
	)
	(via
		(at 1.397 -91.537536)
		(size 0.7112)
		(drill 0.4064)
		(layers "F.Cu" "B.Cu")
		(net "GND")
	)
	(via
		(at 125.000004 -61.000132)
		(size 0.4572)
		(drill 0.2032)
		(layers "F.Cu" "B.Cu")
		(net "GND")
	)
	(via
		(at 91.4527 -85.6488)
		(size 0.508)
		(drill 0.254)
		(layers "F.Cu" "B.Cu")
		(net "GND")
	)
	(via
		(at 187.199778 -2.705354)
		(size 0.6604)
		(drill 0.3556)
		(layers "F.Cu" "B.Cu")
		(net "GND")
	)
	(via
		(at 94.0435 -88.2904)
		(size 0.508)
		(drill 0.254)
		(layers "F.Cu" "B.Cu")
		(net "GND")
	)
	(via
		(at 112.00003 -57.00014)
		(size 0.4572)
		(drill 0.2032)
		(layers "F.Cu" "B.Cu")
		(net "GND")
	)
	(via
		(at 184.22493 -22.506686)
		(size 0.508)
		(drill 0.254)
		(layers "F.Cu" "B.Cu")
		(net "GND")
	)
	(via
		(at 50.0126 -49.8094)
		(size 0.7112)
		(drill 0.4064)
		(layers "F.Cu" "B.Cu")
		(net "GND")
	)
	(via
		(at 169.399966 -29.59989)
		(size 0.508)
		(drill 0.254)
		(layers "F.Cu" "B.Cu")
		(net "GND")
	)
	(via
		(at 171.799758 -50.399696)
		(size 0.508)
		(drill 0.254)
		(layers "F.Cu" "B.Cu")
		(net "GND")
	)
	(via
		(at 15.307564 -143.602964)
		(size 0.7112)
		(drill 0.4064)
		(layers "F.Cu" "B.Cu")
		(net "GND")
	)
	(via
		(at 38.167564 -143.602964)
		(size 0.7112)
		(drill 0.4064)
		(layers "F.Cu" "B.Cu")
		(net "GND")
	)
	(via
		(at 1.397 -71.217536)
		(size 0.7112)
		(drill 0.4064)
		(layers "F.Cu" "B.Cu")
		(net "GND")
	)
	(via
		(at 8.574786 -69.64172)
		(size 0.508)
		(drill 0.254)
		(layers "F.Cu" "B.Cu")
		(net "GND")
	)
	(via
		(at 75.28179 -27.489658)
		(size 0.508)
		(drill 0.254)
		(layers "F.Cu" "B.Cu")
		(net "GND")
	)
	(via
		(at 190.977012 -70.311518)
		(size 0.508)
		(drill 0.254)
		(layers "F.Cu" "B.Cu")
		(net "GND")
	)
	(via
		(at 50.0126 -46.482)
		(size 0.5588)
		(drill 0.3048)
		(layers "F.Cu" "B.Cu")
		(net "GND")
	)
	(via
		(at 172.600112 -32.00019)
		(size 0.508)
		(drill 0.254)
		(layers "F.Cu" "B.Cu")
		(net "GND")
	)
	(via
		(at 1.397 -49.627536)
		(size 0.7112)
		(drill 0.4064)
		(layers "F.Cu" "B.Cu")
		(net "GND")
	)
	(via
		(at 124.000006 -74.000106)
		(size 0.4572)
		(drill 0.2032)
		(layers "F.Cu" "B.Cu")
		(net "GND")
	)
	(via
		(at 59.757564 -143.602964)
		(size 0.7112)
		(drill 0.4064)
		(layers "F.Cu" "B.Cu")
		(net "GND")
	)
	(via
		(at 208.603088 -46.82236)
		(size 0.7112)
		(drill 0.4064)
		(layers "F.Cu" "B.Cu")
		(net "GND")
	)
	(via
		(at 160.02 -118.0846)
		(size 0.508)
		(drill 0.254)
		(layers "F.Cu" "B.Cu")
		(net "GND")
	)
	(via
		(at 177.5206 -116.1796)
		(size 0.5588)
		(drill 0.3048)
		(layers "F.Cu" "B.Cu")
		(net "GND")
	)
	(via
		(at 122.00001 -64.000126)
		(size 0.4572)
		(drill 0.2032)
		(layers "F.Cu" "B.Cu")
		(net "GND")
	)
	(via
		(at 52.162456 -1.397)
		(size 0.7112)
		(drill 0.4064)
		(layers "F.Cu" "B.Cu")
		(net "GND")
	)
	(via
		(at 164.234876 -53.56225)
		(size 0.508)
		(drill 0.254)
		(layers "F.Cu" "B.Cu")
		(net "GND")
	)
	(via
		(at 173.399958 -46.399958)
		(size 0.508)
		(drill 0.254)
		(layers "F.Cu" "B.Cu")
		(net "GND")
	)
	(via
		(at 22.920452 -84.935314)
		(size 0.508)
		(drill 0.254)
		(layers "F.Cu" "B.Cu")
		(net "GND")
	)
	(via
		(at 207.102456 -1.397)
		(size 0.7112)
		(drill 0.4064)
		(layers "F.Cu" "B.Cu")
		(net "GND")
	)
	(via
		(at 12.6238 -99.314)
		(size 0.508)
		(drill 0.254)
		(layers "F.Cu" "B.Cu")
		(net "GND")
	)
	(via
		(at 203.0095 -18.06575)
		(size 0.508)
		(drill 0.254)
		(layers "F.Cu" "B.Cu")
		(net "GND")
	)
	(via
		(at 191.573658 -76.482194)
		(size 0.508)
		(drill 0.254)
		(layers "F.Cu" "B.Cu")
		(net "GND")
	)
	(via
		(at 171.800266 -34.40049)
		(size 0.508)
		(drill 0.254)
		(layers "F.Cu" "B.Cu")
		(net "GND")
	)
	(via
		(at 177.055526 -52.617878)
		(size 0.508)
		(drill 0.254)
		(layers "F.Cu" "B.Cu")
		(net "GND")
	)
	(via
		(at 21.140928 -101.588824)
		(size 0.508)
		(drill 0.254)
		(layers "F.Cu" "B.Cu")
		(net "GND")
	)
	(via
		(at 103.000048 -65.000124)
		(size 0.4572)
		(drill 0.2032)
		(layers "F.Cu" "B.Cu")
		(net "GND")
	)
	(via
		(at 76.10729 -74.3331)
		(size 0.508)
		(drill 0.254)
		(layers "F.Cu" "B.Cu")
		(net "GND")
	)
	(via
		(at 56.642 -96.074484)
		(size 0.7112)
		(drill 0.4064)
		(layers "F.Cu" "B.Cu")
		(net "GND")
	)
	(via
		(at 72.517 -33.1216)
		(size 0.7112)
		(drill 0.4064)
		(layers "F.Cu" "B.Cu")
		(net "GND")
	)
	(via
		(at 155.1305 -85.5599)
		(size 0.508)
		(drill 0.254)
		(layers "F.Cu" "B.Cu")
		(net "GND")
	)
	(via
		(at 118.08333 -125.478286)
		(size 0.7112)
		(drill 0.4064)
		(layers "F.Cu" "B.Cu")
		(net "GND")
	)
	(via
		(at 28.007564 -143.602964)
		(size 0.7112)
		(drill 0.4064)
		(layers "F.Cu" "B.Cu")
		(net "GND")
	)
	(via
		(at 7.712456 -1.397)
		(size 0.7112)
		(drill 0.4064)
		(layers "F.Cu" "B.Cu")
		(net "GND")
	)
	(via
		(at 102.00005 -54.000146)
		(size 0.4572)
		(drill 0.2032)
		(layers "F.Cu" "B.Cu")
		(net "GND")
	)
	(via
		(at 45.787564 -143.602964)
		(size 0.7112)
		(drill 0.4064)
		(layers "F.Cu" "B.Cu")
		(net "GND")
	)
	(via
		(at 208.603088 -8.72236)
		(size 0.7112)
		(drill 0.4064)
		(layers "F.Cu" "B.Cu")
		(net "GND")
	)
	(via
		(at 168.599612 -42.399712)
		(size 0.508)
		(drill 0.254)
		(layers "F.Cu" "B.Cu")
		(net "GND")
	)
	(via
		(at 56.894476 -16.05915)
		(size 0.508)
		(drill 0.254)
		(layers "F.Cu" "B.Cu")
		(net "GND")
	)
	(via
		(at 166.19982 -44.799758)
		(size 0.508)
		(drill 0.254)
		(layers "F.Cu" "B.Cu")
		(net "GND")
	)
	(via
		(at 208.603088 -2.37236)
		(size 0.7112)
		(drill 0.4064)
		(layers "F.Cu" "B.Cu")
		(net "GND")
	)
	(via
		(at 178.0794 -79.0194)
		(size 0.7112)
		(drill 0.4064)
		(layers "F.Cu" "B.Cu")
		(net "GND")
	)
	(via
		(at 72.714866 -64.90716)
		(size 0.7112)
		(drill 0.4064)
		(layers "F.Cu" "B.Cu")
		(net "GND")
	)
	(via
		(at 208.603088 -129.37236)
		(size 0.7112)
		(drill 0.4064)
		(layers "F.Cu" "B.Cu")
		(net "GND")
	)
	(via
		(at 178.20005 -45.599858)
		(size 0.508)
		(drill 0.254)
		(layers "F.Cu" "B.Cu")
		(net "GND")
	)
	(via
		(at 208.603088 -68.41236)
		(size 0.7112)
		(drill 0.4064)
		(layers "F.Cu" "B.Cu")
		(net "GND")
	)
	(via
		(at 192.5447 -41.6687)
		(size 0.508)
		(drill 0.254)
		(layers "F.Cu" "B.Cu")
		(net "GND")
	)
	(via
		(at 129.999994 -53.000148)
		(size 0.4572)
		(drill 0.2032)
		(layers "F.Cu" "B.Cu")
		(net "GND")
	)
	(via
		(at 100.400104 -2.705354)
		(size 0.6604)
		(drill 0.3556)
		(layers "F.Cu" "B.Cu")
		(net "GND")
	)
	(via
		(at 132.827268 -108.072174)
		(size 0.7112)
		(drill 0.4064)
		(layers "F.Cu" "B.Cu")
		(net "GND")
	)
	(via
		(at 45.812456 -1.397)
		(size 0.7112)
		(drill 0.4064)
		(layers "F.Cu" "B.Cu")
		(net "GND")
	)
	(via
		(at 184.59958 -47.200058)
		(size 0.508)
		(drill 0.254)
		(layers "F.Cu" "B.Cu")
		(net "GND")
	)
	(via
		(at 183.9976 -124.5108)
		(size 0.7112)
		(drill 0.4064)
		(layers "F.Cu" "B.Cu")
		(net "GND")
	)
	(via
		(at 110.000034 -61.000132)
		(size 0.4572)
		(drill 0.2032)
		(layers "F.Cu" "B.Cu")
		(net "GND")
	)
	(via
		(at 1.397 -125.827536)
		(size 0.7112)
		(drill 0.4064)
		(layers "F.Cu" "B.Cu")
		(net "GND")
	)
	(via
		(at 54.702456 -1.397)
		(size 0.7112)
		(drill 0.4064)
		(layers "F.Cu" "B.Cu")
		(net "GND")
	)
	(via
		(at 190.799974 -2.705354)
		(size 0.6604)
		(drill 0.3556)
		(layers "F.Cu" "B.Cu")
		(net "GND")
	)
	(via
		(at 161.9377 -143.602964)
		(size 0.7112)
		(drill 0.4064)
		(layers "F.Cu" "B.Cu")
		(net "GND")
	)
	(via
		(at 109.99978 -64.99987)
		(size 0.4572)
		(drill 0.2032)
		(layers "F.Cu" "B.Cu")
		(net "GND")
	)
	(via
		(at 26.827226 -28.236164)
		(size 0.7112)
		(drill 0.4064)
		(layers "F.Cu" "B.Cu")
		(net "GND")
	)
	(via
		(at 101.000052 -61.000132)
		(size 0.4572)
		(drill 0.2032)
		(layers "F.Cu" "B.Cu")
		(net "GND")
	)
	(via
		(at 183.9976 -123.2408)
		(size 0.7112)
		(drill 0.4064)
		(layers "F.Cu" "B.Cu")
		(net "GND")
	)
	(via
		(at 94.149926 -62.634114)
		(size 0.508)
		(drill 0.254)
		(layers "F.Cu" "B.Cu")
		(net "GND")
	)
	(via
		(at 208.603088 -44.28236)
		(size 0.7112)
		(drill 0.4064)
		(layers "F.Cu" "B.Cu")
		(net "GND")
	)
	(via
		(at 120.000014 -59.000136)
		(size 0.4572)
		(drill 0.2032)
		(layers "F.Cu" "B.Cu")
		(net "GND")
	)
	(via
		(at 190.787782 -79.751936)
		(size 0.508)
		(drill 0.254)
		(layers "F.Cu" "B.Cu")
		(net "GND")
	)
	(via
		(at 208.603088 -32.85236)
		(size 0.7112)
		(drill 0.4064)
		(layers "F.Cu" "B.Cu")
		(net "GND")
	)
	(via
		(at 85.8266 -109.5248)
		(size 0.508)
		(drill 0.254)
		(layers "F.Cu" "B.Cu")
		(net "GND")
	)
	(via
		(at 166.19982 -46.399704)
		(size 0.508)
		(drill 0.254)
		(layers "F.Cu" "B.Cu")
		(net "GND")
	)
	(via
		(at 147.9677 -143.602964)
		(size 0.7112)
		(drill 0.4064)
		(layers "F.Cu" "B.Cu")
		(net "GND")
	)
	(via
		(at 1.397 -38.197536)
		(size 0.7112)
		(drill 0.4064)
		(layers "F.Cu" "B.Cu")
		(net "GND")
	)
	(via
		(at 17.6022 -96.2152)
		(size 0.508)
		(drill 0.254)
		(layers "F.Cu" "B.Cu")
		(net "GND")
	)
	(via
		(at 116.000022 -59.000136)
		(size 0.4572)
		(drill 0.2032)
		(layers "F.Cu" "B.Cu")
		(net "GND")
	)
	(via
		(at 154.7876 -117.1575)
		(size 0.5588)
		(drill 0.3048)
		(layers "F.Cu" "B.Cu")
		(net "GND")
	)
	(via
		(at 1.397 -137.257536)
		(size 0.7112)
		(drill 0.4064)
		(layers "F.Cu" "B.Cu")
		(net "GND")
	)
	(via
		(at 1.397 -105.507536)
		(size 0.7112)
		(drill 0.4064)
		(layers "F.Cu" "B.Cu")
		(net "GND")
	)
	(via
		(at 48.8696 -46.482)
		(size 0.5588)
		(drill 0.3048)
		(layers "F.Cu" "B.Cu")
		(net "GND")
	)
	(via
		(at 208.603088 -120.48236)
		(size 0.7112)
		(drill 0.4064)
		(layers "F.Cu" "B.Cu")
		(net "GND")
	)
	(via
		(at 172.599604 -35.199574)
		(size 0.508)
		(drill 0.254)
		(layers "F.Cu" "B.Cu")
		(net "GND")
	)
	(via
		(at 105.000044 -66.000122)
		(size 0.4572)
		(drill 0.2032)
		(layers "F.Cu" "B.Cu")
		(net "GND")
	)
	(via
		(at 208.603088 -60.79236)
		(size 0.7112)
		(drill 0.4064)
		(layers "F.Cu" "B.Cu")
		(net "GND")
	)
	(via
		(at 199.482456 -1.397)
		(size 0.7112)
		(drill 0.4064)
		(layers "F.Cu" "B.Cu")
		(net "GND")
	)
	(via
		(at 72.898 -29.8704)
		(size 0.7112)
		(drill 0.4064)
		(layers "F.Cu" "B.Cu")
		(net "GND")
	)
	(via
		(at 116.000022 -77.0001)
		(size 0.4572)
		(drill 0.2032)
		(layers "F.Cu" "B.Cu")
		(net "GND")
	)
	(via
		(at 50.0126 -47.5742)
		(size 0.5588)
		(drill 0.3048)
		(layers "F.Cu" "B.Cu")
		(net "GND")
	)
	(via
		(at 1.397 -113.127536)
		(size 0.7112)
		(drill 0.4064)
		(layers "F.Cu" "B.Cu")
		(net "GND")
	)
	(via
		(at 95.840296 -76.922376)
		(size 0.508)
		(drill 0.254)
		(layers "F.Cu" "B.Cu")
		(net "GND")
	)
	(via
		(at 165.399974 -38.399974)
		(size 0.508)
		(drill 0.254)
		(layers "F.Cu" "B.Cu")
		(net "GND")
	)
	(via
		(at 42.1386 -40.767)
		(size 0.7112)
		(drill 0.4064)
		(layers "F.Cu" "B.Cu")
		(net "GND")
	)
	(via
		(at 14.230604 -65.053718)
		(size 0.508)
		(drill 0.254)
		(layers "F.Cu" "B.Cu")
		(net "GND")
	)
	(via
		(at 168.599612 -43.999658)
		(size 0.508)
		(drill 0.254)
		(layers "F.Cu" "B.Cu")
		(net "GND")
	)
	(via
		(at 45.6692 -33.909)
		(size 0.5588)
		(drill 0.3048)
		(layers "F.Cu" "B.Cu")
		(net "GND")
	)
	(via
		(at 111.000032 -51.000152)
		(size 0.4572)
		(drill 0.2032)
		(layers "F.Cu" "B.Cu")
		(net "GND")
	)
	(via
		(at 208.603088 -131.91236)
		(size 0.7112)
		(drill 0.4064)
		(layers "F.Cu" "B.Cu")
		(net "GND")
	)
	(via
		(at 208.603088 -35.39236)
		(size 0.7112)
		(drill 0.4064)
		(layers "F.Cu" "B.Cu")
		(net "GND")
	)
	(via
		(at 174.999904 -40.799766)
		(size 0.508)
		(drill 0.254)
		(layers "F.Cu" "B.Cu")
		(net "GND")
	)
	(via
		(at 109.99978 -71.000112)
		(size 0.4572)
		(drill 0.2032)
		(layers "F.Cu" "B.Cu")
		(net "GND")
	)
	(via
		(at 167.634158 -82.062828)
		(size 0.7112)
		(drill 0.4064)
		(layers "F.Cu" "B.Cu")
		(net "GND")
	)
	(via
		(at 73.1012 -54.483)
		(size 0.7112)
		(drill 0.4064)
		(layers "F.Cu" "B.Cu")
		(net "GND")
	)
	(via
		(at 122.00001 -2.705354)
		(size 0.6604)
		(drill 0.3556)
		(layers "F.Cu" "B.Cu")
		(net "GND")
	)
	(via
		(at 175.800004 -45.599858)
		(size 0.508)
		(drill 0.254)
		(layers "F.Cu" "B.Cu")
		(net "GND")
	)
	(via
		(at 64.40805 -81.322418)
		(size 0.508)
		(drill 0.254)
		(layers "F.Cu" "B.Cu")
		(net "GND")
	)
	(via
		(at 1.397 -88.997536)
		(size 0.7112)
		(drill 0.4064)
		(layers "F.Cu" "B.Cu")
		(net "GND")
	)
	(via
		(at 208.603088 -59.52236)
		(size 0.7112)
		(drill 0.4064)
		(layers "F.Cu" "B.Cu")
		(net "GND")
	)
	(via
		(at 67.377564 -143.602964)
		(size 0.7112)
		(drill 0.4064)
		(layers "F.Cu" "B.Cu")
		(net "GND")
	)
	(via
		(at 118.400068 -2.705354)
		(size 0.6604)
		(drill 0.3556)
		(layers "F.Cu" "B.Cu")
		(net "GND")
	)
	(via
		(at 131.34975 -124.19965)
		(size 0.508)
		(drill 0.254)
		(layers "F.Cu" "B.Cu")
		(net "GND")
	)
	(via
		(at 101.000052 -77.0001)
		(size 0.4572)
		(drill 0.2032)
		(layers "F.Cu" "B.Cu")
		(net "GND")
	)
	(via
		(at 149.9108 -84.9249)
		(size 0.508)
		(drill 0.254)
		(layers "F.Cu" "B.Cu")
		(net "GND")
	)
	(via
		(at 1.397 -124.557536)
		(size 0.7112)
		(drill 0.4064)
		(layers "F.Cu" "B.Cu")
		(net "GND")
	)
	(via
		(at 208.603088 -64.60236)
		(size 0.7112)
		(drill 0.4064)
		(layers "F.Cu" "B.Cu")
		(net "GND")
	)
	(via
		(at 106.000042 -76.000102)
		(size 0.4572)
		(drill 0.2032)
		(layers "F.Cu" "B.Cu")
		(net "GND")
	)
	(via
		(at 208.603088 -6.18236)
		(size 0.7112)
		(drill 0.4064)
		(layers "F.Cu" "B.Cu")
		(net "GND")
	)
	(via
		(at 120.000014 -72.00011)
		(size 0.4572)
		(drill 0.2032)
		(layers "F.Cu" "B.Cu")
		(net "GND")
	)
	(via
		(at 72.898 -31.75)
		(size 0.7112)
		(drill 0.4064)
		(layers "F.Cu" "B.Cu")
		(net "GND")
	)
	(via
		(at 1.397 -77.567536)
		(size 0.7112)
		(drill 0.4064)
		(layers "F.Cu" "B.Cu")
		(net "GND")
	)
	(via
		(at 208.603088 -4.91236)
		(size 0.7112)
		(drill 0.4064)
		(layers "F.Cu" "B.Cu")
		(net "GND")
	)
	(via
		(at 178.0794 -77.8002)
		(size 0.7112)
		(drill 0.4064)
		(layers "F.Cu" "B.Cu")
		(net "GND")
	)
	(via
		(at 171.799758 -29.600144)
		(size 0.508)
		(drill 0.254)
		(layers "F.Cu" "B.Cu")
		(net "GND")
	)
	(via
		(at 53.407564 -143.602964)
		(size 0.7112)
		(drill 0.4064)
		(layers "F.Cu" "B.Cu")
		(net "GND")
	)
	(via
		(at 127 -52.00015)
		(size 0.4572)
		(drill 0.2032)
		(layers "F.Cu" "B.Cu")
		(net "GND")
	)
	(via
		(at 208.603088 -54.44236)
		(size 0.7112)
		(drill 0.4064)
		(layers "F.Cu" "B.Cu")
		(net "GND")
	)
	(via
		(at 127.999998 -69.000116)
		(size 0.4572)
		(drill 0.2032)
		(layers "F.Cu" "B.Cu")
		(net "GND")
	)
	(via
		(at 104.000046 -68.000118)
		(size 0.4572)
		(drill 0.2032)
		(layers "F.Cu" "B.Cu")
		(net "GND")
	)
	(via
		(at 40.0431 -106.1974)
		(size 0.7112)
		(drill 0.4064)
		(layers "F.Cu" "B.Cu")
		(net "GND")
	)
	(via
		(at 208.603088 -43.01236)
		(size 0.7112)
		(drill 0.4064)
		(layers "F.Cu" "B.Cu")
		(net "GND")
	)
	(via
		(at 40.7416 -109.855)
		(size 0.7112)
		(drill 0.4064)
		(layers "F.Cu" "B.Cu")
		(net "GND")
	)
	(via
		(at 178.0794 -80.2386)
		(size 0.7112)
		(drill 0.4064)
		(layers "F.Cu" "B.Cu")
		(net "GND")
	)
	(via
		(at 166.19982 -39.19982)
		(size 0.508)
		(drill 0.254)
		(layers "F.Cu" "B.Cu")
		(net "GND")
	)
	(via
		(at 163.2966 -100.4316)
		(size 0.508)
		(drill 0.254)
		(layers "F.Cu" "B.Cu")
		(net "GND")
	)
	(via
		(at 1.397 -50.897536)
		(size 0.7112)
		(drill 0.4064)
		(layers "F.Cu" "B.Cu")
		(net "GND")
	)
	(via
		(at 208.603088 -138.26236)
		(size 0.7112)
		(drill 0.4064)
		(layers "F.Cu" "B.Cu")
		(net "GND")
	)
	(via
		(at 179.00015 -31.20009)
		(size 0.508)
		(drill 0.254)
		(layers "F.Cu" "B.Cu")
		(net "GND")
	)
	(via
		(at 5.8674 -74.2188)
		(size 0.508)
		(drill 0.254)
		(layers "F.Cu" "B.Cu")
		(net "GND")
	)
	(via
		(at 105.000044 -51.000152)
		(size 0.4572)
		(drill 0.2032)
		(layers "F.Cu" "B.Cu")
		(net "GND")
	)
	(via
		(at 108.000038 -79.000096)
		(size 0.4572)
		(drill 0.2032)
		(layers "F.Cu" "B.Cu")
		(net "GND")
	)
	(via
		(at 104.199944 -114.099848)
		(size 0.6604)
		(drill 0.3556)
		(layers "F.Cu" "B.Cu")
		(net "GND")
	)
	(via
		(at 176.599596 -34.399474)
		(size 0.508)
		(drill 0.254)
		(layers "F.Cu" "B.Cu")
		(net "GND")
	)
	(via
		(at 208.603088 -112.86236)
		(size 0.7112)
		(drill 0.4064)
		(layers "F.Cu" "B.Cu")
		(net "GND")
	)
	(via
		(at 208.603088 -51.90236)
		(size 0.7112)
		(drill 0.4064)
		(layers "F.Cu" "B.Cu")
		(net "GND")
	)
	(via
		(at 116.829332 -125.277626)
		(size 0.7112)
		(drill 0.4064)
		(layers "F.Cu" "B.Cu")
		(net "GND")
	)
	(via
		(at 192.4177 -143.602964)
		(size 0.7112)
		(drill 0.4064)
		(layers "F.Cu" "B.Cu")
		(net "GND")
	)
	(via
		(at 68.58 -7.366)
		(size 0.508)
		(drill 0.254)
		(layers "F.Cu" "B.Cu")
		(net "GND")
	)
	(via
		(at 125.000004 -52.00015)
		(size 0.4572)
		(drill 0.2032)
		(layers "F.Cu" "B.Cu")
		(net "GND")
	)
	(via
		(at 101.000052 -83.000088)
		(size 0.4572)
		(drill 0.2032)
		(layers "F.Cu" "B.Cu")
		(net "GND")
	)
	(via
		(at 154.7876 -115.3287)
		(size 0.5588)
		(drill 0.3048)
		(layers "F.Cu" "B.Cu")
		(net "GND")
	)
	(via
		(at 83.15071 -110.167928)
		(size 0.508)
		(drill 0.254)
		(layers "F.Cu" "B.Cu")
		(net "GND")
	)
	(via
		(at 195.672456 -1.397)
		(size 0.7112)
		(drill 0.4064)
		(layers "F.Cu" "B.Cu")
		(net "GND")
	)
	(via
		(at 50.0126 -48.6664)
		(size 0.5588)
		(drill 0.3048)
		(layers "F.Cu" "B.Cu")
		(net "GND")
	)
	(via
		(at 120.000014 -64.000126)
		(size 0.4572)
		(drill 0.2032)
		(layers "F.Cu" "B.Cu")
		(net "GND")
	)
	(via
		(at 168.5036 -59.4614)
		(size 0.508)
		(drill 0.254)
		(layers "F.Cu" "B.Cu")
		(net "GND")
	)
	(via
		(at 12.767564 -143.602964)
		(size 0.7112)
		(drill 0.4064)
		(layers "F.Cu" "B.Cu")
		(net "GND")
	)
	(via
		(at 16.602456 -1.397)
		(size 0.7112)
		(drill 0.4064)
		(layers "F.Cu" "B.Cu")
		(net "GND")
	)
	(via
		(at 208.603088 -50.63236)
		(size 0.7112)
		(drill 0.4064)
		(layers "F.Cu" "B.Cu")
		(net "GND")
	)
	(via
		(at 169.455846 -5.946394)
		(size 0.508)
		(drill 0.254)
		(layers "F.Cu" "B.Cu")
		(net "GND")
	)
	(via
		(at 5.8674 -79.756)
		(size 0.508)
		(drill 0.254)
		(layers "F.Cu" "B.Cu")
		(net "GND")
	)
	(via
		(at 172.599858 -47.99965)
		(size 0.508)
		(drill 0.254)
		(layers "F.Cu" "B.Cu")
		(net "GND")
	)
	(via
		(at 1.397 -5.177536)
		(size 0.7112)
		(drill 0.4064)
		(layers "F.Cu" "B.Cu")
		(net "GND")
	)
	(via
		(at 104.000046 -80.000094)
		(size 0.4572)
		(drill 0.2032)
		(layers "F.Cu" "B.Cu")
		(net "GND")
	)
	(via
		(at 1.397 -15.337536)
		(size 0.7112)
		(drill 0.4064)
		(layers "F.Cu" "B.Cu")
		(net "GND")
	)
	(via
		(at 110.532926 -124.603002)
		(size 0.7112)
		(drill 0.4064)
		(layers "F.Cu" "B.Cu")
		(net "GND")
	)
	(via
		(at 186.0677 -143.602964)
		(size 0.7112)
		(drill 0.4064)
		(layers "F.Cu" "B.Cu")
		(net "GND")
	)
	(via
		(at 174.999904 -48.79975)
		(size 0.508)
		(drill 0.254)
		(layers "F.Cu" "B.Cu")
		(net "GND")
	)
	(via
		(at 11.497564 -143.602964)
		(size 0.7112)
		(drill 0.4064)
		(layers "F.Cu" "B.Cu")
		(net "GND")
	)
	(via
		(at 128.999996 -78.000098)
		(size 0.4572)
		(drill 0.2032)
		(layers "F.Cu" "B.Cu")
		(net "GND")
	)
	(via
		(at 1.397 -78.837536)
		(size 0.7112)
		(drill 0.4064)
		(layers "F.Cu" "B.Cu")
		(net "GND")
	)
	(via
		(at 123.000008 -81.000092)
		(size 0.4572)
		(drill 0.2032)
		(layers "F.Cu" "B.Cu")
		(net "GND")
	)
	(via
		(at 46.8884 -34.8996)
		(size 0.508)
		(drill 0.254)
		(layers "F.Cu" "B.Cu")
		(net "GND")
	)
	(via
		(at 125.000004 -63.000128)
		(size 0.4572)
		(drill 0.2032)
		(layers "F.Cu" "B.Cu")
		(net "GND")
	)
	(via
		(at 119.000016 -54.000146)
		(size 0.4572)
		(drill 0.2032)
		(layers "F.Cu" "B.Cu")
		(net "GND")
	)
	(via
		(at 1.397 -99.157536)
		(size 0.7112)
		(drill 0.4064)
		(layers "F.Cu" "B.Cu")
		(net "GND")
	)
	(via
		(at 180.949346 -40.890698)
		(size 0.6096)
		(drill 0.3048)
		(layers "F.Cu" "B.Cu")
		(net "GND")
	)
	(via
		(at 149.2377 -143.602964)
		(size 0.7112)
		(drill 0.4064)
		(layers "F.Cu" "B.Cu")
		(net "GND")
	)
	(via
		(at 173.399958 -40.80002)
		(size 0.508)
		(drill 0.254)
		(layers "F.Cu" "B.Cu")
		(net "GND")
	)
	(via
		(at 113.999772 -59.000136)
		(size 0.4572)
		(drill 0.2032)
		(layers "F.Cu" "B.Cu")
		(net "GND")
	)
	(via
		(at 175.800004 -46.399704)
		(size 0.508)
		(drill 0.254)
		(layers "F.Cu" "B.Cu")
		(net "GND")
	)
	(via
		(at 150.9268 -99.1616)
		(size 0.508)
		(drill 0.254)
		(layers "F.Cu" "B.Cu")
		(net "GND")
	)
	(via
		(at 125.000004 -70.000114)
		(size 0.4572)
		(drill 0.2032)
		(layers "F.Cu" "B.Cu")
		(net "GND")
	)
	(via
		(at 176.3776 -117.3226)
		(size 0.5588)
		(drill 0.3048)
		(layers "F.Cu" "B.Cu")
		(net "GND")
	)
	(via
		(at 50.19802 -43.307)
		(size 0.7112)
		(drill 0.4064)
		(layers "F.Cu" "B.Cu")
		(net "GND")
	)
	(via
		(at 26.737564 -143.602964)
		(size 0.7112)
		(drill 0.4064)
		(layers "F.Cu" "B.Cu")
		(net "GND")
	)
	(via
		(at 49.622456 -1.397)
		(size 0.7112)
		(drill 0.4064)
		(layers "F.Cu" "B.Cu")
		(net "GND")
	)
	(via
		(at 130.999992 -63.000128)
		(size 0.4572)
		(drill 0.2032)
		(layers "F.Cu" "B.Cu")
		(net "GND")
	)
	(via
		(at 208.603088 -96.35236)
		(size 0.7112)
		(drill 0.4064)
		(layers "F.Cu" "B.Cu")
		(net "GND")
	)
	(via
		(at 43.272456 -1.397)
		(size 0.7112)
		(drill 0.4064)
		(layers "F.Cu" "B.Cu")
		(net "GND")
	)
	(via
		(at 172.599858 -46.400466)
		(size 0.508)
		(drill 0.254)
		(layers "F.Cu" "B.Cu")
		(net "GND")
	)
	(via
		(at 40.7416 -107.4166)
		(size 0.7112)
		(drill 0.4064)
		(layers "F.Cu" "B.Cu")
		(net "GND")
	)
	(via
		(at 48.7426 -51.0286)
		(size 0.7112)
		(drill 0.4064)
		(layers "F.Cu" "B.Cu")
		(net "GND")
	)
	(via
		(at 6.442456 -1.397)
		(size 0.7112)
		(drill 0.4064)
		(layers "F.Cu" "B.Cu")
		(net "GND")
	)
	(via
		(at 1.397 -67.407536)
		(size 0.7112)
		(drill 0.4064)
		(layers "F.Cu" "B.Cu")
		(net "GND")
	)
	(via
		(at 80.077564 -143.602964)
		(size 0.7112)
		(drill 0.4064)
		(layers "F.Cu" "B.Cu")
		(net "GND")
	)
	(via
		(at 7.302246 -48.653192)
		(size 0.508)
		(drill 0.254)
		(layers "F.Cu" "B.Cu")
		(net "GND")
	)
	(via
		(at 203.8477 -143.602964)
		(size 0.7112)
		(drill 0.4064)
		(layers "F.Cu" "B.Cu")
		(net "GND")
	)
	(via
		(at 208.603088 -41.74236)
		(size 0.7112)
		(drill 0.4064)
		(layers "F.Cu" "B.Cu")
		(net "GND")
	)
	(via
		(at 120.000014 -61.000132)
		(size 0.4572)
		(drill 0.2032)
		(layers "F.Cu" "B.Cu")
		(net "GND")
	)
	(via
		(at 182.999888 -45.599858)
		(size 0.508)
		(drill 0.254)
		(layers "F.Cu" "B.Cu")
		(net "GND")
	)
	(via
		(at 182.999634 -42.399712)
		(size 0.508)
		(drill 0.254)
		(layers "F.Cu" "B.Cu")
		(net "GND")
	)
	(via
		(at 157.847284 -1.66243)
		(size 0.7112)
		(drill 0.4064)
		(layers "F.Cu" "B.Cu")
		(net "GND")
	)
	(via
		(at 68.616322 -70.350126)
		(size 0.508)
		(drill 0.254)
		(layers "F.Cu" "B.Cu")
		(net "GND")
	)
	(via
		(at 151.930608 -94.01302)
		(size 0.508)
		(drill 0.254)
		(layers "F.Cu" "B.Cu")
		(net "GND")
	)
	(via
		(at 8.5598 -58.5724)
		(size 0.508)
		(drill 0.254)
		(layers "F.Cu" "B.Cu")
		(net "GND")
	)
	(via
		(at 182.999888 -35.999928)
		(size 0.508)
		(drill 0.254)
		(layers "F.Cu" "B.Cu")
		(net "GND")
	)
	(via
		(at 57.8104 -55.626)
		(size 0.7112)
		(drill 0.4064)
		(layers "F.Cu" "B.Cu")
		(net "GND")
	)
	(via
		(at 63.523622 -101.490018)
		(size 0.5588)
		(drill 0.3048)
		(layers "F.Cu" "B.Cu")
		(net "GND")
	)
	(via
		(at 125.000004 -56.000142)
		(size 0.4572)
		(drill 0.2032)
		(layers "F.Cu" "B.Cu")
		(net "GND")
	)
	(via
		(at 172.599604 -36.79952)
		(size 0.508)
		(drill 0.254)
		(layers "F.Cu" "B.Cu")
		(net "GND")
	)
	(via
		(at 73.446894 -14.749272)
		(size 0.508)
		(drill 0.254)
		(layers "F.Cu" "B.Cu")
		(net "GND")
	)
	(via
		(at 208.603088 -40.47236)
		(size 0.7112)
		(drill 0.4064)
		(layers "F.Cu" "B.Cu")
		(net "GND")
	)
	(via
		(at 202.056492 -62.527434)
		(size 0.508)
		(drill 0.254)
		(layers "F.Cu" "B.Cu")
		(net "GND")
	)
	(via
		(at 56.5912 -56.8452)
		(size 0.7112)
		(drill 0.4064)
		(layers "F.Cu" "B.Cu")
		(net "GND")
	)
	(via
		(at 170.759374 -96.236282)
		(size 0.508)
		(drill 0.254)
		(layers "F.Cu" "B.Cu")
		(net "GND")
	)
	(via
		(at 137.8077 -143.602964)
		(size 0.7112)
		(drill 0.4064)
		(layers "F.Cu" "B.Cu")
		(net "GND")
	)
	(via
		(at 208.603088 -16.34236)
		(size 0.7112)
		(drill 0.4064)
		(layers "F.Cu" "B.Cu")
		(net "GND")
	)
	(via
		(at 1.397 -44.547536)
		(size 0.7112)
		(drill 0.4064)
		(layers "F.Cu" "B.Cu")
		(net "GND")
	)
	(via
		(at 173.399958 -48.79975)
		(size 0.508)
		(drill 0.254)
		(layers "F.Cu" "B.Cu")
		(net "GND")
	)
	(via
		(at 208.603088 -125.56236)
		(size 0.7112)
		(drill 0.4064)
		(layers "F.Cu" "B.Cu")
		(net "GND")
	)
	(via
		(at 2.632456 -1.397)
		(size 0.7112)
		(drill 0.4064)
		(layers "F.Cu" "B.Cu")
		(net "GND")
	)
	(via
		(at 193.22161 -51.2318)
		(size 0.508)
		(drill 0.254)
		(layers "F.Cu" "B.Cu")
		(net "GND")
	)
	(via
		(at 196.342 -30.3784)
		(size 0.508)
		(drill 0.254)
		(layers "F.Cu" "B.Cu")
		(net "GND")
	)
	(via
		(at 120.000014 -57.00014)
		(size 0.4572)
		(drill 0.2032)
		(layers "F.Cu" "B.Cu")
		(net "GND")
	)
	(via
		(at 107.599988 -2.705354)
		(size 0.6604)
		(drill 0.3556)
		(layers "F.Cu" "B.Cu")
		(net "GND")
	)
	(via
		(at 146.64182 -117.96522)
		(size 0.508)
		(drill 0.254)
		(layers "F.Cu" "B.Cu")
		(net "GND")
	)
	(via
		(at 140.7795 -116.205)
		(size 0.508)
		(drill 0.254)
		(layers "F.Cu" "B.Cu")
		(net "GND")
	)
	(via
		(at 61.052456 -1.397)
		(size 0.7112)
		(drill 0.4064)
		(layers "F.Cu" "B.Cu")
		(net "GND")
	)
	(via
		(at 13.72616 -101.44506)
		(size 0.508)
		(drill 0.254)
		(layers "F.Cu" "B.Cu")
		(net "GND")
	)
	(via
		(at 186.0804 -90.2208)
		(size 0.7112)
		(drill 0.4064)
		(layers "F.Cu" "B.Cu")
		(net "GND")
	)
	(via
		(at 182.999888 -37.599874)
		(size 0.508)
		(drill 0.254)
		(layers "F.Cu" "B.Cu")
		(net "GND")
	)
	(via
		(at 1.397 -96.617536)
		(size 0.7112)
		(drill 0.4064)
		(layers "F.Cu" "B.Cu")
		(net "GND")
	)
	(via
		(at 187.3377 -143.602964)
		(size 0.7112)
		(drill 0.4064)
		(layers "F.Cu" "B.Cu")
		(net "GND")
	)
	(via
		(at 5.56514 -55.245)
		(size 0.508)
		(drill 0.254)
		(layers "F.Cu" "B.Cu")
		(net "GND")
	)
	(via
		(at 173.3677 -143.602964)
		(size 0.7112)
		(drill 0.4064)
		(layers "F.Cu" "B.Cu")
		(net "GND")
	)
	(via
		(at 76.267564 -143.602964)
		(size 0.7112)
		(drill 0.4064)
		(layers "F.Cu" "B.Cu")
		(net "GND")
	)
	(via
		(at 113.999772 -76.000356)
		(size 0.4572)
		(drill 0.2032)
		(layers "F.Cu" "B.Cu")
		(net "GND")
	)
	(via
		(at 177.39995 -32.800036)
		(size 0.508)
		(drill 0.254)
		(layers "F.Cu" "B.Cu")
		(net "GND")
	)
	(via
		(at 63.592456 -1.397)
		(size 0.7112)
		(drill 0.4064)
		(layers "F.Cu" "B.Cu")
		(net "GND")
	)
	(via
		(at 150.88235 -72.140318)
		(size 0.508)
		(drill 0.254)
		(layers "F.Cu" "B.Cu")
		(net "GND")
	)
	(via
		(at 122.00001 -65.000124)
		(size 0.4572)
		(drill 0.2032)
		(layers "F.Cu" "B.Cu")
		(net "GND")
	)
	(via
		(at 56.8071 -33.5026)
		(size 0.6604)
		(drill 0.3302)
		(layers "F.Cu" "B.Cu")
		(net "GND")
	)
	(via
		(at 176.68875 -71.6915)
		(size 0.508)
		(drill 0.254)
		(layers "F.Cu" "B.Cu")
		(net "GND")
	)
	(via
		(at 11.9126 -96.071182)
		(size 0.508)
		(drill 0.254)
		(layers "F.Cu" "B.Cu")
		(net "GND")
	)
	(via
		(at 199.39 -40.3606)
		(size 0.508)
		(drill 0.254)
		(layers "F.Cu" "B.Cu")
		(net "GND")
	)
	(via
		(at 120.000014 -68.000118)
		(size 0.4572)
		(drill 0.2032)
		(layers "F.Cu" "B.Cu")
		(net "GND")
	)
	(via
		(at 131.4577 -143.602964)
		(size 0.7112)
		(drill 0.4064)
		(layers "F.Cu" "B.Cu")
		(net "GND")
	)
	(via
		(at 1.397 -110.587536)
		(size 0.7112)
		(drill 0.4064)
		(layers "F.Cu" "B.Cu")
		(net "GND")
	)
	(via
		(at 159.8676 -105.238296)
		(size 0.508)
		(drill 0.254)
		(layers "F.Cu" "B.Cu")
		(net "GND")
	)
	(via
		(at 56.5658 -36.703)
		(size 0.7112)
		(drill 0.4064)
		(layers "F.Cu" "B.Cu")
		(net "GND")
	)
	(via
		(at 175.000412 -34.40049)
		(size 0.508)
		(drill 0.254)
		(layers "F.Cu" "B.Cu")
		(net "GND")
	)
	(via
		(at 9.410446 -76.949046)
		(size 0.508)
		(drill 0.254)
		(layers "F.Cu" "B.Cu")
		(net "GND")
	)
	(via
		(at 106.722926 -124.603002)
		(size 0.7112)
		(drill 0.4064)
		(layers "F.Cu" "B.Cu")
		(net "GND")
	)
	(via
		(at 115.57508 -125.07722)
		(size 0.7112)
		(drill 0.4064)
		(layers "F.Cu" "B.Cu")
		(net "GND")
	)
	(via
		(at 126.399544 -130.945128)
		(size 0.7112)
		(drill 0.4064)
		(layers "F.Cu" "B.Cu")
		(net "GND")
	)
	(via
		(at 198.755 -34.107882)
		(size 0.508)
		(drill 0.254)
		(layers "F.Cu" "B.Cu")
		(net "GND")
	)
	(via
		(at 48.8696 -44.2976)
		(size 0.5588)
		(drill 0.3048)
		(layers "F.Cu" "B.Cu")
		(net "GND")
	)
	(via
		(at 43.4086 -40.767)
		(size 0.7112)
		(drill 0.4064)
		(layers "F.Cu" "B.Cu")
		(net "GND")
	)
	(via
		(at 88.5444 -82.2706)
		(size 0.508)
		(drill 0.254)
		(layers "F.Cu" "B.Cu")
		(net "GND")
	)
	(via
		(at 51.1556 -48.6664)
		(size 0.5588)
		(drill 0.3048)
		(layers "F.Cu" "B.Cu")
		(net "GND")
	)
	(via
		(at 57.72404 -61.027056)
		(size 0.7112)
		(drill 0.4064)
		(layers "F.Cu" "B.Cu")
		(net "GND")
	)
	(via
		(at 208.603088 -92.54236)
		(size 0.7112)
		(drill 0.4064)
		(layers "F.Cu" "B.Cu")
		(net "GND")
	)
	(via
		(at 114.000026 -81.000092)
		(size 0.4572)
		(drill 0.2032)
		(layers "F.Cu" "B.Cu")
		(net "GND")
	)
	(via
		(at 74.997564 -143.602964)
		(size 0.7112)
		(drill 0.4064)
		(layers "F.Cu" "B.Cu")
		(net "GND")
	)
	(via
		(at 159.26308 -99.914456)
		(size 0.508)
		(drill 0.254)
		(layers "F.Cu" "B.Cu")
		(net "GND")
	)
	(via
		(at 159.9946 -62.4332)
		(size 0.508)
		(drill 0.254)
		(layers "F.Cu" "B.Cu")
		(net "GND")
	)
	(via
		(at 208.603088 -17.61236)
		(size 0.7112)
		(drill 0.4064)
		(layers "F.Cu" "B.Cu")
		(net "GND")
	)
	(via
		(at 104.000046 -70.000114)
		(size 0.4572)
		(drill 0.2032)
		(layers "F.Cu" "B.Cu")
		(net "GND")
	)
	(via
		(at 118.000018 -63.000128)
		(size 0.4572)
		(drill 0.2032)
		(layers "F.Cu" "B.Cu")
		(net "GND")
	)
	(via
		(at 182.85968 -109.1438)
		(size 0.508)
		(drill 0.254)
		(layers "F.Cu" "B.Cu")
		(net "GND")
	)
	(via
		(at 152.273762 -116.312442)
		(size 0.5588)
		(drill 0.3048)
		(layers "F.Cu" "B.Cu")
		(net "GND")
	)
	(via
		(at 1.397 -141.067536)
		(size 0.7112)
		(drill 0.4064)
		(layers "F.Cu" "B.Cu")
		(net "GND")
	)
	(via
		(at 208.603088 -21.42236)
		(size 0.7112)
		(drill 0.4064)
		(layers "F.Cu" "B.Cu")
		(net "GND")
	)
	(via
		(at 161.529268 -24.727154)
		(size 0.508)
		(drill 0.254)
		(layers "F.Cu" "B.Cu")
		(net "GND")
	)
	(via
		(at 182.990998 -47.200566)
		(size 0.508)
		(drill 0.254)
		(layers "F.Cu" "B.Cu")
		(net "GND")
	)
	(via
		(at 56.5912 -54.4068)
		(size 0.7112)
		(drill 0.4064)
		(layers "F.Cu" "B.Cu")
		(net "GND")
	)
	(via
		(at 176.59985 -42.399966)
		(size 0.508)
		(drill 0.254)
		(layers "F.Cu" "B.Cu")
		(net "GND")
	)
	(via
		(at 208.603088 -58.25236)
		(size 0.7112)
		(drill 0.4064)
		(layers "F.Cu" "B.Cu")
		(net "GND")
	)
	(via
		(at 1.397 -21.687536)
		(size 0.7112)
		(drill 0.4064)
		(layers "F.Cu" "B.Cu")
		(net "GND")
	)
	(via
		(at 44.542456 -1.397)
		(size 0.7112)
		(drill 0.4064)
		(layers "F.Cu" "B.Cu")
		(net "GND")
	)
	(via
		(at 50.19802 -42.0878)
		(size 0.7112)
		(drill 0.4064)
		(layers "F.Cu" "B.Cu")
		(net "GND")
	)
	(via
		(at 56.5658 -35.4838)
		(size 0.7112)
		(drill 0.4064)
		(layers "F.Cu" "B.Cu")
		(net "GND")
	)
	(via
		(at 51.1556 -46.482)
		(size 0.5588)
		(drill 0.3048)
		(layers "F.Cu" "B.Cu")
		(net "GND")
	)
	(via
		(at 168.402 -63.2968)
		(size 0.508)
		(drill 0.254)
		(layers "F.Cu" "B.Cu")
		(net "GND")
	)
	(via
		(at 126.000002 -78.000098)
		(size 0.4572)
		(drill 0.2032)
		(layers "F.Cu" "B.Cu")
		(net "GND")
	)
	(via
		(at 19.9644 -81.7118)
		(size 0.508)
		(drill 0.254)
		(layers "F.Cu" "B.Cu")
		(net "GND")
	)
	(via
		(at 67.402456 -1.397)
		(size 0.7112)
		(drill 0.4064)
		(layers "F.Cu" "B.Cu")
		(net "GND")
	)
	(via
		(at 125.000004 -54.000146)
		(size 0.4572)
		(drill 0.2032)
		(layers "F.Cu" "B.Cu")
		(net "GND")
	)
	(via
		(at 122.265186 -88.322658)
		(size 0.508)
		(drill 0.254)
		(layers "F.Cu" "B.Cu")
		(net "GND")
	)
	(via
		(at 62.89548 -100.37318)
		(size 0.5588)
		(drill 0.3048)
		(layers "F.Cu" "B.Cu")
		(net "GND")
	)
	(via
		(at 113.019586 -89.421462)
		(size 0.508)
		(drill 0.254)
		(layers "F.Cu" "B.Cu")
		(net "GND")
	)
	(via
		(at 43.247564 -143.602964)
		(size 0.7112)
		(drill 0.4064)
		(layers "F.Cu" "B.Cu")
		(net "GND")
	)
	(via
		(at 82.715354 -111.675672)
		(size 0.508)
		(drill 0.254)
		(layers "F.Cu" "B.Cu")
		(net "GND")
	)
	(via
		(at 173.399958 -37.599874)
		(size 0.508)
		(drill 0.254)
		(layers "F.Cu" "B.Cu")
		(net "GND")
	)
	(via
		(at 129.199894 -2.705354)
		(size 0.6604)
		(drill 0.3556)
		(layers "F.Cu" "B.Cu")
		(net "GND")
	)
	(via
		(at 208.603088 -114.13236)
		(size 0.7112)
		(drill 0.4064)
		(layers "F.Cu" "B.Cu")
		(net "GND")
	)
	(via
		(at 201.3077 -143.602964)
		(size 0.7112)
		(drill 0.4064)
		(layers "F.Cu" "B.Cu")
		(net "GND")
	)
	(via
		(at 101.000052 -59.000136)
		(size 0.4572)
		(drill 0.2032)
		(layers "F.Cu" "B.Cu")
		(net "GND")
	)
	(via
		(at 179.15128 -106.83494)
		(size 0.508)
		(drill 0.254)
		(layers "F.Cu" "B.Cu")
		(net "GND")
	)
	(via
		(at 44.517564 -143.602964)
		(size 0.7112)
		(drill 0.4064)
		(layers "F.Cu" "B.Cu")
		(net "GND")
	)
	(via
		(at 208.603088 -130.64236)
		(size 0.7112)
		(drill 0.4064)
		(layers "F.Cu" "B.Cu")
		(net "GND")
	)
	(via
		(at 81.372456 -1.397)
		(size 0.7112)
		(drill 0.4064)
		(layers "F.Cu" "B.Cu")
		(net "GND")
	)
	(via
		(at 208.603088 -36.66236)
		(size 0.7112)
		(drill 0.4064)
		(layers "F.Cu" "B.Cu")
		(net "GND")
	)
	(via
		(at 169.399712 -35.199574)
		(size 0.508)
		(drill 0.254)
		(layers "F.Cu" "B.Cu")
		(net "GND")
	)
	(via
		(at 125.000004 -59.000136)
		(size 0.4572)
		(drill 0.2032)
		(layers "F.Cu" "B.Cu")
		(net "GND")
	)
	(via
		(at 109.000036 -51.000152)
		(size 0.4572)
		(drill 0.2032)
		(layers "F.Cu" "B.Cu")
		(net "GND")
	)
	(via
		(at 191.224662 -25.6286)
		(size 0.508)
		(drill 0.254)
		(layers "F.Cu" "B.Cu")
		(net "GND")
	)
	(via
		(at 67.865752 -14.018768)
		(size 0.508)
		(drill 0.254)
		(layers "F.Cu" "B.Cu")
		(net "GND")
	)
	(via
		(at 186.0804 -89.0016)
		(size 0.7112)
		(drill 0.4064)
		(layers "F.Cu" "B.Cu")
		(net "GND")
	)
	(via
		(at 187.2996 -86.5632)
		(size 0.7112)
		(drill 0.4064)
		(layers "F.Cu" "B.Cu")
		(net "GND")
	)
	(via
		(at 178.199796 -43.999912)
		(size 0.508)
		(drill 0.254)
		(layers "F.Cu" "B.Cu")
		(net "GND")
	)
	(via
		(at 77.537564 -143.602964)
		(size 0.7112)
		(drill 0.4064)
		(layers "F.Cu" "B.Cu")
		(net "GND")
	)
	(via
		(at 92.962984 -72.96531)
		(size 0.508)
		(drill 0.254)
		(layers "F.Cu" "B.Cu")
		(net "GND")
	)
	(via
		(at 106.000042 -54.000146)
		(size 0.4572)
		(drill 0.2032)
		(layers "F.Cu" "B.Cu")
		(net "GND")
	)
	(via
		(at 178.84521 -101.616764)
		(size 0.7112)
		(drill 0.4064)
		(layers "F.Cu" "B.Cu")
		(net "GND")
	)
	(via
		(at 182.199788 -42.399712)
		(size 0.508)
		(drill 0.254)
		(layers "F.Cu" "B.Cu")
		(net "GND")
	)
	(via
		(at 164.599874 -41.599866)
		(size 0.508)
		(drill 0.254)
		(layers "F.Cu" "B.Cu")
		(net "GND")
	)
	(via
		(at 208.603088 -15.07236)
		(size 0.7112)
		(drill 0.4064)
		(layers "F.Cu" "B.Cu")
		(net "GND")
	)
	(via
		(at 12.050522 -84.886292)
		(size 0.508)
		(drill 0.254)
		(layers "F.Cu" "B.Cu")
		(net "GND")
	)
	(via
		(at 161.078926 -42.291)
		(size 0.508)
		(drill 0.254)
		(layers "F.Cu" "B.Cu")
		(net "GND")
	)
	(via
		(at 160.6677 -143.602964)
		(size 0.7112)
		(drill 0.4064)
		(layers "F.Cu" "B.Cu")
		(net "GND")
	)
	(via
		(at 118.000018 -68.000372)
		(size 0.4572)
		(drill 0.2032)
		(layers "F.Cu" "B.Cu")
		(net "GND")
	)
	(via
		(at 5.172456 -1.397)
		(size 0.7112)
		(drill 0.4064)
		(layers "F.Cu" "B.Cu")
		(net "GND")
	)
	(via
		(at 150.8887 -76.64577)
		(size 0.508)
		(drill 0.254)
		(layers "F.Cu" "B.Cu")
		(net "GND")
	)
	(via
		(at 101.000052 -64.000126)
		(size 0.4572)
		(drill 0.2032)
		(layers "F.Cu" "B.Cu")
		(net "GND")
	)
	(via
		(at 122.00001 -68.000118)
		(size 0.4572)
		(drill 0.2032)
		(layers "F.Cu" "B.Cu")
		(net "GND")
	)
	(via
		(at 166.19982 -41.599866)
		(size 0.508)
		(drill 0.254)
		(layers "F.Cu" "B.Cu")
		(net "GND")
	)
	(via
		(at 48.352456 -1.397)
		(size 0.7112)
		(drill 0.4064)
		(layers "F.Cu" "B.Cu")
		(net "GND")
	)
	(via
		(at 2.607564 -143.602964)
		(size 0.7112)
		(drill 0.4064)
		(layers "F.Cu" "B.Cu")
		(net "GND")
	)
	(via
		(at 104.000046 -2.705354)
		(size 0.6604)
		(drill 0.3556)
		(layers "F.Cu" "B.Cu")
		(net "GND")
	)
	(via
		(at 169.95775 -71.22287)
		(size 0.508)
		(drill 0.254)
		(layers "F.Cu" "B.Cu")
		(net "GND")
	)
	(via
		(at 128.999996 -53.000148)
		(size 0.4572)
		(drill 0.2032)
		(layers "F.Cu" "B.Cu")
		(net "GND")
	)
	(via
		(at 35.627564 -143.602964)
		(size 0.7112)
		(drill 0.4064)
		(layers "F.Cu" "B.Cu")
		(net "GND")
	)
	(via
		(at 161.036 -77.8002)
		(size 0.508)
		(drill 0.254)
		(layers "F.Cu" "B.Cu")
		(net "GND")
	)
	(via
		(at 1.397 -118.207536)
		(size 0.7112)
		(drill 0.4064)
		(layers "F.Cu" "B.Cu")
		(net "GND")
	)
	(via
		(at 57.8104 -54.4068)
		(size 0.7112)
		(drill 0.4064)
		(layers "F.Cu" "B.Cu")
		(net "GND")
	)
	(via
		(at 173.400466 -34.40049)
		(size 0.508)
		(drill 0.254)
		(layers "F.Cu" "B.Cu")
		(net "GND")
	)
	(via
		(at 184.7977 -143.602964)
		(size 0.7112)
		(drill 0.4064)
		(layers "F.Cu" "B.Cu")
		(net "GND")
	)
	(via
		(at 197.2564 -30.3784)
		(size 0.508)
		(drill 0.254)
		(layers "F.Cu" "B.Cu")
		(net "GND")
	)
	(via
		(at 109.262926 -124.603002)
		(size 0.7112)
		(drill 0.4064)
		(layers "F.Cu" "B.Cu")
		(net "GND")
	)
	(via
		(at 160.7185 -84.036916)
		(size 0.508)
		(drill 0.254)
		(layers "F.Cu" "B.Cu")
		(net "GND")
	)
	(via
		(at 157.0482 -83.224116)
		(size 0.508)
		(drill 0.254)
		(layers "F.Cu" "B.Cu")
		(net "GND")
	)
	(via
		(at 208.603088 -126.83236)
		(size 0.7112)
		(drill 0.4064)
		(layers "F.Cu" "B.Cu")
		(net "GND")
	)
	(via
		(at 99.102926 -124.603002)
		(size 0.7112)
		(drill 0.4064)
		(layers "F.Cu" "B.Cu")
		(net "GND")
	)
	(via
		(at 128.999996 -51.000152)
		(size 0.4572)
		(drill 0.2032)
		(layers "F.Cu" "B.Cu")
		(net "GND")
	)
	(via
		(at 200.752456 -1.397)
		(size 0.7112)
		(drill 0.4064)
		(layers "F.Cu" "B.Cu")
		(net "GND")
	)
	(via
		(at 208.603088 -29.04236)
		(size 0.7112)
		(drill 0.4064)
		(layers "F.Cu" "B.Cu")
		(net "GND")
	)
	(via
		(at 131.608068 -109.850174)
		(size 0.7112)
		(drill 0.4064)
		(layers "F.Cu" "B.Cu")
		(net "GND")
	)
	(via
		(at 208.603088 -123.02236)
		(size 0.7112)
		(drill 0.4064)
		(layers "F.Cu" "B.Cu")
		(net "GND")
	)
	(via
		(at 50.0126 -51.0286)
		(size 0.7112)
		(drill 0.4064)
		(layers "F.Cu" "B.Cu")
		(net "GND")
	)
	(via
		(at 1.397 -135.987536)
		(size 0.7112)
		(drill 0.4064)
		(layers "F.Cu" "B.Cu")
		(net "GND")
	)
	(via
		(at 125.000004 -57.00014)
		(size 0.4572)
		(drill 0.2032)
		(layers "F.Cu" "B.Cu")
		(net "GND")
	)
	(via
		(at 169.277284 -1.66243)
		(size 0.7112)
		(drill 0.4064)
		(layers "F.Cu" "B.Cu")
		(net "GND")
	)
	(via
		(at 196.942456 -1.397)
		(size 0.7112)
		(drill 0.4064)
		(layers "F.Cu" "B.Cu")
		(net "GND")
	)
	(via
		(at 208.603088 -77.30236)
		(size 0.7112)
		(drill 0.4064)
		(layers "F.Cu" "B.Cu")
		(net "GND")
	)
	(via
		(at 182.999888 -40.799766)
		(size 0.508)
		(drill 0.254)
		(layers "F.Cu" "B.Cu")
		(net "GND")
	)
	(via
		(at 1.397 -109.317536)
		(size 0.7112)
		(drill 0.4064)
		(layers "F.Cu" "B.Cu")
		(net "GND")
	)
	(via
		(at 168.599612 -39.19982)
		(size 0.508)
		(drill 0.254)
		(layers "F.Cu" "B.Cu")
		(net "GND")
	)
	(via
		(at 182.199788 -46.399704)
		(size 0.508)
		(drill 0.254)
		(layers "F.Cu" "B.Cu")
		(net "GND")
	)
	(via
		(at 208.603088 -87.46236)
		(size 0.7112)
		(drill 0.4064)
		(layers "F.Cu" "B.Cu")
		(net "GND")
	)
	(via
		(at 208.603088 -22.69236)
		(size 0.7112)
		(drill 0.4064)
		(layers "F.Cu" "B.Cu")
		(net "GND")
	)
	(via
		(at 203.071222 -23.6855)
		(size 0.508)
		(drill 0.254)
		(layers "F.Cu" "B.Cu")
		(net "GND")
	)
	(via
		(at 56.5912 -55.626)
		(size 0.7112)
		(drill 0.4064)
		(layers "F.Cu" "B.Cu")
		(net "GND")
	)
	(via
		(at 204.562456 -1.397)
		(size 0.7112)
		(drill 0.4064)
		(layers "F.Cu" "B.Cu")
		(net "GND")
	)
	(via
		(at 122.00001 -69.000116)
		(size 0.4572)
		(drill 0.2032)
		(layers "F.Cu" "B.Cu")
		(net "GND")
	)
	(via
		(at 153.5176 -114.7699)
		(size 0.5588)
		(drill 0.3048)
		(layers "F.Cu" "B.Cu")
		(net "GND")
	)
	(via
		(at 179.999894 -2.705354)
		(size 0.6604)
		(drill 0.3556)
		(layers "F.Cu" "B.Cu")
		(net "GND")
	)
	(via
		(at 182.199788 -31.199836)
		(size 0.508)
		(drill 0.254)
		(layers "F.Cu" "B.Cu")
		(net "GND")
	)
	(via
		(at 61.027564 -143.602964)
		(size 0.7112)
		(drill 0.4064)
		(layers "F.Cu" "B.Cu")
		(net "GND")
	)
	(via
		(at 165.7477 -143.602964)
		(size 0.7112)
		(drill 0.4064)
		(layers "F.Cu" "B.Cu")
		(net "GND")
	)
	(via
		(at 171.817284 -1.66243)
		(size 0.7112)
		(drill 0.4064)
		(layers "F.Cu" "B.Cu")
		(net "GND")
	)
	(via
		(at 104.000046 -79.000096)
		(size 0.4572)
		(drill 0.2032)
		(layers "F.Cu" "B.Cu")
		(net "GND")
	)
	(via
		(at 180.599588 -47.19955)
		(size 0.508)
		(drill 0.254)
		(layers "F.Cu" "B.Cu")
		(net "GND")
	)
	(via
		(at 78.75651 -8.228838)
		(size 0.508)
		(drill 0.254)
		(layers "F.Cu" "B.Cu")
		(net "GND")
	)
	(via
		(at 124.000006 -63.000128)
		(size 0.4572)
		(drill 0.2032)
		(layers "F.Cu" "B.Cu")
		(net "GND")
	)
	(via
		(at 127.999998 -75.000104)
		(size 0.4572)
		(drill 0.2032)
		(layers "F.Cu" "B.Cu")
		(net "GND")
	)
	(via
		(at 208.603088 -135.72236)
		(size 0.7112)
		(drill 0.4064)
		(layers "F.Cu" "B.Cu")
		(net "GND")
	)
	(via
		(at 83.605624 -141.094968)
		(size 0.7112)
		(drill 0.4064)
		(layers "F.Cu" "B.Cu")
		(net "GND")
	)
	(via
		(at 208.603088 -91.27236)
		(size 0.7112)
		(drill 0.4064)
		(layers "F.Cu" "B.Cu")
		(net "GND")
	)
	(via
		(at 164.600128 -31.20009)
		(size 0.508)
		(drill 0.254)
		(layers "F.Cu" "B.Cu")
		(net "GND")
	)
	(via
		(at 170.199812 -39.19982)
		(size 0.508)
		(drill 0.254)
		(layers "F.Cu" "B.Cu")
		(net "GND")
	)
	(via
		(at 172.599858 -41.599866)
		(size 0.508)
		(drill 0.254)
		(layers "F.Cu" "B.Cu")
		(net "GND")
	)
	(via
		(at 70.488556 -14.749272)
		(size 0.508)
		(drill 0.254)
		(layers "F.Cu" "B.Cu")
		(net "GND")
	)
	(via
		(at 114.000026 -63.000128)
		(size 0.4572)
		(drill 0.2032)
		(layers "F.Cu" "B.Cu")
		(net "GND")
	)
	(via
		(at 96.57334 -124.733558)
		(size 0.7112)
		(drill 0.4064)
		(layers "F.Cu" "B.Cu")
		(net "GND")
	)
	(via
		(at 203.355448 -47.099728)
		(size 0.508)
		(drill 0.254)
		(layers "F.Cu" "B.Cu")
		(net "GND")
	)
	(via
		(at 62.2935 -24.9555)
		(size 0.508)
		(drill 0.254)
		(layers "F.Cu" "B.Cu")
		(net "GND")
	)
	(via
		(at 182.199788 -36.79952)
		(size 0.508)
		(drill 0.254)
		(layers "F.Cu" "B.Cu")
		(net "GND")
	)
	(via
		(at 175.79975 -35.199828)
		(size 0.508)
		(drill 0.254)
		(layers "F.Cu" "B.Cu")
		(net "GND")
	)
	(via
		(at 59.5503 -18.542)
		(size 0.508)
		(drill 0.254)
		(layers "F.Cu" "B.Cu")
		(net "GND")
	)
	(via
		(at 103.000048 -51.000152)
		(size 0.4572)
		(drill 0.2032)
		(layers "F.Cu" "B.Cu")
		(net "GND")
	)
	(via
		(at 48.7426 -53.467)
		(size 0.7112)
		(drill 0.4064)
		(layers "F.Cu" "B.Cu")
		(net "GND")
	)
	(via
		(at 50.0126 -52.2478)
		(size 0.7112)
		(drill 0.4064)
		(layers "F.Cu" "B.Cu")
		(net "GND")
	)
	(via
		(at 112.00003 -81.000092)
		(size 0.4572)
		(drill 0.2032)
		(layers "F.Cu" "B.Cu")
		(net "GND")
	)
	(via
		(at 25.303226 -28.236164)
		(size 0.7112)
		(drill 0.4064)
		(layers "F.Cu" "B.Cu")
		(net "GND")
	)
	(via
		(at 170.999658 -36.79952)
		(size 0.508)
		(drill 0.254)
		(layers "F.Cu" "B.Cu")
		(net "GND")
	)
	(via
		(at 179.2986 -77.8002)
		(size 0.7112)
		(drill 0.4064)
		(layers "F.Cu" "B.Cu")
		(net "GND")
	)
	(via
		(at 115.000278 -71.000366)
		(size 0.4572)
		(drill 0.2032)
		(layers "F.Cu" "B.Cu")
		(net "GND")
	)
	(via
		(at 48.514 -27.94)
		(size 0.508)
		(drill 0.254)
		(layers "F.Cu" "B.Cu")
		(net "GND")
	)
	(via
		(at 168.599612 -40.799766)
		(size 0.508)
		(drill 0.254)
		(layers "F.Cu" "B.Cu")
		(net "GND")
	)
	(via
		(at 111.999776 -59.000136)
		(size 0.4572)
		(drill 0.2032)
		(layers "F.Cu" "B.Cu")
		(net "GND")
	)
	(via
		(at 136.5377 -143.602964)
		(size 0.7112)
		(drill 0.4064)
		(layers "F.Cu" "B.Cu")
		(net "GND")
	)
	(via
		(at 208.603088 -49.36236)
		(size 0.7112)
		(drill 0.4064)
		(layers "F.Cu" "B.Cu")
		(net "GND")
	)
	(via
		(at 56.450484 -58.407808)
		(size 0.7112)
		(drill 0.4064)
		(layers "F.Cu" "B.Cu")
		(net "GND")
	)
	(via
		(at 122.00001 -66.000122)
		(size 0.4572)
		(drill 0.2032)
		(layers "F.Cu" "B.Cu")
		(net "GND")
	)
	(via
		(at 208.603088 -119.21236)
		(size 0.7112)
		(drill 0.4064)
		(layers "F.Cu" "B.Cu")
		(net "GND")
	)
	(via
		(at 1.397 -35.657536)
		(size 0.7112)
		(drill 0.4064)
		(layers "F.Cu" "B.Cu")
		(net "GND")
	)
	(via
		(at 186.0804 -84.1248)
		(size 0.7112)
		(drill 0.4064)
		(layers "F.Cu" "B.Cu")
		(net "GND")
	)
	(via
		(at 64.862456 -1.397)
		(size 0.7112)
		(drill 0.4064)
		(layers "F.Cu" "B.Cu")
		(net "GND")
	)
	(via
		(at 1.397 -85.187536)
		(size 0.7112)
		(drill 0.4064)
		(layers "F.Cu" "B.Cu")
		(net "GND")
	)
	(via
		(at 116.000022 -66.000122)
		(size 0.4572)
		(drill 0.2032)
		(layers "F.Cu" "B.Cu")
		(net "GND")
	)
	(via
		(at 73.727564 -143.602964)
		(size 0.7112)
		(drill 0.4064)
		(layers "F.Cu" "B.Cu")
		(net "GND")
	)
	(via
		(at 193.22161 -53.3908)
		(size 0.508)
		(drill 0.254)
		(layers "F.Cu" "B.Cu")
		(net "GND")
	)
	(via
		(at 179.00015 -34.400236)
		(size 0.508)
		(drill 0.254)
		(layers "F.Cu" "B.Cu")
		(net "GND")
	)
	(via
		(at 47.082456 -1.397)
		(size 0.7112)
		(drill 0.4064)
		(layers "F.Cu" "B.Cu")
		(net "GND")
	)
	(via
		(at 124.000006 -66.000122)
		(size 0.4572)
		(drill 0.2032)
		(layers "F.Cu" "B.Cu")
		(net "GND")
	)
	(via
		(at 105.452926 -124.603002)
		(size 0.7112)
		(drill 0.4064)
		(layers "F.Cu" "B.Cu")
		(net "GND")
	)
	(via
		(at 56.5658 -40.3606)
		(size 0.7112)
		(drill 0.4064)
		(layers "F.Cu" "B.Cu")
		(net "GND")
	)
	(via
		(at 58.512456 -1.397)
		(size 0.7112)
		(drill 0.4064)
		(layers "F.Cu" "B.Cu")
		(net "GND")
	)
	(via
		(at 167.799766 -35.200336)
		(size 0.508)
		(drill 0.254)
		(layers "F.Cu" "B.Cu")
		(net "GND")
	)
	(via
		(at 208.603088 -93.81236)
		(size 0.7112)
		(drill 0.4064)
		(layers "F.Cu" "B.Cu")
		(net "GND")
	)
	(via
		(at 208.603088 -78.57236)
		(size 0.7112)
		(drill 0.4064)
		(layers "F.Cu" "B.Cu")
		(net "GND")
	)
	(via
		(at 176.5173 -121.3739)
		(size 0.7112)
		(drill 0.4064)
		(layers "F.Cu" "B.Cu")
		(net "GND")
	)
	(via
		(at 179.799742 -40.799766)
		(size 0.508)
		(drill 0.254)
		(layers "F.Cu" "B.Cu")
		(net "GND")
	)
	(via
		(at 180.599842 -33.599882)
		(size 0.508)
		(drill 0.254)
		(layers "F.Cu" "B.Cu")
		(net "GND")
	)
	(via
		(at 48.7426 -52.2478)
		(size 0.7112)
		(drill 0.4064)
		(layers "F.Cu" "B.Cu")
		(net "GND")
	)
	(via
		(at 53.127656 -121.644918)
		(size 0.7112)
		(drill 0.4064)
		(layers "F.Cu" "B.Cu")
		(net "GND")
	)
	(via
		(at 61.694822 -101.490018)
		(size 0.5588)
		(drill 0.3048)
		(layers "F.Cu" "B.Cu")
		(net "GND")
	)
	(via
		(at 1.397 -94.077536)
		(size 0.7112)
		(drill 0.4064)
		(layers "F.Cu" "B.Cu")
		(net "GND")
	)
	(via
		(at 127.999998 -77.0001)
		(size 0.4572)
		(drill 0.2032)
		(layers "F.Cu" "B.Cu")
		(net "GND")
	)
	(via
		(at 182.199788 -41.599612)
		(size 0.508)
		(drill 0.254)
		(layers "F.Cu" "B.Cu")
		(net "GND")
	)
	(via
		(at 176.6824 -61.049916)
		(size 0.508)
		(drill 0.254)
		(layers "F.Cu" "B.Cu")
		(net "GND")
	)
	(via
		(at 175.9077 -143.602964)
		(size 0.7112)
		(drill 0.4064)
		(layers "F.Cu" "B.Cu")
		(net "GND")
	)
	(via
		(at 83.605624 -132.204968)
		(size 0.7112)
		(drill 0.4064)
		(layers "F.Cu" "B.Cu")
		(net "GND")
	)
	(via
		(at 154.3177 -143.602964)
		(size 0.7112)
		(drill 0.4064)
		(layers "F.Cu" "B.Cu")
		(net "GND")
	)
	(via
		(at 152.273762 -113.569242)
		(size 0.5588)
		(drill 0.3048)
		(layers "F.Cu" "B.Cu")
		(net "GND")
	)
	(via
		(at 76.292456 -1.397)
		(size 0.7112)
		(drill 0.4064)
		(layers "F.Cu" "B.Cu")
		(net "GND")
	)
	(via
		(at 86.233 -66.1416)
		(size 0.508)
		(drill 0.254)
		(layers "F.Cu" "B.Cu")
		(net "GND")
	)
	(via
		(at 178.199796 -37.599874)
		(size 0.508)
		(drill 0.254)
		(layers "F.Cu" "B.Cu")
		(net "GND")
	)
	(via
		(at 60.452 -37.973)
		(size 0.6096)
		(drill 0.3048)
		(layers "F.Cu" "B.Cu")
		(net "GND")
	)
	(via
		(at 182.199788 -32.799782)
		(size 0.508)
		(drill 0.254)
		(layers "F.Cu" "B.Cu")
		(net "GND")
	)
	(via
		(at 104.182926 -124.603002)
		(size 0.7112)
		(drill 0.4064)
		(layers "F.Cu" "B.Cu")
		(net "GND")
	)
	(via
		(at 10.252456 -1.397)
		(size 0.7112)
		(drill 0.4064)
		(layers "F.Cu" "B.Cu")
		(net "GND")
	)
	(via
		(at 166.602156 -10.142728)
		(size 0.508)
		(drill 0.254)
		(layers "F.Cu" "B.Cu")
		(net "GND")
	)
	(via
		(at 1.397 -11.527536)
		(size 0.7112)
		(drill 0.4064)
		(layers "F.Cu" "B.Cu")
		(net "GND")
	)
	(via
		(at 74.3204 -54.483)
		(size 0.7112)
		(drill 0.4064)
		(layers "F.Cu" "B.Cu")
		(net "GND")
	)
	(via
		(at 208.603088 -55.71236)
		(size 0.7112)
		(drill 0.4064)
		(layers "F.Cu" "B.Cu")
		(net "GND")
	)
	(via
		(at 120.000014 -51.000152)
		(size 0.4572)
		(drill 0.2032)
		(layers "F.Cu" "B.Cu")
		(net "GND")
	)
	(via
		(at 50.19802 -40.8686)
		(size 0.7112)
		(drill 0.4064)
		(layers "F.Cu" "B.Cu")
		(net "GND")
	)
	(via
		(at 107.00004 -71.000112)
		(size 0.4572)
		(drill 0.2032)
		(layers "F.Cu" "B.Cu")
		(net "GND")
	)
	(via
		(at 107.999784 -72.000364)
		(size 0.4572)
		(drill 0.2032)
		(layers "F.Cu" "B.Cu")
		(net "GND")
	)
	(via
		(at 93.006926 -62.634114)
		(size 0.508)
		(drill 0.254)
		(layers "F.Cu" "B.Cu")
		(net "GND")
	)
	(via
		(at 80.102456 -1.397)
		(size 0.7112)
		(drill 0.4064)
		(layers "F.Cu" "B.Cu")
		(net "GND")
	)
	(via
		(at 178.999896 -33.599882)
		(size 0.508)
		(drill 0.254)
		(layers "F.Cu" "B.Cu")
		(net "GND")
	)
	(via
		(at 101.000052 -71.000112)
		(size 0.4572)
		(drill 0.2032)
		(layers "F.Cu" "B.Cu")
		(net "GND")
	)
	(via
		(at 51.2318 -51.0286)
		(size 0.7112)
		(drill 0.4064)
		(layers "F.Cu" "B.Cu")
		(net "GND")
	)
	(via
		(at 75.0951 -43.066716)
		(size 0.7112)
		(drill 0.4064)
		(layers "F.Cu" "B.Cu")
		(net "GND")
	)
	(via
		(at 208.603088 -9.99236)
		(size 0.7112)
		(drill 0.4064)
		(layers "F.Cu" "B.Cu")
		(net "GND")
	)
	(via
		(at 161.657284 -1.66243)
		(size 0.7112)
		(drill 0.4064)
		(layers "F.Cu" "B.Cu")
		(net "GND")
	)
	(via
		(at 91.2876 -88.1888)
		(size 0.508)
		(drill 0.254)
		(layers "F.Cu" "B.Cu")
		(net "GND")
	)
	(via
		(at 66.441574 -94.228666)
		(size 0.508)
		(drill 0.254)
		(layers "F.Cu" "B.Cu")
		(net "GND")
	)
	(via
		(at 125.000004 -68.000118)
		(size 0.4572)
		(drill 0.2032)
		(layers "F.Cu" "B.Cu")
		(net "GND")
	)
	(via
		(at 179.2986 -80.2386)
		(size 0.7112)
		(drill 0.4064)
		(layers "F.Cu" "B.Cu")
		(net "GND")
	)
	(via
		(at 199.79894 -81.62036)
		(size 0.508)
		(drill 0.254)
		(layers "F.Cu" "B.Cu")
		(net "GND")
	)
	(via
		(at 174.1805 -106.54284)
		(size 0.508)
		(drill 0.254)
		(layers "F.Cu" "B.Cu")
		(net "GND")
	)
	(via
		(at 66.132456 -1.397)
		(size 0.7112)
		(drill 0.4064)
		(layers "F.Cu" "B.Cu")
		(net "GND")
	)
	(via
		(at 89.419938 -56.02986)
		(size 0.508)
		(drill 0.254)
		(layers "F.Cu" "B.Cu")
		(net "GND")
	)
	(via
		(at 1.397 -72.487536)
		(size 0.7112)
		(drill 0.4064)
		(layers "F.Cu" "B.Cu")
		(net "GND")
	)
	(via
		(at 167.66921 -90.621358)
		(size 0.7112)
		(drill 0.4064)
		(layers "F.Cu" "B.Cu")
		(net "GND")
	)
	(via
		(at 1.397 -55.977536)
		(size 0.7112)
		(drill 0.4064)
		(layers "F.Cu" "B.Cu")
		(net "GND")
	)
	(via
		(at 173.399704 -45.599604)
		(size 0.508)
		(drill 0.254)
		(layers "F.Cu" "B.Cu")
		(net "GND")
	)
	(via
		(at 20.412456 -1.397)
		(size 0.7112)
		(drill 0.4064)
		(layers "F.Cu" "B.Cu")
		(net "GND")
	)
	(via
		(at 13.3096 -60.4012)
		(size 0.508)
		(drill 0.254)
		(layers "F.Cu" "B.Cu")
		(net "GND")
	)
	(via
		(at 73.752456 -1.397)
		(size 0.7112)
		(drill 0.4064)
		(layers "F.Cu" "B.Cu")
		(net "GND")
	)
	(via
		(at 167.634158 -86.939628)
		(size 0.7112)
		(drill 0.4064)
		(layers "F.Cu" "B.Cu")
		(net "GND")
	)
	(via
		(at 100.372926 -124.603002)
		(size 0.7112)
		(drill 0.4064)
		(layers "F.Cu" "B.Cu")
		(net "GND")
	)
	(via
		(at 131.821936 -106.576114)
		(size 0.6604)
		(drill 0.3302)
		(layers "F.Cu" "B.Cu")
		(net "GND")
	)
	(via
		(at 208.603088 -95.08236)
		(size 0.7112)
		(drill 0.4064)
		(layers "F.Cu" "B.Cu")
		(net "GND")
	)
	(via
		(at 177.5333 -117.2972)
		(size 0.5588)
		(drill 0.3048)
		(layers "F.Cu" "B.Cu")
		(net "GND")
	)
	(via
		(at 1.397 -61.057536)
		(size 0.7112)
		(drill 0.4064)
		(layers "F.Cu" "B.Cu")
		(net "GND")
	)
	(via
		(at 170.547284 -1.66243)
		(size 0.7112)
		(drill 0.4064)
		(layers "F.Cu" "B.Cu")
		(net "GND")
	)
	(via
		(at 128.397 -120.396)
		(size 0.7112)
		(drill 0.4064)
		(layers "F.Cu" "B.Cu")
		(net "GND")
	)
	(via
		(at 125.000004 -60.000134)
		(size 0.4572)
		(drill 0.2032)
		(layers "F.Cu" "B.Cu")
		(net "GND")
	)
	(via
		(at 19.117564 -143.602964)
		(size 0.7112)
		(drill 0.4064)
		(layers "F.Cu" "B.Cu")
		(net "GND")
	)
	(via
		(at 178.999896 -48.79975)
		(size 0.508)
		(drill 0.254)
		(layers "F.Cu" "B.Cu")
		(net "GND")
	)
	(via
		(at 101.000052 -69.000116)
		(size 0.4572)
		(drill 0.2032)
		(layers "F.Cu" "B.Cu")
		(net "GND")
	)
	(via
		(at 153.5176 -115.8494)
		(size 0.5588)
		(drill 0.3048)
		(layers "F.Cu" "B.Cu")
		(net "GND")
	)
	(via
		(at 113.067084 -124.6759)
		(size 0.7112)
		(drill 0.4064)
		(layers "F.Cu" "B.Cu")
		(net "GND")
	)
	(via
		(at 1.397 -86.457536)
		(size 0.7112)
		(drill 0.4064)
		(layers "F.Cu" "B.Cu")
		(net "GND")
	)
	(via
		(at 54.677564 -143.602964)
		(size 0.7112)
		(drill 0.4064)
		(layers "F.Cu" "B.Cu")
		(net "GND")
	)
	(via
		(at 104.000046 -81.000092)
		(size 0.4572)
		(drill 0.2032)
		(layers "F.Cu" "B.Cu")
		(net "GND")
	)
	(via
		(at 1.397 -43.277536)
		(size 0.7112)
		(drill 0.4064)
		(layers "F.Cu" "B.Cu")
		(net "GND")
	)
	(via
		(at 125.000004 -53.000148)
		(size 0.4572)
		(drill 0.2032)
		(layers "F.Cu" "B.Cu")
		(net "GND")
	)
	(via
		(at 100.000054 -55.000144)
		(size 0.4572)
		(drill 0.2032)
		(layers "F.Cu" "B.Cu")
		(net "GND")
	)
	(via
		(at 179.92217 -115.496848)
		(size 0.508)
		(drill 0.254)
		(layers "F.Cu" "B.Cu")
		(net "GND")
	)
	(via
		(at 141.582394 -122.18035)
		(size 0.508)
		(drill 0.254)
		(layers "F.Cu" "B.Cu")
		(net "GND")
	)
	(via
		(at 1.397 -57.247536)
		(size 0.7112)
		(drill 0.4064)
		(layers "F.Cu" "B.Cu")
		(net "GND")
	)
	(via
		(at 3.877564 -143.602964)
		(size 0.7112)
		(drill 0.4064)
		(layers "F.Cu" "B.Cu")
		(net "GND")
	)
	(via
		(at 125.000004 -55.000144)
		(size 0.4572)
		(drill 0.2032)
		(layers "F.Cu" "B.Cu")
		(net "GND")
	)
	(via
		(at 182.199788 -38.39972)
		(size 0.508)
		(drill 0.254)
		(layers "F.Cu" "B.Cu")
		(net "GND")
	)
	(via
		(at 183.9976 -122.0216)
		(size 0.7112)
		(drill 0.4064)
		(layers "F.Cu" "B.Cu")
		(net "GND")
	)
	(via
		(at 62.297564 -143.602964)
		(size 0.7112)
		(drill 0.4064)
		(layers "F.Cu" "B.Cu")
		(net "GND")
	)
	(via
		(at 152.146 -60.071)
		(size 0.6096)
		(drill 0.3048)
		(layers "F.Cu" "B.Cu")
		(net "GND")
	)
	(via
		(at 56.618886 -94.453456)
		(size 0.7112)
		(drill 0.4064)
		(layers "F.Cu" "B.Cu")
		(net "GND")
	)
	(via
		(at 21.657564 -143.602964)
		(size 0.7112)
		(drill 0.4064)
		(layers "F.Cu" "B.Cu")
		(net "GND")
	)
	(via
		(at 113.901474 -88.579198)
		(size 0.508)
		(drill 0.254)
		(layers "F.Cu" "B.Cu")
		(net "GND")
	)
	(via
		(at 22.255226 -28.236164)
		(size 0.7112)
		(drill 0.4064)
		(layers "F.Cu" "B.Cu")
		(net "GND")
	)
	(via
		(at 126.399544 -134.755128)
		(size 0.7112)
		(drill 0.4064)
		(layers "F.Cu" "B.Cu")
		(net "GND")
	)
	(via
		(at 114.000026 -61.000132)
		(size 0.4572)
		(drill 0.2032)
		(layers "F.Cu" "B.Cu")
		(net "GND")
	)
	(via
		(at 56.5658 -37.9222)
		(size 0.7112)
		(drill 0.4064)
		(layers "F.Cu" "B.Cu")
		(net "GND")
	)
	(via
		(at 72.481694 -19.81581)
		(size 0.508)
		(drill 0.254)
		(layers "F.Cu" "B.Cu")
		(net "GND")
	)
	(via
		(at 108.000038 -57.00014)
		(size 0.4572)
		(drill 0.2032)
		(layers "F.Cu" "B.Cu")
		(net "GND")
	)
	(via
		(at 208.603088 -30.31236)
		(size 0.7112)
		(drill 0.4064)
		(layers "F.Cu" "B.Cu")
		(net "GND")
	)
	(via
		(at 177.39995 -35.199828)
		(size 0.508)
		(drill 0.254)
		(layers "F.Cu" "B.Cu")
		(net "GND")
	)
	(via
		(at 1.397 -81.377536)
		(size 0.7112)
		(drill 0.4064)
		(layers "F.Cu" "B.Cu")
		(net "GND")
	)
	(via
		(at 208.603088 -25.23236)
		(size 0.7112)
		(drill 0.4064)
		(layers "F.Cu" "B.Cu")
		(net "GND")
	)
	(via
		(at 170.8912 -111.463328)
		(size 0.508)
		(drill 0.254)
		(layers "F.Cu" "B.Cu")
		(net "GND")
	)
	(via
		(at 104.000046 -83.000088)
		(size 0.4572)
		(drill 0.2032)
		(layers "F.Cu" "B.Cu")
		(net "GND")
	)
	(via
		(at 106.000042 -65.000124)
		(size 0.4572)
		(drill 0.2032)
		(layers "F.Cu" "B.Cu")
		(net "GND")
	)
	(via
		(at 119.000016 -81.000092)
		(size 0.4572)
		(drill 0.2032)
		(layers "F.Cu" "B.Cu")
		(net "GND")
	)
	(via
		(at 40.7797 -105.1814)
		(size 0.7112)
		(drill 0.4064)
		(layers "F.Cu" "B.Cu")
		(net "GND")
	)
	(via
		(at 104.000046 -57.00014)
		(size 0.4572)
		(drill 0.2032)
		(layers "F.Cu" "B.Cu")
		(net "GND")
	)
	(via
		(at 159.9946 -60.8838)
		(size 0.508)
		(drill 0.254)
		(layers "F.Cu" "B.Cu")
		(net "GND")
	)
	(via
		(at 208.603088 -105.24236)
		(size 0.7112)
		(drill 0.4064)
		(layers "F.Cu" "B.Cu")
		(net "GND")
	)
	(via
		(at 83.912456 -1.397)
		(size 0.7112)
		(drill 0.4064)
		(layers "F.Cu" "B.Cu")
		(net "GND")
	)
	(via
		(at 150.227284 -1.66243)
		(size 0.7112)
		(drill 0.4064)
		(layers "F.Cu" "B.Cu")
		(net "GND")
	)
	(via
		(at 208.603088 -62.06236)
		(size 0.7112)
		(drill 0.4064)
		(layers "F.Cu" "B.Cu")
		(net "GND")
	)
	(via
		(at 85.268054 -56.89473)
		(size 0.508)
		(drill 0.254)
		(layers "F.Cu" "B.Cu")
		(net "GND")
	)
	(via
		(at 167.048942 -92.8116)
		(size 0.508)
		(drill 0.254)
		(layers "F.Cu" "B.Cu")
		(net "GND")
	)
	(via
		(at 142.8877 -143.602964)
		(size 0.7112)
		(drill 0.4064)
		(layers "F.Cu" "B.Cu")
		(net "GND")
	)
	(via
		(at 124.000006 -71.000112)
		(size 0.4572)
		(drill 0.2032)
		(layers "F.Cu" "B.Cu")
		(net "GND")
	)
	(via
		(at 205.832456 -1.397)
		(size 0.7112)
		(drill 0.4064)
		(layers "F.Cu" "B.Cu")
		(net "GND")
	)
	(via
		(at 171.409614 -66.764916)
		(size 0.508)
		(drill 0.254)
		(layers "F.Cu" "B.Cu")
		(net "GND")
	)
	(via
		(at 181.399688 -38.39972)
		(size 0.508)
		(drill 0.254)
		(layers "F.Cu" "B.Cu")
		(net "GND")
	)
	(via
		(at 178.4477 -143.602964)
		(size 0.7112)
		(drill 0.4064)
		(layers "F.Cu" "B.Cu")
		(net "GND")
	)
	(via
		(at 74.295 -31.877)
		(size 0.6604)
		(drill 0.3302)
		(layers "F.Cu" "B.Cu")
		(net "GND")
	)
	(via
		(at 208.603088 -124.29236)
		(size 0.7112)
		(drill 0.4064)
		(layers "F.Cu" "B.Cu")
		(net "GND")
	)
	(via
		(at 72.457564 -143.602964)
		(size 0.7112)
		(drill 0.4064)
		(layers "F.Cu" "B.Cu")
		(net "GND")
	)
	(via
		(at 208.603088 -100.16236)
		(size 0.7112)
		(drill 0.4064)
		(layers "F.Cu" "B.Cu")
		(net "GND")
	)
	(via
		(at 74.1934 -43.942)
		(size 0.7112)
		(drill 0.4064)
		(layers "F.Cu" "B.Cu")
		(net "GND")
	)
	(via
		(at 52.137564 -143.602964)
		(size 0.7112)
		(drill 0.4064)
		(layers "F.Cu" "B.Cu")
		(net "GND")
	)
	(via
		(at 109.000036 -63.000128)
		(size 0.4572)
		(drill 0.2032)
		(layers "F.Cu" "B.Cu")
		(net "GND")
	)
	(via
		(at 120.591326 -125.879606)
		(size 0.7112)
		(drill 0.4064)
		(layers "F.Cu" "B.Cu")
		(net "GND")
	)
	(via
		(at 130.999992 -65.000124)
		(size 0.4572)
		(drill 0.2032)
		(layers "F.Cu" "B.Cu")
		(net "GND")
	)
	(via
		(at 176.897284 -1.66243)
		(size 0.7112)
		(drill 0.4064)
		(layers "F.Cu" "B.Cu")
		(net "GND")
	)
	(via
		(at 168.599612 -46.399704)
		(size 0.508)
		(drill 0.254)
		(layers "F.Cu" "B.Cu")
		(net "GND")
	)
	(via
		(at 182.199788 -35.999674)
		(size 0.508)
		(drill 0.254)
		(layers "F.Cu" "B.Cu")
		(net "GND")
	)
	(via
		(at 201.653648 -75.44308)
		(size 0.508)
		(drill 0.254)
		(layers "F.Cu" "B.Cu")
		(net "GND")
	)
	(via
		(at 131.736338 -73.391522)
		(size 0.4572)
		(drill 0.2032)
		(layers "F.Cu" "B.Cu")
		(net "GND")
	)
	(via
		(at 184.59958 -44.000166)
		(size 0.508)
		(drill 0.254)
		(layers "F.Cu" "B.Cu")
		(net "GND")
	)
	(via
		(at 129.413 -114.5032)
		(size 0.7112)
		(drill 0.4064)
		(layers "F.Cu" "B.Cu")
		(net "GND")
	)
	(via
		(at 166.041578 -86.966806)
		(size 0.6096)
		(drill 0.3048)
		(layers "F.Cu" "B.Cu")
		(net "GND")
	)
	(via
		(at 128.397 -119.1768)
		(size 0.7112)
		(drill 0.4064)
		(layers "F.Cu" "B.Cu")
		(net "GND")
	)
	(via
		(at 152.273762 -115.398042)
		(size 0.5588)
		(drill 0.3048)
		(layers "F.Cu" "B.Cu")
		(net "GND")
	)
	(via
		(at 155.5242 -90.6399)
		(size 0.508)
		(drill 0.254)
		(layers "F.Cu" "B.Cu")
		(net "GND")
	)
	(via
		(at 157.0736 -44.054522)
		(size 0.508)
		(drill 0.254)
		(layers "F.Cu" "B.Cu")
		(net "GND")
	)
	(via
		(at 130.999992 -78.000098)
		(size 0.4572)
		(drill 0.2032)
		(layers "F.Cu" "B.Cu")
		(net "GND")
	)
	(via
		(at 110.000034 -54.000146)
		(size 0.4572)
		(drill 0.2032)
		(layers "F.Cu" "B.Cu")
		(net "GND")
	)
	(via
		(at 178.84521 -102.835964)
		(size 0.7112)
		(drill 0.4064)
		(layers "F.Cu" "B.Cu")
		(net "GND")
	)
	(via
		(at 1.397 -25.497536)
		(size 0.7112)
		(drill 0.4064)
		(layers "F.Cu" "B.Cu")
		(net "GND")
	)
	(via
		(at 61.652658 -16.101314)
		(size 0.508)
		(drill 0.254)
		(layers "F.Cu" "B.Cu")
		(net "GND")
	)
	(via
		(at 169.399966 -31.999936)
		(size 0.508)
		(drill 0.254)
		(layers "F.Cu" "B.Cu")
		(net "GND")
	)
	(via
		(at 178.20005 -46.399704)
		(size 0.508)
		(drill 0.254)
		(layers "F.Cu" "B.Cu")
		(net "GND")
	)
	(via
		(at 108.585 -85.725)
		(size 0.508)
		(drill 0.254)
		(layers "F.Cu" "B.Cu")
		(net "GND")
	)
	(via
		(at 130.1877 -143.602964)
		(size 0.7112)
		(drill 0.4064)
		(layers "F.Cu" "B.Cu")
		(net "GND")
	)
	(via
		(at 180.599588 -45.599604)
		(size 0.508)
		(drill 0.254)
		(layers "F.Cu" "B.Cu")
		(net "GND")
	)
	(via
		(at 109.000036 -71.000112)
		(size 0.4572)
		(drill 0.2032)
		(layers "F.Cu" "B.Cu")
		(net "GND")
	)
	(via
		(at 208.603088 -82.38236)
		(size 0.7112)
		(drill 0.4064)
		(layers "F.Cu" "B.Cu")
		(net "GND")
	)
	(via
		(at 1.397 -133.447536)
		(size 0.7112)
		(drill 0.4064)
		(layers "F.Cu" "B.Cu")
		(net "GND")
	)
	(via
		(at 185.596276 -57.016142)
		(size 0.508)
		(drill 0.254)
		(layers "F.Cu" "B.Cu")
		(net "GND")
	)
	(via
		(at 181.399688 -45.599604)
		(size 0.508)
		(drill 0.254)
		(layers "F.Cu" "B.Cu")
		(net "GND")
	)
	(via
		(at 173.399958 -43.999912)
		(size 0.508)
		(drill 0.254)
		(layers "F.Cu" "B.Cu")
		(net "GND")
	)
	(via
		(at 51.2318 -52.2478)
		(size 0.7112)
		(drill 0.4064)
		(layers "F.Cu" "B.Cu")
		(net "GND")
	)
	(via
		(at 126.399544 -132.215128)
		(size 0.7112)
		(drill 0.4064)
		(layers "F.Cu" "B.Cu")
		(net "GND")
	)
	(via
		(at 193.1924 -44.1198)
		(size 0.508)
		(drill 0.254)
		(layers "F.Cu" "B.Cu")
		(net "GND")
	)
	(via
		(at 179.799742 -39.19982)
		(size 0.508)
		(drill 0.254)
		(layers "F.Cu" "B.Cu")
		(net "GND")
	)
	(via
		(at 188.836808 -38.56101)
		(size 0.508)
		(drill 0.254)
		(layers "F.Cu" "B.Cu")
		(net "GND")
	)
	(via
		(at 182.199788 -39.999666)
		(size 0.508)
		(drill 0.254)
		(layers "F.Cu" "B.Cu")
		(net "GND")
	)
	(via
		(at 101.000052 -66.000122)
		(size 0.4572)
		(drill 0.2032)
		(layers "F.Cu" "B.Cu")
		(net "GND")
	)
	(via
		(at 104.199944 -102.700074)
		(size 0.6604)
		(drill 0.3556)
		(layers "F.Cu" "B.Cu")
		(net "GND")
	)
	(via
		(at 208.603088 -117.94236)
		(size 0.7112)
		(drill 0.4064)
		(layers "F.Cu" "B.Cu")
		(net "GND")
	)
	(via
		(at 157.102302 -108.868718)
		(size 0.7112)
		(drill 0.4064)
		(layers "F.Cu" "B.Cu")
		(net "GND")
	)
	(via
		(at 168.841674 -82.321146)
		(size 0.7112)
		(drill 0.4064)
		(layers "F.Cu" "B.Cu")
		(net "GND")
	)
	(via
		(at 160.493456 -13.169392)
		(size 0.508)
		(drill 0.254)
		(layers "F.Cu" "B.Cu")
		(net "GND")
	)
	(via
		(at 24.197564 -143.602964)
		(size 0.7112)
		(drill 0.4064)
		(layers "F.Cu" "B.Cu")
		(net "GND")
	)
	(via
		(at 180.599842 -35.999928)
		(size 0.508)
		(drill 0.254)
		(layers "F.Cu" "B.Cu")
		(net "GND")
	)
	(via
		(at 208.603088 -128.10236)
		(size 0.7112)
		(drill 0.4064)
		(layers "F.Cu" "B.Cu")
		(net "GND")
	)
	(via
		(at 129.413 -112.0648)
		(size 0.7112)
		(drill 0.4064)
		(layers "F.Cu" "B.Cu")
		(net "GND")
	)
	(via
		(at 127.999998 -56.000142)
		(size 0.4572)
		(drill 0.2032)
		(layers "F.Cu" "B.Cu")
		(net "GND")
	)
	(via
		(at 57.242456 -1.397)
		(size 0.7112)
		(drill 0.4064)
		(layers "F.Cu" "B.Cu")
		(net "GND")
	)
	(via
		(at 63.567564 -143.602964)
		(size 0.7112)
		(drill 0.4064)
		(layers "F.Cu" "B.Cu")
		(net "GND")
	)
	(via
		(at 208.603088 -84.92236)
		(size 0.7112)
		(drill 0.4064)
		(layers "F.Cu" "B.Cu")
		(net "GND")
	)
	(via
		(at 53.432456 -1.397)
		(size 0.7112)
		(drill 0.4064)
		(layers "F.Cu" "B.Cu")
		(net "GND")
	)
	(via
		(at 57.785 -39.1414)
		(size 0.7112)
		(drill 0.4064)
		(layers "F.Cu" "B.Cu")
		(net "GND")
	)
	(via
		(at 48.8696 -48.6664)
		(size 0.5588)
		(drill 0.3048)
		(layers "F.Cu" "B.Cu")
		(net "GND")
	)
	(via
		(at 102.912926 -124.603002)
		(size 0.7112)
		(drill 0.4064)
		(layers "F.Cu" "B.Cu")
		(net "GND")
	)
	(via
		(at 49.657 -36.1696)
		(size 0.508)
		(drill 0.254)
		(layers "F.Cu" "B.Cu")
		(net "GND")
	)
	(via
		(at 85.637878 -52.337208)
		(size 0.508)
		(drill 0.254)
		(layers "F.Cu" "B.Cu")
		(net "GND")
	)
	(via
		(at 52.7304 -74.2696)
		(size 0.508)
		(drill 0.254)
		(layers "F.Cu" "B.Cu")
		(net "GND")
	)
	(via
		(at 153.0477 -143.602964)
		(size 0.7112)
		(drill 0.4064)
		(layers "F.Cu" "B.Cu")
		(net "GND")
	)
	(via
		(at 177.39995 -34.399982)
		(size 0.508)
		(drill 0.254)
		(layers "F.Cu" "B.Cu")
		(net "GND")
	)
	(via
		(at 175.799496 -34.399474)
		(size 0.508)
		(drill 0.254)
		(layers "F.Cu" "B.Cu")
		(net "GND")
	)
	(via
		(at 44.6532 -33.909)
		(size 0.5588)
		(drill 0.3048)
		(layers "F.Cu" "B.Cu")
		(net "GND")
	)
	(via
		(at 21.682456 -1.397)
		(size 0.7112)
		(drill 0.4064)
		(layers "F.Cu" "B.Cu")
		(net "GND")
	)
	(via
		(at 86.000082 -2.705354)
		(size 0.6604)
		(drill 0.3556)
		(layers "F.Cu" "B.Cu")
		(net "GND")
	)
	(via
		(at 174.200058 -32.00019)
		(size 0.508)
		(drill 0.254)
		(layers "F.Cu" "B.Cu")
		(net "GND")
	)
	(via
		(at 126.399544 -139.835128)
		(size 0.7112)
		(drill 0.4064)
		(layers "F.Cu" "B.Cu")
		(net "GND")
	)
	(via
		(at 155.5877 -143.602964)
		(size 0.7112)
		(drill 0.4064)
		(layers "F.Cu" "B.Cu")
		(net "GND")
	)
	(via
		(at 132.80009 -2.705354)
		(size 0.6604)
		(drill 0.3556)
		(layers "F.Cu" "B.Cu")
		(net "GND")
	)
	(via
		(at 168.841674 -87.197946)
		(size 0.7112)
		(drill 0.4064)
		(layers "F.Cu" "B.Cu")
		(net "GND")
	)
	(via
		(at 163.6014 -28.399994)
		(size 0.508)
		(drill 0.254)
		(layers "F.Cu" "B.Cu")
		(net "GND")
	)
	(via
		(at 1.397 -106.777536)
		(size 0.7112)
		(drill 0.4064)
		(layers "F.Cu" "B.Cu")
		(net "GND")
	)
	(via
		(at 91.557094 -125.535944)
		(size 0.7112)
		(drill 0.4064)
		(layers "F.Cu" "B.Cu")
		(net "GND")
	)
	(via
		(at 96.303592 -85.644736)
		(size 0.508)
		(drill 0.254)
		(layers "F.Cu" "B.Cu")
		(net "GND")
	)
	(via
		(at 1.397 -95.347536)
		(size 0.7112)
		(drill 0.4064)
		(layers "F.Cu" "B.Cu")
		(net "GND")
	)
	(via
		(at 208.603088 -72.22236)
		(size 0.7112)
		(drill 0.4064)
		(layers "F.Cu" "B.Cu")
		(net "GND")
	)
	(via
		(at 122.00001 -63.000128)
		(size 0.4572)
		(drill 0.2032)
		(layers "F.Cu" "B.Cu")
		(net "GND")
	)
	(via
		(at 1.397 -3.907536)
		(size 0.7112)
		(drill 0.4064)
		(layers "F.Cu" "B.Cu")
		(net "GND")
	)
	(via
		(at 97.622614 -80.105758)
		(size 0.508)
		(drill 0.254)
		(layers "F.Cu" "B.Cu")
		(net "GND")
	)
	(via
		(at 41.977564 -143.602964)
		(size 0.7112)
		(drill 0.4064)
		(layers "F.Cu" "B.Cu")
		(net "GND")
	)
	(via
		(at 101.000052 -73.000108)
		(size 0.4572)
		(drill 0.2032)
		(layers "F.Cu" "B.Cu")
		(net "GND")
	)
	(via
		(at 1.397 -36.927536)
		(size 0.7112)
		(drill 0.4064)
		(layers "F.Cu" "B.Cu")
		(net "GND")
	)
	(via
		(at 111.802926 -124.603002)
		(size 0.7112)
		(drill 0.4064)
		(layers "F.Cu" "B.Cu")
		(net "GND")
	)
	(via
		(at 1.397 -2.637536)
		(size 0.7112)
		(drill 0.4064)
		(layers "F.Cu" "B.Cu")
		(net "GND")
	)
	(via
		(at 1.397 -63.597536)
		(size 0.7112)
		(drill 0.4064)
		(layers "F.Cu" "B.Cu")
		(net "GND")
	)
	(via
		(at 201.634598 -72.058784)
		(size 0.508)
		(drill 0.254)
		(layers "F.Cu" "B.Cu")
		(net "GND")
	)
	(via
		(at 86.0171 -71.4629)
		(size 0.508)
		(drill 0.254)
		(layers "F.Cu" "B.Cu")
		(net "GND")
	)
	(via
		(at 82.646012 -12.789154)
		(size 0.508)
		(drill 0.254)
		(layers "F.Cu" "B.Cu")
		(net "GND")
	)
	(via
		(at 82.214974 -65.791842)
		(size 0.508)
		(drill 0.254)
		(layers "F.Cu" "B.Cu")
		(net "GND")
	)
	(via
		(at 125.000004 -74.000106)
		(size 0.4572)
		(drill 0.2032)
		(layers "F.Cu" "B.Cu")
		(net "GND")
	)
	(via
		(at 48.8696 -47.5742)
		(size 0.5588)
		(drill 0.3048)
		(layers "F.Cu" "B.Cu")
		(net "GND")
	)
	(via
		(at 55.947564 -143.602964)
		(size 0.7112)
		(drill 0.4064)
		(layers "F.Cu" "B.Cu")
		(net "GND")
	)
	(via
		(at 89.048844 -125.93701)
		(size 0.7112)
		(drill 0.4064)
		(layers "F.Cu" "B.Cu")
		(net "GND")
	)
	(via
		(at 121.000012 -81.000092)
		(size 0.4572)
		(drill 0.2032)
		(layers "F.Cu" "B.Cu")
		(net "GND")
	)
	(via
		(at 19.9898 -80.6196)
		(size 0.508)
		(drill 0.254)
		(layers "F.Cu" "B.Cu")
		(net "GND")
	)
	(via
		(at 72.9742 -43.942)
		(size 0.7112)
		(drill 0.4064)
		(layers "F.Cu" "B.Cu")
		(net "GND")
	)
	(via
		(at 127.999998 -62.00013)
		(size 0.4572)
		(drill 0.2032)
		(layers "F.Cu" "B.Cu")
		(net "GND")
	)
	(via
		(at 125.599952 -2.705354)
		(size 0.6604)
		(drill 0.3556)
		(layers "F.Cu" "B.Cu")
		(net "GND")
	)
	(via
		(at 167.634158 -84.501228)
		(size 0.7112)
		(drill 0.4064)
		(layers "F.Cu" "B.Cu")
		(net "GND")
	)
	(via
		(at 177.39995 -29.59989)
		(size 0.508)
		(drill 0.254)
		(layers "F.Cu" "B.Cu")
		(net "GND")
	)
	(via
		(at 26.1239 -114.9731)
		(size 0.508)
		(drill 0.254)
		(layers "F.Cu" "B.Cu")
		(net "GND")
	)
	(via
		(at 208.603088 -48.09236)
		(size 0.7112)
		(drill 0.4064)
		(layers "F.Cu" "B.Cu")
		(net "GND")
	)
	(via
		(at 177.0253 -112.1156)
		(size 0.508)
		(drill 0.254)
		(layers "F.Cu" "B.Cu")
		(net "GND")
	)
	(via
		(at 104.000046 -65.000124)
		(size 0.4572)
		(drill 0.2032)
		(layers "F.Cu" "B.Cu")
		(net "GND")
	)
	(via
		(at 144.1577 -143.602964)
		(size 0.7112)
		(drill 0.4064)
		(layers "F.Cu" "B.Cu")
		(net "GND")
	)
	(via
		(at 208.603088 -134.45236)
		(size 0.7112)
		(drill 0.4064)
		(layers "F.Cu" "B.Cu")
		(net "GND")
	)
	(via
		(at 167.799766 -29.600144)
		(size 0.508)
		(drill 0.254)
		(layers "F.Cu" "B.Cu")
		(net "GND")
	)
	(via
		(at 1.397 -31.847536)
		(size 0.7112)
		(drill 0.4064)
		(layers "F.Cu" "B.Cu")
		(net "GND")
	)
	(via
		(at 93.199966 -2.705354)
		(size 0.6604)
		(drill 0.3556)
		(layers "F.Cu" "B.Cu")
		(net "GND")
	)
	(via
		(at 126.399544 -142.375128)
		(size 0.7112)
		(drill 0.4064)
		(layers "F.Cu" "B.Cu")
		(net "GND")
	)
	(via
		(at 131.318 -57.49798)
		(size 0.4572)
		(drill 0.2032)
		(layers "F.Cu" "B.Cu")
		(net "GND")
	)
	(via
		(at 167.66921 -91.840558)
		(size 0.7112)
		(drill 0.4064)
		(layers "F.Cu" "B.Cu")
		(net "GND")
	)
	(via
		(at 160.9852 -60.8584)
		(size 0.508)
		(drill 0.254)
		(layers "F.Cu" "B.Cu")
		(net "GND")
	)
	(via
		(at 106.000042 -70.000114)
		(size 0.4572)
		(drill 0.2032)
		(layers "F.Cu" "B.Cu")
		(net "GND")
	)
	(via
		(at 164.606478 -35.997134)
		(size 0.508)
		(drill 0.254)
		(layers "F.Cu" "B.Cu")
		(net "GND")
	)
	(via
		(at 175.627284 -1.66243)
		(size 0.7112)
		(drill 0.4064)
		(layers "F.Cu" "B.Cu")
		(net "GND")
	)
	(via
		(at 48.97882 -43.307)
		(size 0.7112)
		(drill 0.4064)
		(layers "F.Cu" "B.Cu")
		(net "GND")
	)
	(via
		(at 113.999772 -68.000372)
		(size 0.4572)
		(drill 0.2032)
		(layers "F.Cu" "B.Cu")
		(net "GND")
	)
	(via
		(at 1.397 -24.227536)
		(size 0.7112)
		(drill 0.4064)
		(layers "F.Cu" "B.Cu")
		(net "GND")
	)
	(via
		(at 65.352422 -101.490018)
		(size 0.5588)
		(drill 0.3048)
		(layers "F.Cu" "B.Cu")
		(net "GND")
	)
	(via
		(at 183.599836 -2.705354)
		(size 0.6604)
		(drill 0.3556)
		(layers "F.Cu" "B.Cu")
		(net "GND")
	)
	(via
		(at 1.397 -64.867536)
		(size 0.7112)
		(drill 0.4064)
		(layers "F.Cu" "B.Cu")
		(net "GND")
	)
	(via
		(at 176.59985 -43.999912)
		(size 0.508)
		(drill 0.254)
		(layers "F.Cu" "B.Cu")
		(net "GND")
	)
	(via
		(at 92.811092 -125.335284)
		(size 0.7112)
		(drill 0.4064)
		(layers "F.Cu" "B.Cu")
		(net "GND")
	)
	(via
		(at 160.9852 -62.4078)
		(size 0.508)
		(drill 0.254)
		(layers "F.Cu" "B.Cu")
		(net "GND")
	)
	(via
		(at 174.199804 -50.399696)
		(size 0.508)
		(drill 0.254)
		(layers "F.Cu" "B.Cu")
		(net "GND")
	)
	(via
		(at 153.5176 -113.6269)
		(size 0.5588)
		(drill 0.3048)
		(layers "F.Cu" "B.Cu")
		(net "GND")
	)
	(via
		(at 103.000048 -77.0001)
		(size 0.4572)
		(drill 0.2032)
		(layers "F.Cu" "B.Cu")
		(net "GND")
	)
	(via
		(at 59.817 -81.3054)
		(size 0.508)
		(drill 0.254)
		(layers "F.Cu" "B.Cu")
		(net "GND")
	)
	(via
		(at 208.603088 -11.26236)
		(size 0.7112)
		(drill 0.4064)
		(layers "F.Cu" "B.Cu")
		(net "GND")
	)
	(via
		(at 170.199812 -43.999658)
		(size 0.508)
		(drill 0.254)
		(layers "F.Cu" "B.Cu")
		(net "GND")
	)
	(via
		(at 1.397 -30.577536)
		(size 0.7112)
		(drill 0.4064)
		(layers "F.Cu" "B.Cu")
		(net "GND")
	)
	(via
		(at 202.022456 -1.397)
		(size 0.7112)
		(drill 0.4064)
		(layers "F.Cu" "B.Cu")
		(net "GND")
	)
	(via
		(at 183.520842 -56.21401)
		(size 0.508)
		(drill 0.254)
		(layers "F.Cu" "B.Cu")
		(net "GND")
	)
	(via
		(at 73.934066 -64.90716)
		(size 0.7112)
		(drill 0.4064)
		(layers "F.Cu" "B.Cu")
		(net "GND")
	)
	(via
		(at 152.767284 -1.66243)
		(size 0.7112)
		(drill 0.4064)
		(layers "F.Cu" "B.Cu")
		(net "GND")
	)
	(via
		(at 107.061 -85.725)
		(size 0.508)
		(drill 0.254)
		(layers "F.Cu" "B.Cu")
		(net "GND")
	)
	(via
		(at 181.399688 -36.79952)
		(size 0.508)
		(drill 0.254)
		(layers "F.Cu" "B.Cu")
		(net "GND")
	)
	(via
		(at 9.982454 -51.604164)
		(size 0.508)
		(drill 0.254)
		(layers "F.Cu" "B.Cu")
		(net "GND")
	)
	(via
		(at 66.266822 -101.490018)
		(size 0.5588)
		(drill 0.3048)
		(layers "F.Cu" "B.Cu")
		(net "GND")
	)
	(via
		(at 47.057564 -143.602964)
		(size 0.7112)
		(drill 0.4064)
		(layers "F.Cu" "B.Cu")
		(net "GND")
	)
	(via
		(at 56.595772 -92.660724)
		(size 0.7112)
		(drill 0.4064)
		(layers "F.Cu" "B.Cu")
		(net "GND")
	)
	(via
		(at 50.028602 -30.995366)
		(size 0.508)
		(drill 0.254)
		(layers "F.Cu" "B.Cu")
		(net "GND")
	)
	(via
		(at 45.3263 -51.6001)
		(size 0.7112)
		(drill 0.4064)
		(layers "F.Cu" "B.Cu")
		(net "GND")
	)
	(via
		(at 201.803 -34.107882)
		(size 0.508)
		(drill 0.254)
		(layers "F.Cu" "B.Cu")
		(net "GND")
	)
	(via
		(at 80.6958 -69.9516)
		(size 0.508)
		(drill 0.254)
		(layers "F.Cu" "B.Cu")
		(net "GND")
	)
	(via
		(at 168.599612 -45.599604)
		(size 0.508)
		(drill 0.254)
		(layers "F.Cu" "B.Cu")
		(net "GND")
	)
	(via
		(at 122.00001 -70.000114)
		(size 0.4572)
		(drill 0.2032)
		(layers "F.Cu" "B.Cu")
		(net "GND")
	)
	(via
		(at 205.1177 -143.602964)
		(size 0.7112)
		(drill 0.4064)
		(layers "F.Cu" "B.Cu")
		(net "GND")
	)
	(via
		(at 99.000056 -53.000148)
		(size 0.4572)
		(drill 0.2032)
		(layers "F.Cu" "B.Cu")
		(net "GND")
	)
	(via
		(at 83.605624 -138.554968)
		(size 0.7112)
		(drill 0.4064)
		(layers "F.Cu" "B.Cu")
		(net "GND")
	)
	(via
		(at 1.397 -28.037536)
		(size 0.7112)
		(drill 0.4064)
		(layers "F.Cu" "B.Cu")
		(net "GND")
	)
	(via
		(at 116.000022 -57.00014)
		(size 0.4572)
		(drill 0.2032)
		(layers "F.Cu" "B.Cu")
		(net "GND")
	)
	(via
		(at 168.599612 -34.399474)
		(size 0.508)
		(drill 0.254)
		(layers "F.Cu" "B.Cu")
		(net "GND")
	)
	(via
		(at 200.66 -57.0738)
		(size 0.508)
		(drill 0.254)
		(layers "F.Cu" "B.Cu")
		(net "GND")
	)
	(via
		(at 133.9977 -143.602964)
		(size 0.7112)
		(drill 0.4064)
		(layers "F.Cu" "B.Cu")
		(net "GND")
	)
	(via
		(at 53.0606 -113.9063)
		(size 0.7112)
		(drill 0.4064)
		(layers "F.Cu" "B.Cu")
		(net "GND")
	)
	(via
		(at 180.599842 -31.199836)
		(size 0.508)
		(drill 0.254)
		(layers "F.Cu" "B.Cu")
		(net "GND")
	)
	(via
		(at 1.397 -130.907536)
		(size 0.7112)
		(drill 0.4064)
		(layers "F.Cu" "B.Cu")
		(net "GND")
	)
	(via
		(at 57.785 -40.3606)
		(size 0.7112)
		(drill 0.4064)
		(layers "F.Cu" "B.Cu")
		(net "GND")
	)
	(via
		(at 25.467564 -143.602964)
		(size 0.7112)
		(drill 0.4064)
		(layers "F.Cu" "B.Cu")
		(net "GND")
	)
	(via
		(at 83.605624 -130.934968)
		(size 0.7112)
		(drill 0.4064)
		(layers "F.Cu" "B.Cu")
		(net "GND")
	)
	(via
		(at 139.0777 -143.602964)
		(size 0.7112)
		(drill 0.4064)
		(layers "F.Cu" "B.Cu")
		(net "GND")
	)
	(via
		(at 208.603088 -26.50236)
		(size 0.7112)
		(drill 0.4064)
		(layers "F.Cu" "B.Cu")
		(net "GND")
	)
	(via
		(at 1.397 -45.817536)
		(size 0.7112)
		(drill 0.4064)
		(layers "F.Cu" "B.Cu")
		(net "GND")
	)
	(via
		(at 114.000026 -54.000146)
		(size 0.4572)
		(drill 0.2032)
		(layers "F.Cu" "B.Cu")
		(net "GND")
	)
	(via
		(at 174.6377 -143.602964)
		(size 0.7112)
		(drill 0.4064)
		(layers "F.Cu" "B.Cu")
		(net "GND")
	)
	(via
		(at 169.5577 -143.602964)
		(size 0.7112)
		(drill 0.4064)
		(layers "F.Cu" "B.Cu")
		(net "GND")
	)
	(via
		(at 6.6294 -96.101408)
		(size 0.508)
		(drill 0.254)
		(layers "F.Cu" "B.Cu")
		(net "GND")
	)
	(via
		(at 72.482456 -1.397)
		(size 0.7112)
		(drill 0.4064)
		(layers "F.Cu" "B.Cu")
		(net "GND")
	)
	(via
		(at 183.799988 -31.199836)
		(size 0.508)
		(drill 0.254)
		(layers "F.Cu" "B.Cu")
		(net "GND")
	)
	(via
		(at 118.000018 -76.000356)
		(size 0.4572)
		(drill 0.2032)
		(layers "F.Cu" "B.Cu")
		(net "GND")
	)
	(via
		(at 1.397 -134.717536)
		(size 0.7112)
		(drill 0.4064)
		(layers "F.Cu" "B.Cu")
		(net "GND")
	)
	(via
		(at 106.000042 -78.000098)
		(size 0.4572)
		(drill 0.2032)
		(layers "F.Cu" "B.Cu")
		(net "GND")
	)
	(via
		(at 127.999998 -73.000108)
		(size 0.4572)
		(drill 0.2032)
		(layers "F.Cu" "B.Cu")
		(net "GND")
	)
	(via
		(at 140.3477 -143.602964)
		(size 0.7112)
		(drill 0.4064)
		(layers "F.Cu" "B.Cu")
		(net "GND")
	)
	(via
		(at 172.0977 -143.602964)
		(size 0.7112)
		(drill 0.4064)
		(layers "F.Cu" "B.Cu")
		(net "GND")
	)
	(via
		(at 78.832456 -1.397)
		(size 0.7112)
		(drill 0.4064)
		(layers "F.Cu" "B.Cu")
		(net "GND")
	)
	(via
		(at 187.2996 -87.7824)
		(size 0.7112)
		(drill 0.4064)
		(layers "F.Cu" "B.Cu")
		(net "GND")
	)
	(via
		(at 7.098538 -84.852764)
		(size 0.508)
		(drill 0.254)
		(layers "F.Cu" "B.Cu")
		(net "GND")
	)
	(via
		(at 167.634158 -83.282028)
		(size 0.7112)
		(drill 0.4064)
		(layers "F.Cu" "B.Cu")
		(net "GND")
	)
	(via
		(at 112.00003 -61.000132)
		(size 0.4572)
		(drill 0.2032)
		(layers "F.Cu" "B.Cu")
		(net "GND")
	)
	(via
		(at 1.397 -19.147536)
		(size 0.7112)
		(drill 0.4064)
		(layers "F.Cu" "B.Cu")
		(net "GND")
	)
	(via
		(at 83.605624 -134.744968)
		(size 0.7112)
		(drill 0.4064)
		(layers "F.Cu" "B.Cu")
		(net "GND")
	)
	(via
		(at 83.278472 -73.69175)
		(size 0.508)
		(drill 0.254)
		(layers "F.Cu" "B.Cu")
		(net "GND")
	)
	(via
		(at 118.000018 -66.000122)
		(size 0.4572)
		(drill 0.2032)
		(layers "F.Cu" "B.Cu")
		(net "GND")
	)
	(via
		(at 48.7426 -49.8094)
		(size 0.7112)
		(drill 0.4064)
		(layers "F.Cu" "B.Cu")
		(net "GND")
	)
	(via
		(at 51.562 -114.6302)
		(size 0.7112)
		(drill 0.4064)
		(layers "F.Cu" "B.Cu")
		(net "GND")
	)
	(via
		(at 126.399544 -137.295128)
		(size 0.7112)
		(drill 0.4064)
		(layers "F.Cu" "B.Cu")
		(net "GND")
	)
	(via
		(at 1.397 -102.967536)
		(size 0.7112)
		(drill 0.4064)
		(layers "F.Cu" "B.Cu")
		(net "GND")
	)
	(via
		(at 1.397 -80.107536)
		(size 0.7112)
		(drill 0.4064)
		(layers "F.Cu" "B.Cu")
		(net "GND")
	)
	(via
		(at 58.487564 -143.602964)
		(size 0.7112)
		(drill 0.4064)
		(layers "F.Cu" "B.Cu")
		(net "GND")
	)
	(via
		(at 170.20032 -37.59962)
		(size 0.508)
		(drill 0.254)
		(layers "F.Cu" "B.Cu")
		(net "GND")
	)
	(via
		(at 57.669684 -58.407808)
		(size 0.7112)
		(drill 0.4064)
		(layers "F.Cu" "B.Cu")
		(net "GND")
	)
	(via
		(at 200.0377 -143.602964)
		(size 0.7112)
		(drill 0.4064)
		(layers "F.Cu" "B.Cu")
		(net "GND")
	)
	(via
		(at 181.399688 -43.999658)
		(size 0.508)
		(drill 0.254)
		(layers "F.Cu" "B.Cu")
		(net "GND")
	)
	(via
		(at 82.646012 -8.979154)
		(size 0.508)
		(drill 0.254)
		(layers "F.Cu" "B.Cu")
		(net "GND")
	)
	(via
		(at 168.599612 -44.799758)
		(size 0.508)
		(drill 0.254)
		(layers "F.Cu" "B.Cu")
		(net "GND")
	)
	(via
		(at 128.9177 -143.602964)
		(size 0.7112)
		(drill 0.4064)
		(layers "F.Cu" "B.Cu")
		(net "GND")
	)
	(via
		(at 74.9554 -33.1216)
		(size 0.7112)
		(drill 0.4064)
		(layers "F.Cu" "B.Cu")
		(net "GND")
	)
	(via
		(at 154.559 -80.01)
		(size 0.508)
		(drill 0.254)
		(layers "F.Cu" "B.Cu")
		(net "GND")
	)
	(via
		(at 173.399704 -47.199804)
		(size 0.508)
		(drill 0.254)
		(layers "F.Cu" "B.Cu")
		(net "GND")
	)
	(via
		(at 5.6515 -56.769)
		(size 0.508)
		(drill 0.254)
		(layers "F.Cu" "B.Cu")
		(net "GND")
	)
	(via
		(at 174.999904 -42.399966)
		(size 0.508)
		(drill 0.254)
		(layers "F.Cu" "B.Cu")
		(net "GND")
	)
	(via
		(at 131.318 -59.500008)
		(size 0.4572)
		(drill 0.2032)
		(layers "F.Cu" "B.Cu")
		(net "GND")
	)
	(via
		(at 1.397 -53.437536)
		(size 0.7112)
		(drill 0.4064)
		(layers "F.Cu" "B.Cu")
		(net "GND")
	)
	(via
		(at 65.05448 -100.37318)
		(size 0.5588)
		(drill 0.3048)
		(layers "F.Cu" "B.Cu")
		(net "GND")
	)
	(via
		(at 107.00004 -51.000152)
		(size 0.4572)
		(drill 0.2032)
		(layers "F.Cu" "B.Cu")
		(net "GND")
	)
	(via
		(at 90.302842 -125.73635)
		(size 0.7112)
		(drill 0.4064)
		(layers "F.Cu" "B.Cu")
		(net "GND")
	)
	(via
		(at 127.999998 -60.000134)
		(size 0.4572)
		(drill 0.2032)
		(layers "F.Cu" "B.Cu")
		(net "GND")
	)
	(via
		(at 208.603088 -12.53236)
		(size 0.7112)
		(drill 0.4064)
		(layers "F.Cu" "B.Cu")
		(net "GND")
	)
	(via
		(at 141.6177 -143.602964)
		(size 0.7112)
		(drill 0.4064)
		(layers "F.Cu" "B.Cu")
		(net "GND")
	)
	(via
		(at 111.012478 -70.971156)
		(size 0.4572)
		(drill 0.2032)
		(layers "F.Cu" "B.Cu")
		(net "GND")
	)
	(via
		(at 8.957564 -143.602964)
		(size 0.7112)
		(drill 0.4064)
		(layers "F.Cu" "B.Cu")
		(net "GND")
	)
	(via
		(at 37.0586 -34.671)
		(size 0.508)
		(drill 0.254)
		(layers "F.Cu" "B.Cu")
		(net "GND")
	)
	(via
		(at 159.3977 -143.602964)
		(size 0.7112)
		(drill 0.4064)
		(layers "F.Cu" "B.Cu")
		(net "GND")
	)
	(via
		(at 160.7185 -84.9122)
		(size 0.508)
		(drill 0.254)
		(layers "F.Cu" "B.Cu")
		(net "GND")
	)
	(via
		(at 198.212456 -1.397)
		(size 0.7112)
		(drill 0.4064)
		(layers "F.Cu" "B.Cu")
		(net "GND")
	)
	(via
		(at 81.347564 -143.602964)
		(size 0.7112)
		(drill 0.4064)
		(layers "F.Cu" "B.Cu")
		(net "GND")
	)
	(via
		(at 1.397 -16.607536)
		(size 0.7112)
		(drill 0.4064)
		(layers "F.Cu" "B.Cu")
		(net "GND")
	)
	(via
		(at 20.574 -74.0918)
		(size 0.508)
		(drill 0.254)
		(layers "F.Cu" "B.Cu")
		(net "GND")
	)
	(via
		(at 208.603088 -142.07236)
		(size 0.7112)
		(drill 0.4064)
		(layers "F.Cu" "B.Cu")
		(net "GND")
	)
	(via
		(at 167.66921 -89.402158)
		(size 0.7112)
		(drill 0.4064)
		(layers "F.Cu" "B.Cu")
		(net "GND")
	)
	(via
		(at 83.605624 -142.364968)
		(size 0.7112)
		(drill 0.4064)
		(layers "F.Cu" "B.Cu")
		(net "GND")
	)
	(via
		(at 175.1838 -117.3099)
		(size 0.5588)
		(drill 0.3048)
		(layers "F.Cu" "B.Cu")
		(net "GND")
	)
	(via
		(at 50.0126 -45.3898)
		(size 0.5588)
		(drill 0.3048)
		(layers "F.Cu" "B.Cu")
		(net "GND")
	)
	(via
		(at 93.4847 -85.6488)
		(size 0.508)
		(drill 0.254)
		(layers "F.Cu" "B.Cu")
		(net "GND")
	)
	(via
		(at 111.999776 -68.000372)
		(size 0.4572)
		(drill 0.2032)
		(layers "F.Cu" "B.Cu")
		(net "GND")
	)
	(via
		(at 109.000036 -69.000116)
		(size 0.4572)
		(drill 0.2032)
		(layers "F.Cu" "B.Cu")
		(net "GND")
	)
	(via
		(at 118.000018 -57.00014)
		(size 0.4572)
		(drill 0.2032)
		(layers "F.Cu" "B.Cu")
		(net "GND")
	)
	(via
		(at 208.603088 -97.62236)
		(size 0.7112)
		(drill 0.4064)
		(layers "F.Cu" "B.Cu")
		(net "GND")
	)
	(via
		(at 181.399688 -39.999666)
		(size 0.508)
		(drill 0.254)
		(layers "F.Cu" "B.Cu")
		(net "GND")
	)
	(via
		(at 177.39995 -48.79975)
		(size 0.508)
		(drill 0.254)
		(layers "F.Cu" "B.Cu")
		(net "GND")
	)
	(via
		(at 57.8104 -56.8452)
		(size 0.7112)
		(drill 0.4064)
		(layers "F.Cu" "B.Cu")
		(net "GND")
	)
	(via
		(at 208.603088 -74.76236)
		(size 0.7112)
		(drill 0.4064)
		(layers "F.Cu" "B.Cu")
		(net "GND")
	)
	(via
		(at 124.000006 -69.000116)
		(size 0.4572)
		(drill 0.2032)
		(layers "F.Cu" "B.Cu")
		(net "GND")
	)
	(via
		(at 168.599612 -43.199812)
		(size 0.508)
		(drill 0.254)
		(layers "F.Cu" "B.Cu")
		(net "GND")
	)
	(via
		(at 33.087564 -143.602964)
		(size 0.7112)
		(drill 0.4064)
		(layers "F.Cu" "B.Cu")
		(net "GND")
	)
	(via
		(at 174.357284 -1.66243)
		(size 0.7112)
		(drill 0.4064)
		(layers "F.Cu" "B.Cu")
		(net "GND")
	)
	(via
		(at 134.046468 -108.072174)
		(size 0.7112)
		(drill 0.4064)
		(layers "F.Cu" "B.Cu")
		(net "GND")
	)
	(via
		(at 185.112152 -22.48916)
		(size 0.508)
		(drill 0.254)
		(layers "F.Cu" "B.Cu")
		(net "GND")
	)
	(via
		(at 51.2318 -49.8094)
		(size 0.7112)
		(drill 0.4064)
		(layers "F.Cu" "B.Cu")
		(net "GND")
	)
	(via
		(at 10.227564 -143.602964)
		(size 0.7112)
		(drill 0.4064)
		(layers "F.Cu" "B.Cu")
		(net "GND")
	)
	(via
		(at 175.800004 -47.200058)
		(size 0.508)
		(drill 0.254)
		(layers "F.Cu" "B.Cu")
		(net "GND")
	)
	(via
		(at 166.99992 -38.409626)
		(size 0.508)
		(drill 0.254)
		(layers "F.Cu" "B.Cu")
		(net "GND")
	)
	(via
		(at 1.397 -20.417536)
		(size 0.7112)
		(drill 0.4064)
		(layers "F.Cu" "B.Cu")
		(net "GND")
	)
	(via
		(at 105.000044 -57.00014)
		(size 0.4572)
		(drill 0.2032)
		(layers "F.Cu" "B.Cu")
		(net "GND")
	)
	(via
		(at 117.983 -88.24214)
		(size 0.508)
		(drill 0.254)
		(layers "F.Cu" "B.Cu")
		(net "GND")
	)
	(via
		(at 176.59985 -39.19982)
		(size 0.508)
		(drill 0.254)
		(layers "F.Cu" "B.Cu")
		(net "GND")
	)
	(via
		(at 38.481 -52.07)
		(size 0.7112)
		(drill 0.4064)
		(layers "F.Cu" "B.Cu")
		(net "GND")
	)
	(via
		(at 184.59958 -45.600112)
		(size 0.508)
		(drill 0.254)
		(layers "F.Cu" "B.Cu")
		(net "GND")
	)
	(via
		(at 186.0804 -86.5632)
		(size 0.7112)
		(drill 0.4064)
		(layers "F.Cu" "B.Cu")
		(net "GND")
	)
	(via
		(at 155.307284 -1.66243)
		(size 0.7112)
		(drill 0.4064)
		(layers "F.Cu" "B.Cu")
		(net "GND")
	)
	(via
		(at 1.397 -100.427536)
		(size 0.7112)
		(drill 0.4064)
		(layers "F.Cu" "B.Cu")
		(net "GND")
	)
	(via
		(at 174.199804 -51.199796)
		(size 0.508)
		(drill 0.254)
		(layers "F.Cu" "B.Cu")
		(net "GND")
	)
	(via
		(at 103.000048 -66.000122)
		(size 0.4572)
		(drill 0.2032)
		(layers "F.Cu" "B.Cu")
		(net "GND")
	)
	(via
		(at 1.397 -76.297536)
		(size 0.7112)
		(drill 0.4064)
		(layers "F.Cu" "B.Cu")
		(net "GND")
	)
	(via
		(at 68.672456 -1.397)
		(size 0.7112)
		(drill 0.4064)
		(layers "F.Cu" "B.Cu")
		(net "GND")
	)
	(via
		(at 208.603088 -136.99236)
		(size 0.7112)
		(drill 0.4064)
		(layers "F.Cu" "B.Cu")
		(net "GND")
	)
	(via
		(at 168.841674 -84.759546)
		(size 0.7112)
		(drill 0.4064)
		(layers "F.Cu" "B.Cu")
		(net "GND")
	)
	(via
		(at 51.41722 -40.8686)
		(size 0.7112)
		(drill 0.4064)
		(layers "F.Cu" "B.Cu")
		(net "GND")
	)
	(via
		(at 178.199796 -40.799766)
		(size 0.508)
		(drill 0.254)
		(layers "F.Cu" "B.Cu")
		(net "GND")
	)
	(via
		(at 125.000004 -77.0001)
		(size 0.4572)
		(drill 0.2032)
		(layers "F.Cu" "B.Cu")
		(net "GND")
	)
	(via
		(at 162.927284 -1.66243)
		(size 0.7112)
		(drill 0.4064)
		(layers "F.Cu" "B.Cu")
		(net "GND")
	)
	(via
		(at 194.9577 -143.602964)
		(size 0.7112)
		(drill 0.4064)
		(layers "F.Cu" "B.Cu")
		(net "GND")
	)
	(via
		(at 57.73166 -59.784742)
		(size 0.7112)
		(drill 0.4064)
		(layers "F.Cu" "B.Cu")
		(net "GND")
	)
	(via
		(at 1.397 -42.007536)
		(size 0.7112)
		(drill 0.4064)
		(layers "F.Cu" "B.Cu")
		(net "GND")
	)
	(via
		(at 113.000028 -71.000366)
		(size 0.4572)
		(drill 0.2032)
		(layers "F.Cu" "B.Cu")
		(net "GND")
	)
	(via
		(at 123.000008 -54.000146)
		(size 0.4572)
		(drill 0.2032)
		(layers "F.Cu" "B.Cu")
		(net "GND")
	)
	(via
		(at 74.7395 -82.55)
		(size 0.508)
		(drill 0.254)
		(layers "F.Cu" "B.Cu")
		(net "GND")
	)
	(via
		(at 127.999998 -52.00015)
		(size 0.4572)
		(drill 0.2032)
		(layers "F.Cu" "B.Cu")
		(net "GND")
	)
	(via
		(at 150.5077 -143.602964)
		(size 0.7112)
		(drill 0.4064)
		(layers "F.Cu" "B.Cu")
		(net "GND")
	)
	(via
		(at 179.799742 -37.599874)
		(size 0.508)
		(drill 0.254)
		(layers "F.Cu" "B.Cu")
		(net "GND")
	)
	(via
		(at 164.600128 -34.400236)
		(size 0.508)
		(drill 0.254)
		(layers "F.Cu" "B.Cu")
		(net "GND")
	)
	(via
		(at 159.9946 -64.008)
		(size 0.508)
		(drill 0.254)
		(layers "F.Cu" "B.Cu")
		(net "GND")
	)
	(via
		(at 113.999772 -66.000122)
		(size 0.4572)
		(drill 0.2032)
		(layers "F.Cu" "B.Cu")
		(net "GND")
	)
	(via
		(at 1.397 -128.367536)
		(size 0.7112)
		(drill 0.4064)
		(layers "F.Cu" "B.Cu")
		(net "GND")
	)
	(via
		(at 106.000042 -83.000088)
		(size 0.4572)
		(drill 0.2032)
		(layers "F.Cu" "B.Cu")
		(net "GND")
	)
	(via
		(at 106.000042 -57.00014)
		(size 0.4572)
		(drill 0.2032)
		(layers "F.Cu" "B.Cu")
		(net "GND")
	)
	(via
		(at 117.00002 -54.000146)
		(size 0.4572)
		(drill 0.2032)
		(layers "F.Cu" "B.Cu")
		(net "GND")
	)
	(via
		(at 208.603088 -34.12236)
		(size 0.7112)
		(drill 0.4064)
		(layers "F.Cu" "B.Cu")
		(net "GND")
	)
	(via
		(at 1.397 -122.017536)
		(size 0.7112)
		(drill 0.4064)
		(layers "F.Cu" "B.Cu")
		(net "GND")
	)
	(via
		(at 1.397 -22.957536)
		(size 0.7112)
		(drill 0.4064)
		(layers "F.Cu" "B.Cu")
		(net "GND")
	)
	(via
		(at 166.497 -91.44)
		(size 0.7112)
		(drill 0.4064)
		(layers "F.Cu" "B.Cu")
		(net "GND")
	)
	(via
		(at 197.4977 -143.602964)
		(size 0.7112)
		(drill 0.4064)
		(layers "F.Cu" "B.Cu")
		(net "GND")
	)
	(via
		(at 168.2877 -143.602964)
		(size 0.7112)
		(drill 0.4064)
		(layers "F.Cu" "B.Cu")
		(net "GND")
	)
	(via
		(at 174.19955 -35.199574)
		(size 0.508)
		(drill 0.254)
		(layers "F.Cu" "B.Cu")
		(net "GND")
	)
	(via
		(at 166.737284 -1.66243)
		(size 0.7112)
		(drill 0.4064)
		(layers "F.Cu" "B.Cu")
		(net "GND")
	)
	(via
		(at 152.0444 -62.9412)
		(size 0.508)
		(drill 0.254)
		(layers "F.Cu" "B.Cu")
		(net "GND")
	)
	(via
		(at 82.617564 -143.602964)
		(size 0.7112)
		(drill 0.4064)
		(layers "F.Cu" "B.Cu")
		(net "GND")
	)
	(via
		(at 51.880008 -119.430292)
		(size 0.7112)
		(drill 0.4064)
		(layers "F.Cu" "B.Cu")
		(net "GND")
	)
	(via
		(at 128.397 -117.9576)
		(size 0.7112)
		(drill 0.4064)
		(layers "F.Cu" "B.Cu")
		(net "GND")
	)
	(via
		(at 176.59985 -40.799766)
		(size 0.508)
		(drill 0.254)
		(layers "F.Cu" "B.Cu")
		(net "GND")
	)
	(via
		(at 59.782456 -1.397)
		(size 0.7112)
		(drill 0.4064)
		(layers "F.Cu" "B.Cu")
		(net "GND")
	)
	(via
		(at 83.605624 -137.284968)
		(size 0.7112)
		(drill 0.4064)
		(layers "F.Cu" "B.Cu")
		(net "GND")
	)
	(via
		(at 101.000052 -54.000146)
		(size 0.4572)
		(drill 0.2032)
		(layers "F.Cu" "B.Cu")
		(net "GND")
	)
	(via
		(at 184.212738 -116.579396)
		(size 0.7112)
		(drill 0.4064)
		(layers "F.Cu" "B.Cu")
		(net "GND")
	)
	(via
		(at 57.8104 -51.9684)
		(size 0.7112)
		(drill 0.4064)
		(layers "F.Cu" "B.Cu")
		(net "GND")
	)
	(via
		(at 168.841674 -85.978746)
		(size 0.7112)
		(drill 0.4064)
		(layers "F.Cu" "B.Cu")
		(net "GND")
	)
	(via
		(at 147.5486 -105.3592)
		(size 0.7112)
		(drill 0.4064)
		(layers "F.Cu" "B.Cu")
		(net "GND")
	)
	(via
		(at 193.22161 -54.4068)
		(size 0.508)
		(drill 0.254)
		(layers "F.Cu" "B.Cu")
		(net "GND")
	)
	(via
		(at 110.000034 -63.000128)
		(size 0.4572)
		(drill 0.2032)
		(layers "F.Cu" "B.Cu")
		(net "GND")
	)
	(via
		(at 101.000052 -81.000092)
		(size 0.4572)
		(drill 0.2032)
		(layers "F.Cu" "B.Cu")
		(net "GND")
	)
	(via
		(at 1.397 -58.517536)
		(size 0.7112)
		(drill 0.4064)
		(layers "F.Cu" "B.Cu")
		(net "GND")
	)
	(via
		(at 1.397 -97.887536)
		(size 0.7112)
		(drill 0.4064)
		(layers "F.Cu" "B.Cu")
		(net "GND")
	)
	(via
		(at 183.5277 -143.602964)
		(size 0.7112)
		(drill 0.4064)
		(layers "F.Cu" "B.Cu")
		(net "GND")
	)
	(via
		(at 208.603088 -23.96236)
		(size 0.7112)
		(drill 0.4064)
		(layers "F.Cu" "B.Cu")
		(net "GND")
	)
	(via
		(at 122.00001 -51.000152)
		(size 0.4572)
		(drill 0.2032)
		(layers "F.Cu" "B.Cu")
		(net "GND")
	)
	(via
		(at 108.000038 -65.000124)
		(size 0.4572)
		(drill 0.2032)
		(layers "F.Cu" "B.Cu")
		(net "GND")
	)
	(via
		(at 170.209464 -33.599882)
		(size 0.508)
		(drill 0.254)
		(layers "F.Cu" "B.Cu")
		(net "GND")
	)
	(via
		(at 110.000034 -70.000114)
		(size 0.4572)
		(drill 0.2032)
		(layers "F.Cu" "B.Cu")
		(net "GND")
	)
	(via
		(at 1.397 -33.117536)
		(size 0.7112)
		(drill 0.4064)
		(layers "F.Cu" "B.Cu")
		(net "GND")
	)
	(via
		(at 1.397 -59.787536)
		(size 0.7112)
		(drill 0.4064)
		(layers "F.Cu" "B.Cu")
		(net "GND")
	)
	(via
		(at 186.199526 -42.40022)
		(size 0.508)
		(drill 0.254)
		(layers "F.Cu" "B.Cu")
		(net "GND")
	)
	(via
		(at 154.7876 -113.4999)
		(size 0.5588)
		(drill 0.3048)
		(layers "F.Cu" "B.Cu")
		(net "GND")
	)
	(via
		(at 153.5176 -118.0719)
		(size 0.5588)
		(drill 0.3048)
		(layers "F.Cu" "B.Cu")
		(net "GND")
	)
	(via
		(at 29.277564 -143.602964)
		(size 0.7112)
		(drill 0.4064)
		(layers "F.Cu" "B.Cu")
		(net "GND")
	)
	(via
		(at 65.28308 -99.23018)
		(size 0.5588)
		(drill 0.3048)
		(layers "F.Cu" "B.Cu")
		(net "GND")
	)
	(via
		(at 1.397 -73.757536)
		(size 0.7112)
		(drill 0.4064)
		(layers "F.Cu" "B.Cu")
		(net "GND")
	)
	(via
		(at 106.000042 -68.000118)
		(size 0.4572)
		(drill 0.2032)
		(layers "F.Cu" "B.Cu")
		(net "GND")
	)
	(via
		(at 208.603088 -98.89236)
		(size 0.7112)
		(drill 0.4064)
		(layers "F.Cu" "B.Cu")
		(net "GND")
	)
	(via
		(at 130.999992 -68.000118)
		(size 0.4572)
		(drill 0.2032)
		(layers "F.Cu" "B.Cu")
		(net "GND")
	)
	(via
		(at 123.2154 -93.1672)
		(size 0.508)
		(drill 0.254)
		(layers "F.Cu" "B.Cu")
		(net "GND")
	)
	(via
		(at 1.397 -7.717536)
		(size 0.7112)
		(drill 0.4064)
		(layers "F.Cu" "B.Cu")
		(net "GND")
	)
	(via
		(at 101.642926 -124.603002)
		(size 0.7112)
		(drill 0.4064)
		(layers "F.Cu" "B.Cu")
		(net "GND")
	)
	(via
		(at 126.399544 -141.105128)
		(size 0.7112)
		(drill 0.4064)
		(layers "F.Cu" "B.Cu")
		(net "GND")
	)
	(via
		(at 1.397 -52.167536)
		(size 0.7112)
		(drill 0.4064)
		(layers "F.Cu" "B.Cu")
		(net "GND")
	)
	(via
		(at 66.107564 -143.602964)
		(size 0.7112)
		(drill 0.4064)
		(layers "F.Cu" "B.Cu")
		(net "GND")
	)
	(via
		(at 154.7876 -118.0719)
		(size 0.5588)
		(drill 0.3048)
		(layers "F.Cu" "B.Cu")
		(net "GND")
	)
	(via
		(at 135.2677 -143.602964)
		(size 0.7112)
		(drill 0.4064)
		(layers "F.Cu" "B.Cu")
		(net "GND")
	)
	(via
		(at 110.000034 -79.000096)
		(size 0.4572)
		(drill 0.2032)
		(layers "F.Cu" "B.Cu")
		(net "GND")
	)
	(via
		(at 130.999992 -81.000092)
		(size 0.4572)
		(drill 0.2032)
		(layers "F.Cu" "B.Cu")
		(net "GND")
	)
	(via
		(at 1.397 -108.047536)
		(size 0.7112)
		(drill 0.4064)
		(layers "F.Cu" "B.Cu")
		(net "GND")
	)
	(via
		(at 104.199944 -106.499914)
		(size 0.6604)
		(drill 0.3556)
		(layers "F.Cu" "B.Cu")
		(net "GND")
	)
	(via
		(at 3.902456 -1.397)
		(size 0.7112)
		(drill 0.4064)
		(layers "F.Cu" "B.Cu")
		(net "GND")
	)
	(via
		(at 50.867564 -143.602964)
		(size 0.7112)
		(drill 0.4064)
		(layers "F.Cu" "B.Cu")
		(net "GND")
	)
	(via
		(at 1.397 -40.737536)
		(size 0.7112)
		(drill 0.4064)
		(layers "F.Cu" "B.Cu")
		(net "GND")
	)
	(via
		(at 55.499 -81.3308)
		(size 0.508)
		(drill 0.254)
		(layers "F.Cu" "B.Cu")
		(net "GND")
	)
	(via
		(at 188.5188 -87.7824)
		(size 0.7112)
		(drill 0.4064)
		(layers "F.Cu" "B.Cu")
		(net "GND")
	)
	(via
		(at 208.603088 -133.18236)
		(size 0.7112)
		(drill 0.4064)
		(layers "F.Cu" "B.Cu")
		(net "GND")
	)
	(segment
		(start 106.0196 -64.980566)
		(end 106.000042 -65.000124)
		(width 0.254)
		(layer "B.Cu")
		(net "GND")
	)
	(segment
		(start 116.798598 -80.79867)
		(end 117.00002 -81.000092)
		(width 0.3048)
		(layer "B.Cu")
		(net "GND")
	)
	(segment
		(start 124.0028 -65.5066)
		(end 124.000006 -65.509394)
		(width 0.254)
		(layer "B.Cu")
		(net "GND")
	)
	(segment
		(start 106.5022 -66.525648)
		(end 106.5022 -66.0654)
		(width 0.254)
		(layer "B.Cu")
		(net "GND")
	)
	(segment
		(start 90.1192 -81.84134)
		(end 90.1192 -81.2546)
		(width 0.508)
		(layer "B.Cu")
		(net "GND")
	)
	(segment
		(start 184.744868 -47.345346)
		(end 184.59958 -47.200058)
		(width 0.3048)
		(layer "B.Cu")
		(net "GND")
	)
	(segment
		(start 200.66 -57.0738)
		(end 201.8538 -57.0738)
		(width 0.508)
		(layer "B.Cu")
		(net "GND")
	)
	(segment
		(start 125.000004 -70.000114)
		(end 125.000004 -69.513704)
		(width 0.254)
		(layer "B.Cu")
		(net "GND")
	)
	(segment
		(start 196.117464 -21.093684)
		(end 196.115178 -21.093684)
		(width 0.508)
		(layer "B.Cu")
		(net "GND")
	)
	(segment
		(start 119.888 -90.91295)
		(end 118.814596 -91.986354)
		(width 0.508)
		(layer "B.Cu")
		(net "GND")
	)
	(segment
		(start 125.998986 -51.716178)
		(end 125.283976 -51.716178)
		(width 0.3048)
		(layer "B.Cu")
		(net "GND")
	)
	(segment
		(start 180.7718 -31.027878)
		(end 180.7718 -30.353)
		(width 0.3048)
		(layer "B.Cu")
		(net "GND")
	)
	(segment
		(start 114.5794 -80.7466)
		(end 114.253518 -80.7466)
		(width 0.3048)
		(layer "B.Cu")
		(net "GND")
	)
	(segment
		(start 124.00026 -68.999862)
		(end 124.000006 -69.000116)
		(width 0.254)
		(layer "B.Cu")
		(net "GND")
	)
	(segment
		(start 184.744868 -44.145454)
		(end 184.59958 -44.000166)
		(width 0.3048)
		(layer "B.Cu")
		(net "GND")
	)
	(segment
		(start 125.000004 -69.513704)
		(end 124.9934 -69.5071)
		(width 0.254)
		(layer "B.Cu")
		(net "GND")
	)
	(segment
		(start 123.9647 -71.035418)
		(end 124.000006 -71.000112)
		(width 0.254)
		(layer "B.Cu")
		(net "GND")
	)
	(segment
		(start 167.8051 -32.6771)
		(end 167.8051 -32.005016)
		(width 0.3048)
		(layer "B.Cu")
		(net "GND")
	)
	(segment
		(start 107.517438 -66.0654)
		(end 107.93476 -66.0654)
		(width 0.254)
		(layer "B.Cu")
		(net "GND")
	)
	(segment
		(start 177.60823 -29.39161)
		(end 177.39995 -29.59989)
		(width 0.3048)
		(layer "B.Cu")
		(net "GND")
	)
	(segment
		(start 123.987814 -73.0123)
		(end 123.5075 -73.0123)
		(width 0.3048)
		(layer "B.Cu")
		(net "GND")
	)
	(segment
		(start 128.520444 -73.517252)
		(end 128.253998 -73.517252)
		(width 0.3048)
		(layer "B.Cu")
		(net "GND")
	)
	(segment
		(start 124.82703 -89.794588)
		(end 124.483876 -90.137742)
		(width 0.508)
		(layer "B.Cu")
		(net "GND")
	)
	(segment
		(start 122.584972 -88.002872)
		(end 122.265186 -88.322658)
		(width 0.508)
		(layer "B.Cu")
		(net "GND")
	)
	(segment
		(start 127.691388 -54.502304)
		(end 127.691388 -54.308756)
		(width 0.3048)
		(layer "B.Cu")
		(net "GND")
	)
	(segment
		(start 184.434988 -31.834836)
		(end 183.799988 -31.199836)
		(width 0.3048)
		(layer "B.Cu")
		(net "GND")
	)
	(segment
		(start 166.84625 -43.523408)
		(end 166.523416 -43.523408)
		(width 0.3048)
		(layer "B.Cu")
		(net "GND")
	)
	(segment
		(start 104.504744 -61.9506)
		(end 104.049576 -61.9506)
		(width 0.254)
		(layer "B.Cu")
		(net "GND")
	)
	(segment
		(start 119.92483 -75.075288)
		(end 120.000014 -75.000104)
		(width 0.508)
		(layer "B.Cu")
		(net "GND")
	)
	(segment
		(start 108.2548 -64.745362)
		(end 108.000038 -65.000124)
		(width 0.254)
		(layer "B.Cu")
		(net "GND")
	)
	(segment
		(start 177.8508 -31.650686)
		(end 177.400204 -31.20009)
		(width 0.3048)
		(layer "B.Cu")
		(net "GND")
	)
	(segment
		(start 171.51985 -42.91965)
		(end 171.000166 -42.399966)
		(width 0.3556)
		(layer "B.Cu")
		(net "GND")
	)
	(segment
		(start 130.2258 -81.1784)
		(end 130.821684 -81.1784)
		(width 0.3048)
		(layer "B.Cu")
		(net "GND")
	)
	(segment
		(start 184.744868 -43.19651)
		(end 184.744868 -42.545508)
		(width 0.3556)
		(layer "B.Cu")
		(net "GND")
	)
	(segment
		(start 201.803 -34.8869)
		(end 202.819 -34.8869)
		(width 0.508)
		(layer "B.Cu")
		(net "GND")
	)
	(segment
		(start 127.5588 -92.470986)
		(end 127.5588 -92.837)
		(width 0.508)
		(layer "B.Cu")
		(net "GND")
	)
	(segment
		(start 104.013 -83.013042)
		(end 104.000046 -83.000088)
		(width 0.508)
		(layer "B.Cu")
		(net "GND")
	)
	(segment
		(start 116.5098 -76.7461)
		(end 116.2558 -77.0001)
		(width 0.254)
		(layer "B.Cu")
		(net "GND")
	)
	(segment
		(start 123.0376 -93.345)
		(end 123.2154 -93.1672)
		(width 0.508)
		(layer "B.Cu")
		(net "GND")
	)
	(segment
		(start 169.95775 -69.7865)
		(end 169.95775 -71.22287)
		(width 0.508)
		(layer "B.Cu")
		(net "GND")
	)
	(segment
		(start 170.763438 -32.236918)
		(end 171.000166 -32.00019)
		(width 0.3048)
		(layer "B.Cu")
		(net "GND")
	)
	(segment
		(start 124.46 -90.161618)
		(end 124.46 -92.3798)
		(width 0.508)
		(layer "B.Cu")
		(net "GND")
	)
	(segment
		(start 120.266714 -76.7334)
		(end 120.000014 -77.0001)
		(width 0.3048)
		(layer "B.Cu")
		(net "GND")
	)
	(segment
		(start 11.43 -51.3588)
		(end 10.227818 -51.3588)
		(width 0.508)
		(layer "B.Cu")
		(net "GND")
	)
	(segment
		(start 118.000018 -76.000356)
		(end 118.27256 -75.727814)
		(width 0.508)
		(layer "B.Cu")
		(net "GND")
	)
	(segment
		(start 124.483876 -90.137742)
		(end 124.46 -90.161618)
		(width 0.508)
		(layer "B.Cu")
		(net "GND")
	)
	(segment
		(start 178.9938 -31.19374)
		(end 178.9938 -30.353)
		(width 0.3048)
		(layer "B.Cu")
		(net "GND")
	)
	(segment
		(start 143.0147 -122.18035)
		(end 141.582394 -122.18035)
		(width 0.508)
		(layer "B.Cu")
		(net "GND")
	)
	(segment
		(start 165.29812 -48.101758)
		(end 165.399974 -47.999904)
		(width 0.3556)
		(layer "B.Cu")
		(net "GND")
	)
	(segment
		(start 171.842938 -42.91965)
		(end 171.51985 -42.91965)
		(width 0.3556)
		(layer "B.Cu")
		(net "GND")
	)
	(segment
		(start 175.60925 -71.6915)
		(end 176.68875 -71.6915)
		(width 0.508)
		(layer "B.Cu")
		(net "GND")
	)
	(segment
		(start 108.2548 -64.516)
		(end 108.2548 -64.745362)
		(width 0.254)
		(layer "B.Cu")
		(net "GND")
	)
	(segment
		(start 107.061 -85.725)
		(end 107.061 -86.6267)
		(width 0.508)
		(layer "B.Cu")
		(net "GND")
	)
	(segment
		(start 172.08627 -29.313632)
		(end 171.799758 -29.600144)
		(width 0.3048)
		(layer "B.Cu")
		(net "GND")
	)
	(segment
		(start 125.117098 -74.1172)
		(end 125.5014 -74.1172)
		(width 0.3048)
		(layer "B.Cu")
		(net "GND")
	)
	(segment
		(start 108.690664 -63.3095)
		(end 109.000036 -63.000128)
		(width 0.4572)
		(layer "B.Cu")
		(net "GND")
	)
	(segment
		(start 177.60823 -28.92425)
		(end 177.60823 -29.39161)
		(width 0.3048)
		(layer "B.Cu")
		(net "GND")
	)
	(segment
		(start 100.457 -61.214)
		(end 100.786184 -61.214)
		(width 0.3048)
		(layer "B.Cu")
		(net "GND")
	)
	(segment
		(start 104.4956 -65.0494)
		(end 104.049322 -65.0494)
		(width 0.254)
		(layer "B.Cu")
		(net "GND")
	)
	(segment
		(start 124.7775 -53.777642)
		(end 125.000004 -54.000146)
		(width 0.254)
		(layer "B.Cu")
		(net "GND")
	)
	(segment
		(start 116.501418 -80.79867)
		(end 116.798598 -80.79867)
		(width 0.3048)
		(layer "B.Cu")
		(net "GND")
	)
	(segment
		(start 183.6928 -30.353)
		(end 183.6928 -31.092648)
		(width 0.3048)
		(layer "B.Cu")
		(net "GND")
	)
	(segment
		(start 114.681 -53.7464)
		(end 114.253772 -53.7464)
		(width 0.3048)
		(layer "B.Cu")
		(net "GND")
	)
	(segment
		(start 108.585 -84.8741)
		(end 108.585 -85.725)
		(width 0.508)
		(layer "B.Cu")
		(net "GND")
	)
	(segment
		(start 117.5004 -76.3016)
		(end 117.698774 -76.3016)
		(width 0.3048)
		(layer "B.Cu")
		(net "GND")
	)
	(segment
		(start 83.278472 -73.69175)
		(end 84.105496 -73.69175)
		(width 0.254)
		(layer "B.Cu")
		(net "GND")
	)
	(segment
		(start 85.2678 -74.854054)
		(end 85.2678 -75.6031)
		(width 0.254)
		(layer "B.Cu")
		(net "GND")
	)
	(segment
		(start 70.742556 -15.003272)
		(end 70.488556 -14.749272)
		(width 0.508)
		(layer "B.Cu")
		(net "GND")
	)
	(segment
		(start 103.505 -60.2234)
		(end 103.77678 -60.2234)
		(width 0.3048)
		(layer "B.Cu")
		(net "GND")
	)
	(segment
		(start 172.08627 -29.016198)
		(end 172.08627 -29.313632)
		(width 0.3048)
		(layer "B.Cu")
		(net "GND")
	)
	(segment
		(start 184.744868 -42.545508)
		(end 184.59958 -42.40022)
		(width 0.3556)
		(layer "B.Cu")
		(net "GND")
	)
	(segment
		(start 124.000006 -74.000106)
		(end 124.2568 -73.743312)
		(width 0.3048)
		(layer "B.Cu")
		(net "GND")
	)
	(segment
		(start 179.1716 -31.75)
		(end 179.1716 -31.37154)
		(width 0.3048)
		(layer "B.Cu")
		(net "GND")
	)
	(segment
		(start 177.2158 -31.015686)
		(end 177.2158 -30.353)
		(width 0.3048)
		(layer "B.Cu")
		(net "GND")
	)
	(segment
		(start 103.77678 -60.2234)
		(end 104.000046 -60.000134)
		(width 0.3048)
		(layer "B.Cu")
		(net "GND")
	)
	(segment
		(start 120.523 -76.7334)
		(end 120.266714 -76.7334)
		(width 0.3048)
		(layer "B.Cu")
		(net "GND")
	)
	(segment
		(start 165.46322 -44.255436)
		(end 166.007542 -44.799758)
		(width 0.508)
		(layer "B.Cu")
		(net "GND")
	)
	(segment
		(start 124.00026 -68.50634)
		(end 124.00026 -68.999862)
		(width 0.254)
		(layer "B.Cu")
		(net "GND")
	)
	(segment
		(start 125.000004 -74.000106)
		(end 125.117098 -74.1172)
		(width 0.3048)
		(layer "B.Cu")
		(net "GND")
	)
	(segment
		(start 166.007542 -44.799758)
		(end 166.19982 -44.799758)
		(width 0.508)
		(layer "B.Cu")
		(net "GND")
	)
	(segment
		(start 180.599842 -31.199836)
		(end 180.7718 -31.027878)
		(width 0.3048)
		(layer "B.Cu")
		(net "GND")
	)
	(segment
		(start 124.000006 -61.000132)
		(end 123.9901 -61.010038)
		(width 0.254)
		(layer "B.Cu")
		(net "GND")
	)
	(segment
		(start 100.457 -59.2074)
		(end 100.792788 -59.2074)
		(width 0.3048)
		(layer "B.Cu")
		(net "GND")
	)
	(segment
		(start 123.9647 -71.501)
		(end 123.9647 -71.035418)
		(width 0.254)
		(layer "B.Cu")
		(net "GND")
	)
	(segment
		(start 103.049324 -65.0494)
		(end 103.000048 -65.000124)
		(width 0.254)
		(layer "B.Cu")
		(net "GND")
	)
	(segment
		(start 125.001528 -76.294742)
		(end 125.001528 -76.998576)
		(width 0.508)
		(layer "B.Cu")
		(net "GND")
	)
	(segment
		(start 127.691388 -58.493914)
		(end 127.691388 -58.308748)
		(width 0.3048)
		(layer "B.Cu")
		(net "GND")
	)
	(segment
		(start 67.376548 -15.142972)
		(end 67.376548 -14.507972)
		(width 0.508)
		(layer "B.Cu")
		(net "GND")
	)
	(segment
		(start 127.7239 -93.0021)
		(end 127.7239 -93.599)
		(width 0.508)
		(layer "B.Cu")
		(net "GND")
	)
	(segment
		(start 101.785674 -64.000126)
		(end 102.0572 -63.7286)
		(width 0.254)
		(layer "B.Cu")
		(net "GND")
	)
	(segment
		(start 185.31967 -49.520094)
		(end 184.59958 -48.800004)
		(width 0.3048)
		(layer "B.Cu")
		(net "GND")
	)
	(segment
		(start 192.4431 -25.29967)
		(end 191.553592 -25.29967)
		(width 0.508)
		(layer "B.Cu")
		(net "GND")
	)
	(segment
		(start 99.5426 -86.5251)
		(end 98.947986 -85.930486)
		(width 0.508)
		(layer "B.Cu")
		(net "GND")
	)
	(segment
		(start 162.790632 -42.164)
		(end 162.333432 -42.6212)
		(width 0.508)
		(layer "B.Cu")
		(net "GND")
	)
	(segment
		(start 117.856 -87.4395)
		(end 117.983 -87.5665)
		(width 0.508)
		(layer "B.Cu")
		(net "GND")
	)
	(segment
		(start 201.803 -34.107882)
		(end 201.803 -34.8869)
		(width 0.508)
		(layer "B.Cu")
		(net "GND")
	)
	(segment
		(start 125.0061 -72.375014)
		(end 125.0061 -72.5043)
		(width 0.254)
		(layer "B.Cu")
		(net "GND")
	)
	(segment
		(start 104.013 -83.8835)
		(end 104.013 -83.013042)
		(width 0.508)
		(layer "B.Cu")
		(net "GND")
	)
	(segment
		(start 184.434988 -35.368484)
		(end 184.434988 -32.230314)
		(width 0.3048)
		(layer "B.Cu")
		(net "GND")
	)
	(segment
		(start 114.253518 -80.7466)
		(end 114.000026 -81.000092)
		(width 0.3048)
		(layer "B.Cu")
		(net "GND")
	)
	(segment
		(start 140.7795 -117.16004)
		(end 140.7795 -116.205)
		(width 0.508)
		(layer "B.Cu")
		(net "GND")
	)
	(segment
		(start 176.7205 -53.3908)
		(end 176.7205 -52.952904)
		(width 0.508)
		(layer "B.Cu")
		(net "GND")
	)
	(segment
		(start 124.0028 -64.4906)
		(end 124.000006 -64.493394)
		(width 0.254)
		(layer "B.Cu")
		(net "GND")
	)
	(segment
		(start 123.166632 -80.833468)
		(end 123.000008 -81.000092)
		(width 0.3048)
		(layer "B.Cu")
		(net "GND")
	)
	(segment
		(start 184.744868 -43.854878)
		(end 184.59958 -44.000166)
		(width 0.3048)
		(layer "B.Cu")
		(net "GND")
	)
	(segment
		(start 127.691388 -55.499)
		(end 127.691388 -55.691532)
		(width 0.3048)
		(layer "B.Cu")
		(net "GND")
	)
	(segment
		(start 72.517 -15.003272)
		(end 73.192894 -15.003272)
		(width 0.508)
		(layer "B.Cu")
		(net "GND")
	)
	(segment
		(start 203.22032 -62.527434)
		(end 202.056492 -62.527434)
		(width 0.3048)
		(layer "B.Cu")
		(net "GND")
	)
	(segment
		(start 122.584972 -87.094568)
		(end 122.584972 -88.002872)
		(width 0.508)
		(layer "B.Cu")
		(net "GND")
	)
	(segment
		(start 181.9656 -31.75)
		(end 181.9656 -31.434024)
		(width 0.3048)
		(layer "B.Cu")
		(net "GND")
	)
	(segment
		(start 180.5686 -31.231078)
		(end 180.599842 -31.199836)
		(width 0.3048)
		(layer "B.Cu")
		(net "GND")
	)
	(segment
		(start 93.6244 -84.35594)
		(end 93.6244 -83.57489)
		(width 0.381)
		(layer "B.Cu")
		(net "GND")
	)
	(segment
		(start 105.283 -66.283078)
		(end 105.283 -66.7766)
		(width 0.254)
		(layer "B.Cu")
		(net "GND")
	)
	(segment
		(start 101.13772 -83.137756)
		(end 101.000052 -83.000088)
		(width 0.508)
		(layer "B.Cu")
		(net "GND")
	)
	(segment
		(start 185.31967 -49.663858)
		(end 185.31967 -49.520094)
		(width 0.3048)
		(layer "B.Cu")
		(net "GND")
	)
	(segment
		(start 103.505 -65.0494)
		(end 103.049324 -65.0494)
		(width 0.254)
		(layer "B.Cu")
		(net "GND")
	)
	(segment
		(start 184.744868 -48.05299)
		(end 184.744868 -48.654716)
		(width 0.3048)
		(layer "B.Cu")
		(net "GND")
	)
	(segment
		(start 168.57853 -5.947156)
		(end 168.579292 -5.946394)
		(width 0.508)
		(layer "B.Cu")
		(net "GND")
	)
	(segment
		(start 127.691388 -57.4929)
		(end 127.691388 -57.691528)
		(width 0.3048)
		(layer "B.Cu")
		(net "GND")
	)
	(segment
		(start 106.661966 -67.01409)
		(end 106.661966 -66.685414)
		(width 0.254)
		(layer "B.Cu")
		(net "GND")
	)
	(segment
		(start 73.192894 -15.003272)
		(end 73.446894 -14.749272)
		(width 0.508)
		(layer "B.Cu")
		(net "GND")
	)
	(segment
		(start 127.6858 -93.5609)
		(end 126.6317 -93.5609)
		(width 0.508)
		(layer "B.Cu")
		(net "GND")
	)
	(segment
		(start 86.0171 -72.5932)
		(end 86.0171 -71.4629)
		(width 0.508)
		(layer "B.Cu")
		(net "GND")
	)
	(segment
		(start 184.744868 -45.454824)
		(end 184.59958 -45.600112)
		(width 0.3048)
		(layer "B.Cu")
		(net "GND")
	)
	(segment
		(start 84.105496 -73.69175)
		(end 85.2678 -74.854054)
		(width 0.254)
		(layer "B.Cu")
		(net "GND")
	)
	(segment
		(start 66.7512 -94.538292)
		(end 66.7512 -95.4405)
		(width 0.508)
		(layer "B.Cu")
		(net "GND")
	)
	(segment
		(start 180.5686 -31.75)
		(end 180.5686 -31.231078)
		(width 0.3048)
		(layer "B.Cu")
		(net "GND")
	)
	(segment
		(start 66.441574 -94.228666)
		(end 66.7512 -94.538292)
		(width 0.508)
		(layer "B.Cu")
		(net "GND")
	)
	(segment
		(start 104.049576 -61.9506)
		(end 104.000046 -62.00013)
		(width 0.254)
		(layer "B.Cu")
		(net "GND")
	)
	(segment
		(start 105.890314 -78.310486)
		(end 105.890314 -78.24724)
		(width 0.254)
		(layer "B.Cu")
		(net "GND")
	)
	(segment
		(start 127.7239 -93.599)
		(end 127.6858 -93.5609)
		(width 0.508)
		(layer "B.Cu")
		(net "GND")
	)
	(segment
		(start 104.51338 -85.25002)
		(end 104.51338 -84.836)
		(width 0.508)
		(layer "B.Cu")
		(net "GND")
	)
	(segment
		(start 184.744868 -48.05299)
		(end 184.744868 -47.345346)
		(width 0.3048)
		(layer "B.Cu")
		(net "GND")
	)
	(segment
		(start 107.061 -84.8995)
		(end 107.061 -85.725)
		(width 0.508)
		(layer "B.Cu")
		(net "GND")
	)
	(segment
		(start 184.434988 -32.230314)
		(end 184.434988 -31.834836)
		(width 0.3048)
		(layer "B.Cu")
		(net "GND")
	)
	(segment
		(start 100.0506 -57.4802)
		(end 100.0506 -57.949592)
		(width 0.254)
		(layer "B.Cu")
		(net "GND")
	)
	(segment
		(start 89.68994 -82.2706)
		(end 90.1192 -81.84134)
		(width 0.508)
		(layer "B.Cu")
		(net "GND")
	)
	(segment
		(start 105.5116 -79.3242)
		(end 105.5116 -78.6892)
		(width 0.254)
		(layer "B.Cu")
		(net "GND")
	)
	(segment
		(start 75.7682 -74.67219)
		(end 75.7682 -75.6031)
		(width 0.254)
		(layer "B.Cu")
		(net "GND")
	)
	(segment
		(start 114.3508 -81.350866)
		(end 114.000026 -81.000092)
		(width 0.4064)
		(layer "B.Cu")
		(net "GND")
	)
	(segment
		(start 127.691388 -54.308756)
		(end 127.999998 -54.000146)
		(width 0.3048)
		(layer "B.Cu")
		(net "GND")
	)
	(segment
		(start 67.376548 -14.507972)
		(end 67.865752 -14.018768)
		(width 0.508)
		(layer "B.Cu")
		(net "GND")
	)
	(segment
		(start 203.0095 -18.95475)
		(end 203.0095 -18.06575)
		(width 0.508)
		(layer "B.Cu")
		(net "GND")
	)
	(segment
		(start 174.612808 -51.199796)
		(end 174.199804 -51.199796)
		(width 0.508)
		(layer "B.Cu")
		(net "GND")
	)
	(segment
		(start 124.000006 -73.000108)
		(end 123.987814 -73.0123)
		(width 0.3048)
		(layer "B.Cu")
		(net "GND")
	)
	(segment
		(start 95.814134 -84.734654)
		(end 96.303592 -85.224112)
		(width 0.508)
		(layer "B.Cu")
		(net "GND")
	)
	(segment
		(start 188.043566 -38.582346)
		(end 188.815472 -38.582346)
		(width 0.508)
		(layer "B.Cu")
		(net "GND")
	)
	(segment
		(start 105.000044 -66.000122)
		(end 105.283 -66.283078)
		(width 0.254)
		(layer "B.Cu")
		(net "GND")
	)
	(segment
		(start 124.0028 -63.5)
		(end 124.000006 -63.497206)
		(width 0.254)
		(layer "B.Cu")
		(net "GND")
	)
	(segment
		(start 127.691388 -55.691532)
		(end 127.999998 -56.000142)
		(width 0.3048)
		(layer "B.Cu")
		(net "GND")
	)
	(segment
		(start 79.3877 -73.6854)
		(end 78.74 -74.3331)
		(width 0.508)
		(layer "B.Cu")
		(net "GND")
	)
	(segment
		(start 124.000006 -65.509394)
		(end 124.000006 -66.000122)
		(width 0.254)
		(layer "B.Cu")
		(net "GND")
	)
	(segment
		(start 113.733072 -75.733656)
		(end 113.999772 -76.000356)
		(width 0.3048)
		(layer "B.Cu")
		(net "GND")
	)
	(segment
		(start 96.303592 -85.224112)
		(end 96.303592 -85.644736)
		(width 0.508)
		(layer "B.Cu")
		(net "GND")
	)
	(segment
		(start 114.253772 -53.7464)
		(end 114.000026 -54.000146)
		(width 0.3048)
		(layer "B.Cu")
		(net "GND")
	)
	(segment
		(start 183.21528 -32.12973)
		(end 183.21528 -31.72587)
		(width 0.3048)
		(layer "B.Cu")
		(net "GND")
	)
	(segment
		(start 127.999998 -73.263252)
		(end 127.999998 -73.000108)
		(width 0.3048)
		(layer "B.Cu")
		(net "GND")
	)
	(segment
		(start 119.888 -89.9795)
		(end 119.888 -90.91295)
		(width 0.508)
		(layer "B.Cu")
		(net "GND")
	)
	(segment
		(start 184.744868 -38.39845)
		(end 184.744868 -36.87191)
		(width 0.3048)
		(layer "B.Cu")
		(net "GND")
	)
	(segment
		(start 128.2446 -66.675)
		(end 128.2446 -66.244724)
		(width 0.3048)
		(layer "B.Cu")
		(net "GND")
	)
	(segment
		(start 125.000004 -67.469004)
		(end 125.000004 -68.000118)
		(width 0.254)
		(layer "B.Cu")
		(net "GND")
	)
	(segment
		(start 111.819944 -89.240614)
		(end 112.838738 -89.240614)
		(width 0.508)
		(layer "B.Cu")
		(net "GND")
	)
	(segment
		(start 100.792788 -59.2074)
		(end 101.000052 -59.000136)
		(width 0.3048)
		(layer "B.Cu")
		(net "GND")
	)
	(segment
		(start 98.947986 -85.930486)
		(end 98.947986 -85.624162)
		(width 0.508)
		(layer "B.Cu")
		(net "GND")
	)
	(segment
		(start 76.10729 -74.3331)
		(end 75.7682 -74.67219)
		(width 0.254)
		(layer "B.Cu")
		(net "GND")
	)
	(segment
		(start 124.2568 -73.743312)
		(end 124.2568 -73.4822)
		(width 0.3048)
		(layer "B.Cu")
		(net "GND")
	)
	(segment
		(start 124.000006 -62.486794)
		(end 124.000006 -63.000128)
		(width 0.254)
		(layer "B.Cu")
		(net "GND")
	)
	(segment
		(start 86.0171 -71.4629)
		(end 86.0171 -70.55358)
		(width 0.508)
		(layer "B.Cu")
		(net "GND")
	)
	(segment
		(start 166.523416 -43.523408)
		(end 166.19982 -43.199812)
		(width 0.3048)
		(layer "B.Cu")
		(net "GND")
	)
	(segment
		(start 184.744868 -44.78401)
		(end 184.744868 -44.145454)
		(width 0.3048)
		(layer "B.Cu")
		(net "GND")
	)
	(segment
		(start 184.744868 -44.78401)
		(end 184.744868 -45.454824)
		(width 0.3048)
		(layer "B.Cu")
		(net "GND")
	)
	(segment
		(start 191.553592 -25.29967)
		(end 191.224662 -25.6286)
		(width 0.508)
		(layer "B.Cu")
		(net "GND")
	)
	(segment
		(start 176.7205 -52.952904)
		(end 177.055526 -52.617878)
		(width 0.508)
		(layer "B.Cu")
		(net "GND")
	)
	(segment
		(start 114.3508 -81.8261)
		(end 114.3508 -81.350866)
		(width 0.4064)
		(layer "B.Cu")
		(net "GND")
	)
	(segment
		(start 125.000004 -72.368918)
		(end 125.0061 -72.375014)
		(width 0.254)
		(layer "B.Cu")
		(net "GND")
	)
	(segment
		(start 127.691388 -59.491626)
		(end 127.691388 -59.691524)
		(width 0.3048)
		(layer "B.Cu")
		(net "GND")
	)
	(segment
		(start 102.0572 -63.7286)
		(end 103.3272 -63.7286)
		(width 0.254)
		(layer "B.Cu")
		(net "GND")
	)
	(segment
		(start 172.753528 -32.69869)
		(end 172.600112 -32.545274)
		(width 0.508)
		(layer "B.Cu")
		(net "GND")
	)
	(segment
		(start 202.311 -57.531)
		(end 202.311 -58.2295)
		(width 0.508)
		(layer "B.Cu")
		(net "GND")
	)
	(segment
		(start 188.815472 -38.582346)
		(end 188.836808 -38.56101)
		(width 0.508)
		(layer "B.Cu")
		(net "GND")
	)
	(segment
		(start 183.21528 -31.72587)
		(end 183.741314 -31.199836)
		(width 0.3048)
		(layer "B.Cu")
		(net "GND")
	)
	(segment
		(start 101.000052 -66.391028)
		(end 101.000052 -66.000122)
		(width 0.508)
		(layer "B.Cu")
		(net "GND")
	)
	(segment
		(start 184.744868 -46.42993)
		(end 184.744868 -47.05477)
		(width 0.3048)
		(layer "B.Cu")
		(net "GND")
	)
	(segment
		(start 108.2548 -65.254886)
		(end 108.000038 -65.000124)
		(width 0.254)
		(layer "B.Cu")
		(net "GND")
	)
	(segment
		(start 127.691388 -56.308752)
		(end 127.999998 -56.000142)
		(width 0.3048)
		(layer "B.Cu")
		(net "GND")
	)
	(segment
		(start 124.82703 -89.003632)
		(end 124.82703 -89.794588)
		(width 0.508)
		(layer "B.Cu")
		(net "GND")
	)
	(segment
		(start 93.4847 -84.49564)
		(end 93.6244 -84.35594)
		(width 0.381)
		(layer "B.Cu")
		(net "GND")
	)
	(segment
		(start 177.400204 -31.20009)
		(end 177.2158 -31.015686)
		(width 0.3048)
		(layer "B.Cu")
		(net "GND")
	)
	(segment
		(start 130.1496 -78.74)
		(end 130.1496 -78.149704)
		(width 0.3048)
		(layer "B.Cu")
		(net "GND")
	)
	(segment
		(start 104.51338 -84.836)
		(end 104.013 -84.33562)
		(width 0.508)
		(layer "B.Cu")
		(net "GND")
	)
	(segment
		(start 113.733072 -75.47737)
		(end 113.733072 -75.733656)
		(width 0.3048)
		(layer "B.Cu")
		(net "GND")
	)
	(segment
		(start 88.5444 -82.2706)
		(end 89.68994 -82.2706)
		(width 0.508)
		(layer "B.Cu")
		(net "GND")
	)
	(segment
		(start 166.628318 -44.799758)
		(end 166.19982 -44.799758)
		(width 0.3048)
		(layer "B.Cu")
		(net "GND")
	)
	(segment
		(start 168.579292 -5.946394)
		(end 169.455846 -5.946394)
		(width 0.508)
		(layer "B.Cu")
		(net "GND")
	)
	(segment
		(start 106.000042 -78.137512)
		(end 106.000042 -78.000098)
		(width 0.254)
		(layer "B.Cu")
		(net "GND")
	)
	(segment
		(start 126.238 -78.49108)
		(end 126.238 -78.238096)
		(width 0.3048)
		(layer "B.Cu")
		(net "GND")
	)
	(segment
		(start 132.5753 -124.19965)
		(end 131.34975 -124.19965)
		(width 0.508)
		(layer "B.Cu")
		(net "GND")
	)
	(segment
		(start 123.9901 -61.010038)
		(end 123.9901 -61.5061)
		(width 0.254)
		(layer "B.Cu")
		(net "GND")
	)
	(segment
		(start 167.8051 -32.005016)
		(end 166.99992 -31.199836)
		(width 0.3048)
		(layer "B.Cu")
		(net "GND")
	)
	(segment
		(start 100.0506 -57.949592)
		(end 100.000054 -58.000138)
		(width 0.254)
		(layer "B.Cu")
		(net "GND")
	)
	(segment
		(start 100.786184 -61.214)
		(end 101.000052 -61.000132)
		(width 0.3048)
		(layer "B.Cu")
		(net "GND")
	)
	(segment
		(start 179.1716 -31.37154)
		(end 179.00015 -31.20009)
		(width 0.3048)
		(layer "B.Cu")
		(net "GND")
	)
	(segment
		(start 71.5518 -15.003272)
		(end 70.742556 -15.003272)
		(width 0.508)
		(layer "B.Cu")
		(net "GND")
	)
	(segment
		(start 171.842938 -43.47845)
		(end 171.521628 -43.47845)
		(width 0.3556)
		(layer "B.Cu")
		(net "GND")
	)
	(segment
		(start 184.744868 -36.87191)
		(end 184.744868 -35.678364)
		(width 0.3048)
		(layer "B.Cu")
		(net "GND")
	)
	(segment
		(start 163.0045 -42.164)
		(end 162.790632 -42.164)
		(width 0.508)
		(layer "B.Cu")
		(net "GND")
	)
	(segment
		(start 107.93476 -66.0654)
		(end 108.000038 -66.000122)
		(width 0.254)
		(layer "B.Cu")
		(net "GND")
	)
	(segment
		(start 100.000054 -58.000138)
		(end 100.2538 -58.253884)
		(width 0.3048)
		(layer "B.Cu")
		(net "GND")
	)
	(segment
		(start 116.84 -87.4395)
		(end 117.856 -87.4395)
		(width 0.508)
		(layer "B.Cu")
		(net "GND")
	)
	(segment
		(start 184.744868 -46.42993)
		(end 184.744868 -45.7454)
		(width 0.3048)
		(layer "B.Cu")
		(net "GND")
	)
	(segment
		(start 124.0028 -68.5038)
		(end 124.00026 -68.50634)
		(width 0.254)
		(layer "B.Cu")
		(net "GND")
	)
	(segment
		(start 127.691388 -56.5023)
		(end 127.691388 -56.308752)
		(width 0.3048)
		(layer "B.Cu")
		(net "GND")
	)
	(segment
		(start 106.000042 -68.000118)
		(end 106.661966 -67.338194)
		(width 0.254)
		(layer "B.Cu")
		(net "GND")
	)
	(segment
		(start 196.11975 -19.8755)
		(end 196.11975 -21.091398)
		(width 0.508)
		(layer "B.Cu")
		(net "GND")
	)
	(segment
		(start 117.698774 -76.3016)
		(end 118.000018 -76.000356)
		(width 0.3048)
		(layer "B.Cu")
		(net "GND")
	)
	(segment
		(start 174.6885 -32.6898)
		(end 175.699166 -32.6898)
		(width 0.508)
		(layer "B.Cu")
		(net "GND")
	)
	(segment
		(start 108.2548 -65.5066)
		(end 108.2548 -65.254886)
		(width 0.254)
		(layer "B.Cu")
		(net "GND")
	)
	(segment
		(start 201.8538 -57.0738)
		(end 202.311 -57.531)
		(width 0.508)
		(layer "B.Cu")
		(net "GND")
	)
	(segment
		(start 125.0061 -70.00621)
		(end 125.000004 -70.000114)
		(width 0.254)
		(layer "B.Cu")
		(net "GND")
	)
	(segment
		(start 101.398832 -66.789808)
		(end 101.000052 -66.391028)
		(width 0.508)
		(layer "B.Cu")
		(net "GND")
	)
	(segment
		(start 181.9656 -31.434024)
		(end 182.199788 -31.199836)
		(width 0.3048)
		(layer "B.Cu")
		(net "GND")
	)
	(segment
		(start 93.4847 -85.6488)
		(end 93.4847 -84.49564)
		(width 0.381)
		(layer "B.Cu")
		(net "GND")
	)
	(segment
		(start 124.000006 -63.497206)
		(end 124.000006 -63.000128)
		(width 0.254)
		(layer "B.Cu")
		(net "GND")
	)
	(segment
		(start 184.744868 -40.05961)
		(end 184.744868 -38.39845)
		(width 0.3048)
		(layer "B.Cu")
		(net "GND")
	)
	(segment
		(start 161.798762 -16.702786)
		(end 161.798762 -17.477486)
		(width 0.508)
		(layer "B.Cu")
		(net "GND")
	)
	(segment
		(start 183.198008 -33.53435)
		(end 183.198008 -34.201862)
		(width 0.3048)
		(layer "B.Cu")
		(net "GND")
	)
	(segment
		(start 104.049322 -65.0494)
		(end 104.000046 -65.000124)
		(width 0.254)
		(layer "B.Cu")
		(net "GND")
	)
	(segment
		(start 203.22032 -72.027034)
		(end 201.666348 -72.027034)
		(width 0.3048)
		(layer "B.Cu")
		(net "GND")
	)
	(segment
		(start 184.744868 -43.19651)
		(end 184.744868 -43.854878)
		(width 0.3048)
		(layer "B.Cu")
		(net "GND")
	)
	(segment
		(start 73.025 -73.5965)
		(end 73.025 -75.431396)
		(width 0.508)
		(layer "B.Cu")
		(net "GND")
	)
	(segment
		(start 172.399706 -66.764916)
		(end 171.409614 -66.764916)
		(width 0.508)
		(layer "B.Cu")
		(net "GND")
	)
	(segment
		(start 116.2558 -77.0001)
		(end 116.000022 -77.0001)
		(width 0.254)
		(layer "B.Cu")
		(net "GND")
	)
	(segment
		(start 125.000004 -72.00011)
		(end 125.000004 -72.368918)
		(width 0.254)
		(layer "B.Cu")
		(net "GND")
	)
	(segment
		(start 73.025 -75.431396)
		(end 72.262492 -76.193904)
		(width 0.508)
		(layer "B.Cu")
		(net "GND")
	)
	(segment
		(start 124.0028 -62.484)
		(end 124.000006 -62.486794)
		(width 0.254)
		(layer "B.Cu")
		(net "GND")
	)
	(segment
		(start 174.612808 -51.18735)
		(end 174.612808 -51.199796)
		(width 0.508)
		(layer "B.Cu")
		(net "GND")
	)
	(segment
		(start 125.283976 -51.716178)
		(end 125.000004 -52.00015)
		(width 0.3048)
		(layer "B.Cu")
		(net "GND")
	)
	(segment
		(start 184.744868 -48.654716)
		(end 184.59958 -48.800004)
		(width 0.3048)
		(layer "B.Cu")
		(net "GND")
	)
	(segment
		(start 179.00015 -31.20009)
		(end 178.9938 -31.19374)
		(width 0.3048)
		(layer "B.Cu")
		(net "GND")
	)
	(segment
		(start 183.741314 -31.199836)
		(end 183.799988 -31.199836)
		(width 0.3048)
		(layer "B.Cu")
		(net "GND")
	)
	(segment
		(start 183.198008 -34.201862)
		(end 182.999888 -34.399982)
		(width 0.3048)
		(layer "B.Cu")
		(net "GND")
	)
	(segment
		(start 101.13772 -84.18322)
		(end 101.13772 -83.137756)
		(width 0.508)
		(layer "B.Cu")
		(net "GND")
	)
	(segment
		(start 105.5116 -78.6892)
		(end 105.890314 -78.310486)
		(width 0.254)
		(layer "B.Cu")
		(net "GND")
	)
	(segment
		(start 78.74 -74.3331)
		(end 76.10729 -74.3331)
		(width 0.508)
		(layer "B.Cu")
		(net "GND")
	)
	(segment
		(start 108.2802 -63.3095)
		(end 108.690664 -63.3095)
		(width 0.4572)
		(layer "B.Cu")
		(net "GND")
	)
	(segment
		(start 166.863776 -45.035216)
		(end 166.628318 -44.799758)
		(width 0.3048)
		(layer "B.Cu")
		(net "GND")
	)
	(segment
		(start 106.661966 -67.338194)
		(end 106.661966 -67.01409)
		(width 0.254)
		(layer "B.Cu")
		(net "GND")
	)
	(segment
		(start 95.814134 -84.53374)
		(end 95.814134 -84.734654)
		(width 0.508)
		(layer "B.Cu")
		(net "GND")
	)
	(segment
		(start 127.691388 -58.308748)
		(end 127.999998 -58.000138)
		(width 0.3048)
		(layer "B.Cu")
		(net "GND")
	)
	(segment
		(start 100.2538 -58.253884)
		(end 100.2538 -58.4962)
		(width 0.3048)
		(layer "B.Cu")
		(net "GND")
	)
	(segment
		(start 203.071222 -23.6855)
		(end 202.08875 -23.6855)
		(width 0.508)
		(layer "B.Cu")
		(net "GND")
	)
	(segment
		(start 126.238 -78.238096)
		(end 126.000002 -78.000098)
		(width 0.3048)
		(layer "B.Cu")
		(net "GND")
	)
	(segment
		(start 172.600112 -32.545274)
		(end 172.600112 -32.00019)
		(width 0.508)
		(layer "B.Cu")
		(net "GND")
	)
	(segment
		(start 128.253998 -73.517252)
		(end 127.999998 -73.263252)
		(width 0.3048)
		(layer "B.Cu")
		(net "GND")
	)
	(segment
		(start 128.2446 -66.244724)
		(end 127.999998 -66.000122)
		(width 0.3048)
		(layer "B.Cu")
		(net "GND")
	)
	(segment
		(start 183.6928 -31.092648)
		(end 183.799988 -31.199836)
		(width 0.3048)
		(layer "B.Cu")
		(net "GND")
	)
	(segment
		(start 125.001528 -76.998576)
		(end 125.000004 -77.0001)
		(width 0.508)
		(layer "B.Cu")
		(net "GND")
	)
	(segment
		(start 199.39 -38.608)
		(end 199.39 -40.3606)
		(width 0.508)
		(layer "B.Cu")
		(net "GND")
	)
	(segment
		(start 196.11975 -21.091398)
		(end 196.117464 -21.093684)
		(width 0.508)
		(layer "B.Cu")
		(net "GND")
	)
	(segment
		(start 108.585 -85.725)
		(end 108.585 -86.4997)
		(width 0.508)
		(layer "B.Cu")
		(net "GND")
	)
	(segment
		(start 104.648 -66.7766)
		(end 104.648 -66.352166)
		(width 0.254)
		(layer "B.Cu")
		(net "GND")
	)
	(segment
		(start 124.000006 -64.493394)
		(end 124.000006 -65.000124)
		(width 0.254)
		(layer "B.Cu")
		(net "GND")
	)
	(segment
		(start 171.521628 -43.47845)
		(end 171.000166 -43.999912)
		(width 0.3556)
		(layer "B.Cu")
		(net "GND")
	)
	(segment
		(start 127.691388 -59.691524)
		(end 127.999998 -60.000134)
		(width 0.3048)
		(layer "B.Cu")
		(net "GND")
	)
	(segment
		(start 118.27256 -75.727814)
		(end 118.27256 -75.075288)
		(width 0.508)
		(layer "B.Cu")
		(net "GND")
	)
	(segment
		(start 105.890314 -78.24724)
		(end 106.000042 -78.137512)
		(width 0.254)
		(layer "B.Cu")
		(net "GND")
	)
	(segment
		(start 172.399706 -64.943736)
		(end 172.399706 -66.764916)
		(width 0.508)
		(layer "B.Cu")
		(net "GND")
	)
	(segment
		(start 104.013 -84.33562)
		(end 104.013 -83.8835)
		(width 0.508)
		(layer "B.Cu")
		(net "GND")
	)
	(segment
		(start 104.648 -66.352166)
		(end 105.000044 -66.000122)
		(width 0.254)
		(layer "B.Cu")
		(net "GND")
	)
	(segment
		(start 127.5588 -92.837)
		(end 127.7239 -93.0021)
		(width 0.508)
		(layer "B.Cu")
		(net "GND")
	)
	(segment
		(start 124.000006 -66.532506)
		(end 124.000006 -66.000122)
		(width 0.254)
		(layer "B.Cu")
		(net "GND")
	)
	(segment
		(start 184.744868 -45.7454)
		(end 184.59958 -45.600112)
		(width 0.3048)
		(layer "B.Cu")
		(net "GND")
	)
	(segment
		(start 130.821684 -81.1784)
		(end 130.999992 -81.000092)
		(width 0.3048)
		(layer "B.Cu")
		(net "GND")
	)
	(segment
		(start 127.691388 -57.691528)
		(end 127.999998 -58.000138)
		(width 0.3048)
		(layer "B.Cu")
		(net "GND")
	)
	(segment
		(start 119.25046 -75.075288)
		(end 119.92483 -75.075288)
		(width 0.508)
		(layer "B.Cu")
		(net "GND")
	)
	(segment
		(start 10.227818 -51.3588)
		(end 9.982454 -51.604164)
		(width 0.508)
		(layer "B.Cu")
		(net "GND")
	)
	(segment
		(start 124.9934 -67.4624)
		(end 125.000004 -67.469004)
		(width 0.254)
		(layer "B.Cu")
		(net "GND")
	)
	(segment
		(start 201.666348 -72.027034)
		(end 201.634598 -72.058784)
		(width 0.3048)
		(layer "B.Cu")
		(net "GND")
	)
	(segment
		(start 166.813992 -46.399704)
		(end 166.88943 -46.475142)
		(width 0.3048)
		(layer "B.Cu")
		(net "GND")
	)
	(segment
		(start 175.039528 -50.76063)
		(end 174.612808 -51.18735)
		(width 0.508)
		(layer "B.Cu")
		(net "GND")
	)
	(segment
		(start 166.19982 -46.399704)
		(end 166.813992 -46.399704)
		(width 0.3048)
		(layer "B.Cu")
		(net "GND")
	)
	(segment
		(start 198.755 -34.8869)
		(end 198.755 -34.107882)
		(width 0.508)
		(layer "B.Cu")
		(net "GND")
	)
	(segment
		(start 184.744868 -35.678364)
		(end 184.434988 -35.368484)
		(width 0.3048)
		(layer "B.Cu")
		(net "GND")
	)
	(segment
		(start 170.763438 -32.785304)
		(end 170.763438 -32.236918)
		(width 0.3048)
		(layer "B.Cu")
		(net "GND")
	)
	(segment
		(start 175.699166 -32.6898)
		(end 175.805592 -32.796226)
		(width 0.508)
		(layer "B.Cu")
		(net "GND")
	)
	(segment
		(start 124.0028 -66.5353)
		(end 124.000006 -66.532506)
		(width 0.254)
		(layer "B.Cu")
		(net "GND")
	)
	(segment
		(start 184.744868 -47.05477)
		(end 184.59958 -47.200058)
		(width 0.3048)
		(layer "B.Cu")
		(net "GND")
	)
	(segment
		(start 123.522232 -80.833468)
		(end 123.166632 -80.833468)
		(width 0.3048)
		(layer "B.Cu")
		(net "GND")
	)
	(segment
		(start 177.8508 -31.75)
		(end 177.8508 -31.650686)
		(width 0.3048)
		(layer "B.Cu")
		(net "GND")
	)
	(segment
		(start 116.5098 -76.2762)
		(end 116.5098 -76.7461)
		(width 0.254)
		(layer "B.Cu")
		(net "GND")
	)
	(segment
		(start 130.1496 -78.149704)
		(end 129.999994 -78.000098)
		(width 0.3048)
		(layer "B.Cu")
		(net "GND")
	)
	(segment
		(start 164.852858 -48.101758)
		(end 165.29812 -48.101758)
		(width 0.3556)
		(layer "B.Cu")
		(net "GND")
	)
	(segment
		(start 106.0196 -64.516)
		(end 106.0196 -64.980566)
		(width 0.254)
		(layer "B.Cu")
		(net "GND")
	)
	(segment
		(start 122.3899 -93.345)
		(end 123.0376 -93.345)
		(width 0.508)
		(layer "B.Cu")
		(net "GND")
	)
	(segment
		(start 106.661966 -66.685414)
		(end 106.5022 -66.525648)
		(width 0.254)
		(layer "B.Cu")
		(net "GND")
	)
	(segment
		(start 124.7775 -53.5051)
		(end 124.7775 -53.777642)
		(width 0.254)
		(layer "B.Cu")
		(net "GND")
	)
	(segment
		(start 112.838738 -89.240614)
		(end 113.019586 -89.421462)
		(width 0.508)
		(layer "B.Cu")
		(net "GND")
	)
	(segment
		(start 125.0061 -70.485)
		(end 125.0061 -70.00621)
		(width 0.254)
		(layer "B.Cu")
		(net "GND")
	)
	(segment
		(start 117.983 -87.5665)
		(end 117.983 -88.24214)
		(width 0.508)
		(layer "B.Cu")
		(net "GND")
	)
	(segment
		(start 101.000052 -64.000126)
		(end 101.785674 -64.000126)
		(width 0.254)
		(layer "B.Cu")
		(net "GND")
	)
	(segment
		(start 127.500126 -73.500234)
		(end 127.999998 -74.000106)
		(width 0.4572)
		(layer "F.Cu")
		(net "GB_VDDA")
	)
	(segment
		(start 128.500124 -56.500014)
		(end 128.999996 -56.000142)
		(width 0.4572)
		(layer "F.Cu")
		(net "GB_VDDA")
	)
	(segment
		(start 124.500132 -68.500244)
		(end 125.000004 -69.000116)
		(width 0.4572)
		(layer "F.Cu")
		(net "GB_VDDA")
	)
	(segment
		(start 106.499914 -53.50002)
		(end 106.000042 -53.000148)
		(width 0.4572)
		(layer "F.Cu")
		(net "GB_VDDA")
	)
	(segment
		(start 122.500136 -60.500006)
		(end 123.000008 -60.000134)
		(width 0.4572)
		(layer "F.Cu")
		(net "GB_VDDA")
	)
	(segment
		(start 111.499904 -54.500018)
		(end 111.000032 -54.000146)
		(width 0.4572)
		(layer "F.Cu")
		(net "GB_VDDA")
	)
	(segment
		(start 128.500124 -68.500244)
		(end 128.999996 -69.000116)
		(width 0.4572)
		(layer "F.Cu")
		(net "GB_VDDA")
	)
	(segment
		(start 104.499918 -53.50002)
		(end 104.000046 -53.000148)
		(width 0.4572)
		(layer "F.Cu")
		(net "GB_VDDA")
	)
	(segment
		(start 127.500126 -55.500016)
		(end 127.999998 -55.000144)
		(width 0.4572)
		(layer "F.Cu")
		(net "GB_VDDA")
	)
	(segment
		(start 119.500142 -58.50001)
		(end 120.000014 -58.000138)
		(width 0.4572)
		(layer "F.Cu")
		(net "GB_VDDA")
	)
	(segment
		(start 115.50015 -58.50001)
		(end 116.000022 -58.000138)
		(width 0.4572)
		(layer "F.Cu")
		(net "GB_VDDA")
	)
	(segment
		(start 118.500144 -57.500012)
		(end 118.000018 -58.000138)
		(width 0.4572)
		(layer "F.Cu")
		(net "GB_VDDA")
	)
	(segment
		(start 118.500144 -53.50002)
		(end 119.000016 -53.000148)
		(width 0.4572)
		(layer "F.Cu")
		(net "GB_VDDA")
	)
	(segment
		(start 114.499898 -59.500008)
		(end 113.999772 -60.000134)
		(width 0.4572)
		(layer "F.Cu")
		(net "GB_VDDA")
	)
	(segment
		(start 120.50014 -53.50002)
		(end 121.000012 -53.000148)
		(width 0.4572)
		(layer "F.Cu")
		(net "GB_VDDA")
	)
	(segment
		(start 115.50015 -54.500018)
		(end 116.000022 -54.000146)
		(width 0.4572)
		(layer "F.Cu")
		(net "GB_VDDA")
	)
	(segment
		(start 117.500146 -60.500006)
		(end 118.000018 -60.000134)
		(width 0.4572)
		(layer "F.Cu")
		(net "GB_VDDA")
	)
	(segment
		(start 127.500126 -59.500008)
		(end 127.999998 -59.000136)
		(width 0.4572)
		(layer "F.Cu")
		(net "GB_VDDA")
	)
	(segment
		(start 113.4999 -54.500018)
		(end 113.000028 -54.000146)
		(width 0.4572)
		(layer "F.Cu")
		(net "GB_VDDA")
	)
	(segment
		(start 128.500124 -58.50001)
		(end 128.999996 -58.000138)
		(width 0.4572)
		(layer "F.Cu")
		(net "GB_VDDA")
	)
	(segment
		(start 122.500136 -68.500244)
		(end 123.000008 -69.000116)
		(width 0.4572)
		(layer "F.Cu")
		(net "GB_VDDA")
	)
	(segment
		(start 125.50013 -53.50002)
		(end 126.000002 -53.000148)
		(width 0.4572)
		(layer "F.Cu")
		(net "GB_VDDA")
	)
	(segment
		(start 120.50014 -59.500008)
		(end 120.000014 -60.000134)
		(width 0.4572)
		(layer "F.Cu")
		(net "GB_VDDA")
	)
	(segment
		(start 123.500134 -67.500246)
		(end 124.000006 -68.000118)
		(width 0.4572)
		(layer "F.Cu")
		(net "GB_VDDA")
	)
	(segment
		(start 127.500126 -57.500012)
		(end 127.999998 -57.00014)
		(width 0.4572)
		(layer "F.Cu")
		(net "GB_VDDA")
	)
	(segment
		(start 110.499906 -53.50002)
		(end 110.000034 -53.000148)
		(width 0.4572)
		(layer "F.Cu")
		(net "GB_VDDA")
	)
	(segment
		(start 127.500126 -69.500242)
		(end 127.999998 -70.000114)
		(width 0.4572)
		(layer "F.Cu")
		(net "GB_VDDA")
	)
	(segment
		(start 117.500146 -54.500018)
		(end 118.000018 -54.000146)
		(width 0.4572)
		(layer "F.Cu")
		(net "GB_VDDA")
	)
	(segment
		(start 127.500126 -61.500004)
		(end 127.999998 -61.000132)
		(width 0.4572)
		(layer "F.Cu")
		(net "GB_VDDA")
	)
	(segment
		(start 111.499904 -60.500006)
		(end 111.999776 -60.000134)
		(width 0.4572)
		(layer "F.Cu")
		(net "GB_VDDA")
	)
	(segment
		(start 128.500124 -70.50024)
		(end 128.999996 -71.000112)
		(width 0.4572)
		(layer "F.Cu")
		(net "GB_VDDA")
	)
	(segment
		(start 109.499908 -60.500006)
		(end 109.99978 -60.000134)
		(width 0.4572)
		(layer "F.Cu")
		(net "GB_VDDA")
	)
	(segment
		(start 114.499898 -53.50002)
		(end 114.000026 -53.000148)
		(width 0.4572)
		(layer "F.Cu")
		(net "GB_VDDA")
	)
	(segment
		(start 116.500148 -53.50002)
		(end 117.00002 -53.000148)
		(width 0.4572)
		(layer "F.Cu")
		(net "GB_VDDA")
	)
	(segment
		(start 109.499908 -54.500018)
		(end 109.000036 -54.000146)
		(width 0.4572)
		(layer "F.Cu")
		(net "GB_VDDA")
	)
	(segment
		(start 110.499906 -57.500012)
		(end 109.99978 -58.000138)
		(width 0.4572)
		(layer "F.Cu")
		(net "GB_VDDA")
	)
	(segment
		(start 112.499902 -53.50002)
		(end 112.00003 -53.000148)
		(width 0.4572)
		(layer "F.Cu")
		(net "GB_VDDA")
	)
	(segment
		(start 113.4999 -60.500006)
		(end 113.999772 -60.000134)
		(width 0.4572)
		(layer "F.Cu")
		(net "GB_VDDA")
	)
	(segment
		(start 124.500132 -64.499998)
		(end 125.000004 -64.000126)
		(width 0.4572)
		(layer "F.Cu")
		(net "GB_VDDA")
	)
	(segment
		(start 108.49991 -53.50002)
		(end 108.000038 -53.000148)
		(width 0.4572)
		(layer "F.Cu")
		(net "GB_VDDA")
	)
	(segment
		(start 120.50014 -57.500012)
		(end 120.000014 -58.000138)
		(width 0.4572)
		(layer "F.Cu")
		(net "GB_VDDA")
	)
	(segment
		(start 127.500126 -67.500246)
		(end 127.999998 -68.000118)
		(width 0.4572)
		(layer "F.Cu")
		(net "GB_VDDA")
	)
	(segment
		(start 127.500126 -63.5)
		(end 127.999998 -63.000128)
		(width 0.4572)
		(layer "F.Cu")
		(net "GB_VDDA")
	)
	(segment
		(start 128.500124 -76.500228)
		(end 128.999996 -77.0001)
		(width 0.4572)
		(layer "F.Cu")
		(net "GB_VDDA")
	)
	(segment
		(start 103.49992 -54.500018)
		(end 103.000048 -54.000146)
		(width 0.4572)
		(layer "F.Cu")
		(net "GB_VDDA")
	)
	(segment
		(start 124.500132 -70.50024)
		(end 125.000004 -71.000112)
		(width 0.4572)
		(layer "F.Cu")
		(net "GB_VDDA")
	)
	(segment
		(start 123.500134 -69.500242)
		(end 124.000006 -70.000114)
		(width 0.4572)
		(layer "F.Cu")
		(net "GB_VDDA")
	)
	(segment
		(start 119.500142 -60.500006)
		(end 120.000014 -60.000134)
		(width 0.4572)
		(layer "F.Cu")
		(net "GB_VDDA")
	)
	(segment
		(start 122.500136 -66.499994)
		(end 123.000008 -66.000122)
		(width 0.4572)
		(layer "F.Cu")
		(net "GB_VDDA")
	)
	(segment
		(start 127.500126 -75.50023)
		(end 127.999998 -76.000102)
		(width 0.4572)
		(layer "F.Cu")
		(net "GB_VDDA")
	)
	(segment
		(start 112.499902 -59.500008)
		(end 111.999776 -60.000134)
		(width 0.4572)
		(layer "F.Cu")
		(net "GB_VDDA")
	)
	(segment
		(start 117.500146 -58.50001)
		(end 118.000018 -58.000138)
		(width 0.4572)
		(layer "F.Cu")
		(net "GB_VDDA")
	)
	(segment
		(start 128.500124 -54.500018)
		(end 128.999996 -54.000146)
		(width 0.4572)
		(layer "F.Cu")
		(net "GB_VDDA")
	)
	(segment
		(start 124.500132 -72.500236)
		(end 125.000004 -73.000108)
		(width 0.4572)
		(layer "F.Cu")
		(net "GB_VDDA")
	)
	(segment
		(start 122.500136 -62.500002)
		(end 123.000008 -62.00013)
		(width 0.4572)
		(layer "F.Cu")
		(net "GB_VDDA")
	)
	(segment
		(start 122.500136 -64.499998)
		(end 123.000008 -64.000126)
		(width 0.4572)
		(layer "F.Cu")
		(net "GB_VDDA")
	)
	(segment
		(start 107.499912 -58.50001)
		(end 107.999784 -58.000138)
		(width 0.4572)
		(layer "F.Cu")
		(net "GB_VDDA")
	)
	(segment
		(start 123.500134 -71.500238)
		(end 124.000006 -72.00011)
		(width 0.4572)
		(layer "F.Cu")
		(net "GB_VDDA")
	)
	(segment
		(start 111.499904 -58.50001)
		(end 111.999776 -58.000138)
		(width 0.4572)
		(layer "F.Cu")
		(net "GB_VDDA")
	)
	(segment
		(start 119.500142 -54.500018)
		(end 120.000014 -54.000146)
		(width 0.4572)
		(layer "F.Cu")
		(net "GB_VDDA")
	)
	(segment
		(start 123.500134 -59.500008)
		(end 124.000006 -59.000136)
		(width 0.4572)
		(layer "F.Cu")
		(net "GB_VDDA")
	)
	(segment
		(start 127.500126 -65.499996)
		(end 127.999998 -65.000124)
		(width 0.4572)
		(layer "F.Cu")
		(net "GB_VDDA")
	)
	(segment
		(start 122.500136 -57.500012)
		(end 122.00001 -58.000138)
		(width 0.4572)
		(layer "F.Cu")
		(net "GB_VDDA")
	)
	(segment
		(start 122.500136 -53.50002)
		(end 123.000008 -53.000148)
		(width 0.4572)
		(layer "F.Cu")
		(net "GB_VDDA")
	)
	(segment
		(start 118.500144 -59.500008)
		(end 118.000018 -60.000134)
		(width 0.4572)
		(layer "F.Cu")
		(net "GB_VDDA")
	)
	(segment
		(start 109.499908 -58.50001)
		(end 109.99978 -58.000138)
		(width 0.4572)
		(layer "F.Cu")
		(net "GB_VDDA")
	)
	(segment
		(start 128.500124 -62.500002)
		(end 128.999996 -62.00013)
		(width 0.4572)
		(layer "F.Cu")
		(net "GB_VDDA")
	)
	(segment
		(start 127.500126 -71.500238)
		(end 127.999998 -72.00011)
		(width 0.4572)
		(layer "F.Cu")
		(net "GB_VDDA")
	)
	(segment
		(start 128.500124 -72.500236)
		(end 128.999996 -73.000108)
		(width 0.4572)
		(layer "F.Cu")
		(net "GB_VDDA")
	)
	(segment
		(start 102.499922 -53.50002)
		(end 102.00005 -53.000148)
		(width 0.4572)
		(layer "F.Cu")
		(net "GB_VDDA")
	)
	(segment
		(start 110.499906 -59.500008)
		(end 109.99978 -60.000134)
		(width 0.4572)
		(layer "F.Cu")
		(net "GB_VDDA")
	)
	(segment
		(start 128.500124 -60.500006)
		(end 128.999996 -60.000134)
		(width 0.4572)
		(layer "F.Cu")
		(net "GB_VDDA")
	)
	(segment
		(start 116.500148 -57.500012)
		(end 116.000022 -58.000138)
		(width 0.4572)
		(layer "F.Cu")
		(net "GB_VDDA")
	)
	(segment
		(start 123.500134 -54.500018)
		(end 124.000006 -54.000146)
		(width 0.4572)
		(layer "F.Cu")
		(net "GB_VDDA")
	)
	(segment
		(start 121.500138 -54.500018)
		(end 122.00001 -54.000146)
		(width 0.4572)
		(layer "F.Cu")
		(net "GB_VDDA")
	)
	(segment
		(start 115.50015 -60.500006)
		(end 116.000022 -60.000134)
		(width 0.4572)
		(layer "F.Cu")
		(net "GB_VDDA")
	)
	(segment
		(start 124.500132 -66.499994)
		(end 125.000004 -66.000122)
		(width 0.4572)
		(layer "F.Cu")
		(net "GB_VDDA")
	)
	(segment
		(start 121.500138 -58.50001)
		(end 122.00001 -58.000138)
		(width 0.4572)
		(layer "F.Cu")
		(net "GB_VDDA")
	)
	(segment
		(start 128.500124 -66.499994)
		(end 128.999996 -66.000122)
		(width 0.4572)
		(layer "F.Cu")
		(net "GB_VDDA")
	)
	(segment
		(start 124.500132 -62.500002)
		(end 125.000004 -62.00013)
		(width 0.4572)
		(layer "F.Cu")
		(net "GB_VDDA")
	)
	(segment
		(start 128.500124 -64.499998)
		(end 128.999996 -64.000126)
		(width 0.4572)
		(layer "F.Cu")
		(net "GB_VDDA")
	)
	(segment
		(start 114.499898 -57.500012)
		(end 113.999772 -58.000138)
		(width 0.4572)
		(layer "F.Cu")
		(net "GB_VDDA")
	)
	(segment
		(start 128.500124 -74.500232)
		(end 128.999996 -75.000104)
		(width 0.4572)
		(layer "F.Cu")
		(net "GB_VDDA")
	)
	(segment
		(start 107.499912 -54.500018)
		(end 107.00004 -54.000146)
		(width 0.4572)
		(layer "F.Cu")
		(net "GB_VDDA")
	)
	(segment
		(start 116.500148 -59.500008)
		(end 116.000022 -60.000134)
		(width 0.4572)
		(layer "F.Cu")
		(net "GB_VDDA")
	)
	(segment
		(start 100.499926 -53.50002)
		(end 100.000054 -53.000148)
		(width 0.508)
		(layer "F.Cu")
		(net "GB_VDDA")
	)
	(segment
		(start 112.499902 -57.500012)
		(end 111.999776 -58.000138)
		(width 0.4572)
		(layer "F.Cu")
		(net "GB_VDDA")
	)
	(segment
		(start 113.4999 -58.50001)
		(end 113.999772 -58.000138)
		(width 0.4572)
		(layer "F.Cu")
		(net "GB_VDDA")
	)
	(segment
		(start 122.500136 -70.50024)
		(end 123.000008 -71.000112)
		(width 0.4572)
		(layer "F.Cu")
		(net "GB_VDDA")
	)
	(segment
		(start 105.499916 -54.500018)
		(end 105.000044 -54.000146)
		(width 0.4572)
		(layer "F.Cu")
		(net "GB_VDDA")
	)
	(segment
		(start 108.49991 -59.500008)
		(end 108.000038 -59.99988)
		(width 0.4572)
		(layer "F.Cu")
		(net "GB_VDDA")
	)
	(via
		(at 127.999998 -74.000106)
		(size 0.4572)
		(drill 0.2032)
		(layers "F.Cu" "B.Cu")
		(net "GB_VDDA")
	)
	(via
		(at 122.00001 -54.000146)
		(size 0.4572)
		(drill 0.2032)
		(layers "F.Cu" "B.Cu")
		(net "GB_VDDA")
	)
	(via
		(at 108.000038 -53.000148)
		(size 0.4572)
		(drill 0.2032)
		(layers "F.Cu" "B.Cu")
		(net "GB_VDDA")
	)
	(via
		(at 127.999998 -55.000144)
		(size 0.4572)
		(drill 0.2032)
		(layers "F.Cu" "B.Cu")
		(net "GB_VDDA")
	)
	(via
		(at 123.000008 -69.000116)
		(size 0.4572)
		(drill 0.2032)
		(layers "F.Cu" "B.Cu")
		(net "GB_VDDA")
	)
	(via
		(at 119.000016 -53.000148)
		(size 0.4572)
		(drill 0.2032)
		(layers "F.Cu" "B.Cu")
		(net "GB_VDDA")
	)
	(via
		(at 120.000014 -60.000134)
		(size 0.4572)
		(drill 0.2032)
		(layers "F.Cu" "B.Cu")
		(net "GB_VDDA")
	)
	(via
		(at 78.462378 -43.6372)
		(size 0.7112)
		(drill 0.4064)
		(layers "F.Cu" "B.Cu")
		(net "GB_VDDA")
	)
	(via
		(at 111.999776 -60.000134)
		(size 0.4572)
		(drill 0.2032)
		(layers "F.Cu" "B.Cu")
		(net "GB_VDDA")
	)
	(via
		(at 75.17384 -39.214298)
		(size 0.7112)
		(drill 0.4064)
		(layers "F.Cu" "B.Cu")
		(net "GB_VDDA")
	)
	(via
		(at 114.000026 -53.000148)
		(size 0.4572)
		(drill 0.2032)
		(layers "F.Cu" "B.Cu")
		(net "GB_VDDA")
	)
	(via
		(at 110.000034 -53.000148)
		(size 0.4572)
		(drill 0.2032)
		(layers "F.Cu" "B.Cu")
		(net "GB_VDDA")
	)
	(via
		(at 75.17384 -37.842698)
		(size 0.7112)
		(drill 0.4064)
		(layers "F.Cu" "B.Cu")
		(net "GB_VDDA")
	)
	(via
		(at 125.000004 -64.000126)
		(size 0.4572)
		(drill 0.2032)
		(layers "F.Cu" "B.Cu")
		(net "GB_VDDA")
	)
	(via
		(at 123.000008 -71.000112)
		(size 0.4572)
		(drill 0.2032)
		(layers "F.Cu" "B.Cu")
		(net "GB_VDDA")
	)
	(via
		(at 124.000006 -68.000118)
		(size 0.4572)
		(drill 0.2032)
		(layers "F.Cu" "B.Cu")
		(net "GB_VDDA")
	)
	(via
		(at 128.999996 -71.000112)
		(size 0.4572)
		(drill 0.2032)
		(layers "F.Cu" "B.Cu")
		(net "GB_VDDA")
	)
	(via
		(at 113.000028 -54.000146)
		(size 0.4572)
		(drill 0.2032)
		(layers "F.Cu" "B.Cu")
		(net "GB_VDDA")
	)
	(via
		(at 81.28 -45.72)
		(size 0.6096)
		(drill 0.3048)
		(layers "F.Cu" "B.Cu")
		(net "GB_VDDA")
	)
	(via
		(at 75.2856 -59.0677)
		(size 0.7112)
		(drill 0.4064)
		(layers "F.Cu" "B.Cu")
		(net "GB_VDDA")
	)
	(via
		(at 78.462378 -58.7756)
		(size 0.7112)
		(drill 0.4064)
		(layers "F.Cu" "B.Cu")
		(net "GB_VDDA")
	)
	(via
		(at 78.462378 -51.9176)
		(size 0.7112)
		(drill 0.4064)
		(layers "F.Cu" "B.Cu")
		(net "GB_VDDA")
	)
	(via
		(at 78.462378 -50.546)
		(size 0.7112)
		(drill 0.4064)
		(layers "F.Cu" "B.Cu")
		(net "GB_VDDA")
	)
	(via
		(at 127.999998 -68.000118)
		(size 0.4572)
		(drill 0.2032)
		(layers "F.Cu" "B.Cu")
		(net "GB_VDDA")
	)
	(via
		(at 123.000008 -62.00013)
		(size 0.4572)
		(drill 0.2032)
		(layers "F.Cu" "B.Cu")
		(net "GB_VDDA")
	)
	(via
		(at 78.462378 -57.404)
		(size 0.7112)
		(drill 0.4064)
		(layers "F.Cu" "B.Cu")
		(net "GB_VDDA")
	)
	(via
		(at 78.462378 -60.1472)
		(size 0.7112)
		(drill 0.4064)
		(layers "F.Cu" "B.Cu")
		(net "GB_VDDA")
	)
	(via
		(at 123.000008 -53.000148)
		(size 0.4572)
		(drill 0.2032)
		(layers "F.Cu" "B.Cu")
		(net "GB_VDDA")
	)
	(via
		(at 127.999998 -63.000128)
		(size 0.4572)
		(drill 0.2032)
		(layers "F.Cu" "B.Cu")
		(net "GB_VDDA")
	)
	(via
		(at 121.000012 -53.000148)
		(size 0.4572)
		(drill 0.2032)
		(layers "F.Cu" "B.Cu")
		(net "GB_VDDA")
	)
	(via
		(at 78.462378 -46.4312)
		(size 0.7112)
		(drill 0.4064)
		(layers "F.Cu" "B.Cu")
		(net "GB_VDDA")
	)
	(via
		(at 125.000004 -66.000122)
		(size 0.4572)
		(drill 0.2032)
		(layers "F.Cu" "B.Cu")
		(net "GB_VDDA")
	)
	(via
		(at 127.999998 -70.000114)
		(size 0.4572)
		(drill 0.2032)
		(layers "F.Cu" "B.Cu")
		(net "GB_VDDA")
	)
	(via
		(at 78.462378 -45.0088)
		(size 0.7112)
		(drill 0.4064)
		(layers "F.Cu" "B.Cu")
		(net "GB_VDDA")
	)
	(via
		(at 128.999996 -64.000126)
		(size 0.4572)
		(drill 0.2032)
		(layers "F.Cu" "B.Cu")
		(net "GB_VDDA")
	)
	(via
		(at 78.462378 -53.2892)
		(size 0.7112)
		(drill 0.4064)
		(layers "F.Cu" "B.Cu")
		(net "GB_VDDA")
	)
	(via
		(at 118.000018 -58.000138)
		(size 0.4572)
		(drill 0.2032)
		(layers "F.Cu" "B.Cu")
		(net "GB_VDDA")
	)
	(via
		(at 71.070216 -44.461938)
		(size 0.6604)
		(drill 0.3302)
		(layers "F.Cu" "B.Cu")
		(net "GB_VDDA")
	)
	(via
		(at 125.000004 -69.000116)
		(size 0.4572)
		(drill 0.2032)
		(layers "F.Cu" "B.Cu")
		(net "GB_VDDA")
	)
	(via
		(at 71.374 -55.499)
		(size 0.6604)
		(drill 0.3302)
		(layers "F.Cu" "B.Cu")
		(net "GB_VDDA")
	)
	(via
		(at 103.000048 -54.000146)
		(size 0.4572)
		(drill 0.2032)
		(layers "F.Cu" "B.Cu")
		(net "GB_VDDA")
	)
	(via
		(at 127.999998 -76.000102)
		(size 0.4572)
		(drill 0.2032)
		(layers "F.Cu" "B.Cu")
		(net "GB_VDDA")
	)
	(via
		(at 116.000022 -60.000134)
		(size 0.4572)
		(drill 0.2032)
		(layers "F.Cu" "B.Cu")
		(net "GB_VDDA")
	)
	(via
		(at 124.000006 -72.00011)
		(size 0.4572)
		(drill 0.2032)
		(layers "F.Cu" "B.Cu")
		(net "GB_VDDA")
	)
	(via
		(at 128.999996 -62.00013)
		(size 0.4572)
		(drill 0.2032)
		(layers "F.Cu" "B.Cu")
		(net "GB_VDDA")
	)
	(via
		(at 78.462378 -47.8028)
		(size 0.7112)
		(drill 0.4064)
		(layers "F.Cu" "B.Cu")
		(net "GB_VDDA")
	)
	(via
		(at 127.999998 -72.00011)
		(size 0.4572)
		(drill 0.2032)
		(layers "F.Cu" "B.Cu")
		(net "GB_VDDA")
	)
	(via
		(at 76.439522 -59.73572)
		(size 0.6604)
		(drill 0.3302)
		(layers "F.Cu" "B.Cu")
		(net "GB_VDDA")
	)
	(via
		(at 128.999996 -54.000146)
		(size 0.4572)
		(drill 0.2032)
		(layers "F.Cu" "B.Cu")
		(net "GB_VDDA")
	)
	(via
		(at 117.00002 -53.000148)
		(size 0.4572)
		(drill 0.2032)
		(layers "F.Cu" "B.Cu")
		(net "GB_VDDA")
	)
	(via
		(at 120.000014 -58.000138)
		(size 0.4572)
		(drill 0.2032)
		(layers "F.Cu" "B.Cu")
		(net "GB_VDDA")
	)
	(via
		(at 78.462378 -42.2656)
		(size 0.7112)
		(drill 0.4064)
		(layers "F.Cu" "B.Cu")
		(net "GB_VDDA")
	)
	(via
		(at 128.999996 -73.000108)
		(size 0.4572)
		(drill 0.2032)
		(layers "F.Cu" "B.Cu")
		(net "GB_VDDA")
	)
	(via
		(at 105.000044 -54.000146)
		(size 0.4572)
		(drill 0.2032)
		(layers "F.Cu" "B.Cu")
		(net "GB_VDDA")
	)
	(via
		(at 111.999776 -58.000138)
		(size 0.4572)
		(drill 0.2032)
		(layers "F.Cu" "B.Cu")
		(net "GB_VDDA")
	)
	(via
		(at 78.462378 -56.0324)
		(size 0.7112)
		(drill 0.4064)
		(layers "F.Cu" "B.Cu")
		(net "GB_VDDA")
	)
	(via
		(at 76.5556 -48.26)
		(size 0.6604)
		(drill 0.3302)
		(layers "F.Cu" "B.Cu")
		(net "GB_VDDA")
	)
	(via
		(at 78.039722 -39.735506)
		(size 0.6096)
		(drill 0.3048)
		(layers "F.Cu" "B.Cu")
		(net "GB_VDDA")
	)
	(via
		(at 109.99978 -60.000134)
		(size 0.4572)
		(drill 0.2032)
		(layers "F.Cu" "B.Cu")
		(net "GB_VDDA")
	)
	(via
		(at 111.000032 -54.000146)
		(size 0.4572)
		(drill 0.2032)
		(layers "F.Cu" "B.Cu")
		(net "GB_VDDA")
	)
	(via
		(at 118.000018 -54.000146)
		(size 0.4572)
		(drill 0.2032)
		(layers "F.Cu" "B.Cu")
		(net "GB_VDDA")
	)
	(via
		(at 128.999996 -69.000116)
		(size 0.4572)
		(drill 0.2032)
		(layers "F.Cu" "B.Cu")
		(net "GB_VDDA")
	)
	(via
		(at 124.000006 -70.000114)
		(size 0.4572)
		(drill 0.2032)
		(layers "F.Cu" "B.Cu")
		(net "GB_VDDA")
	)
	(via
		(at 125.000004 -62.00013)
		(size 0.4572)
		(drill 0.2032)
		(layers "F.Cu" "B.Cu")
		(net "GB_VDDA")
	)
	(via
		(at 124.000006 -59.000136)
		(size 0.4572)
		(drill 0.2032)
		(layers "F.Cu" "B.Cu")
		(net "GB_VDDA")
	)
	(via
		(at 128.999996 -60.000134)
		(size 0.4572)
		(drill 0.2032)
		(layers "F.Cu" "B.Cu")
		(net "GB_VDDA")
	)
	(via
		(at 100.000054 -53.000148)
		(size 0.4572)
		(drill 0.2032)
		(layers "F.Cu" "B.Cu")
		(net "GB_VDDA")
	)
	(via
		(at 116.000022 -58.000138)
		(size 0.4572)
		(drill 0.2032)
		(layers "F.Cu" "B.Cu")
		(net "GB_VDDA")
	)
	(via
		(at 109.000036 -54.000146)
		(size 0.4572)
		(drill 0.2032)
		(layers "F.Cu" "B.Cu")
		(net "GB_VDDA")
	)
	(via
		(at 128.999996 -75.000104)
		(size 0.4572)
		(drill 0.2032)
		(layers "F.Cu" "B.Cu")
		(net "GB_VDDA")
	)
	(via
		(at 128.999996 -66.000122)
		(size 0.4572)
		(drill 0.2032)
		(layers "F.Cu" "B.Cu")
		(net "GB_VDDA")
	)
	(via
		(at 123.000008 -64.000126)
		(size 0.4572)
		(drill 0.2032)
		(layers "F.Cu" "B.Cu")
		(net "GB_VDDA")
	)
	(via
		(at 127.999998 -65.000124)
		(size 0.4572)
		(drill 0.2032)
		(layers "F.Cu" "B.Cu")
		(net "GB_VDDA")
	)
	(via
		(at 122.00001 -58.000138)
		(size 0.4572)
		(drill 0.2032)
		(layers "F.Cu" "B.Cu")
		(net "GB_VDDA")
	)
	(via
		(at 123.000008 -66.000122)
		(size 0.4572)
		(drill 0.2032)
		(layers "F.Cu" "B.Cu")
		(net "GB_VDDA")
	)
	(via
		(at 107.00004 -54.000146)
		(size 0.4572)
		(drill 0.2032)
		(layers "F.Cu" "B.Cu")
		(net "GB_VDDA")
	)
	(via
		(at 124.000006 -54.000146)
		(size 0.4572)
		(drill 0.2032)
		(layers "F.Cu" "B.Cu")
		(net "GB_VDDA")
	)
	(via
		(at 104.000046 -53.000148)
		(size 0.4572)
		(drill 0.2032)
		(layers "F.Cu" "B.Cu")
		(net "GB_VDDA")
	)
	(via
		(at 80.391 -58.039)
		(size 0.6096)
		(drill 0.3048)
		(layers "F.Cu" "B.Cu")
		(net "GB_VDDA")
	)
	(via
		(at 102.00005 -53.000148)
		(size 0.4572)
		(drill 0.2032)
		(layers "F.Cu" "B.Cu")
		(net "GB_VDDA")
	)
	(via
		(at 127.999998 -59.000136)
		(size 0.4572)
		(drill 0.2032)
		(layers "F.Cu" "B.Cu")
		(net "GB_VDDA")
	)
	(via
		(at 107.999784 -58.000138)
		(size 0.4572)
		(drill 0.2032)
		(layers "F.Cu" "B.Cu")
		(net "GB_VDDA")
	)
	(via
		(at 128.999996 -56.000142)
		(size 0.4572)
		(drill 0.2032)
		(layers "F.Cu" "B.Cu")
		(net "GB_VDDA")
	)
	(via
		(at 125.000004 -73.000108)
		(size 0.4572)
		(drill 0.2032)
		(layers "F.Cu" "B.Cu")
		(net "GB_VDDA")
	)
	(via
		(at 78.462378 -40.894)
		(size 0.7112)
		(drill 0.4064)
		(layers "F.Cu" "B.Cu")
		(net "GB_VDDA")
	)
	(via
		(at 113.999772 -60.000134)
		(size 0.4572)
		(drill 0.2032)
		(layers "F.Cu" "B.Cu")
		(net "GB_VDDA")
	)
	(via
		(at 108.000038 -59.99988)
		(size 0.4572)
		(drill 0.2032)
		(layers "F.Cu" "B.Cu")
		(net "GB_VDDA")
	)
	(via
		(at 106.000042 -53.000148)
		(size 0.4572)
		(drill 0.2032)
		(layers "F.Cu" "B.Cu")
		(net "GB_VDDA")
	)
	(via
		(at 128.999996 -77.0001)
		(size 0.4572)
		(drill 0.2032)
		(layers "F.Cu" "B.Cu")
		(net "GB_VDDA")
	)
	(via
		(at 109.99978 -58.000138)
		(size 0.4572)
		(drill 0.2032)
		(layers "F.Cu" "B.Cu")
		(net "GB_VDDA")
	)
	(via
		(at 128.999996 -58.000138)
		(size 0.4572)
		(drill 0.2032)
		(layers "F.Cu" "B.Cu")
		(net "GB_VDDA")
	)
	(via
		(at 78.462378 -49.1744)
		(size 0.7112)
		(drill 0.4064)
		(layers "F.Cu" "B.Cu")
		(net "GB_VDDA")
	)
	(via
		(at 127.999998 -57.00014)
		(size 0.4572)
		(drill 0.2032)
		(layers "F.Cu" "B.Cu")
		(net "GB_VDDA")
	)
	(via
		(at 113.999772 -58.000138)
		(size 0.4572)
		(drill 0.2032)
		(layers "F.Cu" "B.Cu")
		(net "GB_VDDA")
	)
	(via
		(at 127.999998 -61.000132)
		(size 0.4572)
		(drill 0.2032)
		(layers "F.Cu" "B.Cu")
		(net "GB_VDDA")
	)
	(via
		(at 125.000004 -71.000112)
		(size 0.4572)
		(drill 0.2032)
		(layers "F.Cu" "B.Cu")
		(net "GB_VDDA")
	)
	(via
		(at 116.000022 -54.000146)
		(size 0.4572)
		(drill 0.2032)
		(layers "F.Cu" "B.Cu")
		(net "GB_VDDA")
	)
	(via
		(at 112.00003 -53.000148)
		(size 0.4572)
		(drill 0.2032)
		(layers "F.Cu" "B.Cu")
		(net "GB_VDDA")
	)
	(via
		(at 80.330802 -53.784754)
		(size 0.6096)
		(drill 0.3048)
		(layers "F.Cu" "B.Cu")
		(net "GB_VDDA")
	)
	(via
		(at 78.462378 -61.5188)
		(size 0.7112)
		(drill 0.4064)
		(layers "F.Cu" "B.Cu")
		(net "GB_VDDA")
	)
	(via
		(at 75.2348 -48.387)
		(size 0.7112)
		(drill 0.4064)
		(layers "F.Cu" "B.Cu")
		(net "GB_VDDA")
	)
	(via
		(at 75.2348 -49.7586)
		(size 0.7112)
		(drill 0.4064)
		(layers "F.Cu" "B.Cu")
		(net "GB_VDDA")
	)
	(via
		(at 123.000008 -60.000134)
		(size 0.4572)
		(drill 0.2032)
		(layers "F.Cu" "B.Cu")
		(net "GB_VDDA")
	)
	(via
		(at 75.2856 -60.4393)
		(size 0.7112)
		(drill 0.4064)
		(layers "F.Cu" "B.Cu")
		(net "GB_VDDA")
	)
	(via
		(at 118.000018 -60.000134)
		(size 0.4572)
		(drill 0.2032)
		(layers "F.Cu" "B.Cu")
		(net "GB_VDDA")
	)
	(via
		(at 78.462378 -54.6608)
		(size 0.7112)
		(drill 0.4064)
		(layers "F.Cu" "B.Cu")
		(net "GB_VDDA")
	)
	(via
		(at 126.000002 -53.000148)
		(size 0.4572)
		(drill 0.2032)
		(layers "F.Cu" "B.Cu")
		(net "GB_VDDA")
	)
	(via
		(at 120.000014 -54.000146)
		(size 0.4572)
		(drill 0.2032)
		(layers "F.Cu" "B.Cu")
		(net "GB_VDDA")
	)
	(segment
		(start 128.8034 -66.675)
		(end 128.8034 -66.196718)
		(width 0.3048)
		(layer "B.Cu")
		(net "GB_VDDA")
	)
	(segment
		(start 125.998986 -52.274978)
		(end 125.998986 -52.999132)
		(width 0.3048)
		(layer "B.Cu")
		(net "GB_VDDA")
	)
	(segment
		(start 128.8034 -66.196718)
		(end 128.999996 -66.000122)
		(width 0.3048)
		(layer "B.Cu")
		(net "GB_VDDA")
	)
	(segment
		(start 125.998986 -52.999132)
		(end 126.000002 -53.000148)
		(width 0.3048)
		(layer "B.Cu")
		(net "GB_VDDA")
	)
	(segment
		(start 124.2187 -53.5051)
		(end 124.2187 -53.781452)
		(width 0.254)
		(layer "B.Cu")
		(net "GB_VDDA")
	)
	(segment
		(start 124.2187 -53.781452)
		(end 124.000006 -54.000146)
		(width 0.254)
		(layer "B.Cu")
		(net "GB_VDDA")
	)
	(segment
		(start 129.079244 -73.079356)
		(end 128.999996 -73.000108)
		(width 0.3048)
		(layer "B.Cu")
		(net "GB_VDDA")
	)
	(segment
		(start 114.681 -53.1876)
		(end 114.187478 -53.1876)
		(width 0.3048)
		(layer "B.Cu")
		(net "GB_VDDA")
	)
	(segment
		(start 114.187478 -53.1876)
		(end 114.000026 -53.000148)
		(width 0.3048)
		(layer "B.Cu")
		(net "GB_VDDA")
	)
	(segment
		(start 129.079244 -73.517252)
		(end 129.079244 -73.079356)
		(width 0.3048)
		(layer "B.Cu")
		(net "GB_VDDA")
	)
	(segment
		(start 109.499908 -84.140802)
		(end 109.499908 -82.500216)
		(width 0.127)
		(layer "F.Cu")
		(net "FW_RESET_N")
	)
	(via
		(at 109.499908 -84.140802)
		(size 0.4572)
		(drill 0.2032)
		(layers "F.Cu" "B.Cu")
		(net "FW_RESET_N")
	)
	(via
		(at 98.084386 -85.61832)
		(size 0.508)
		(drill 0.254)
		(layers "F.Cu" "B.Cu")
		(net "FW_RESET_N")
	)
	(via
		(at 98.084386 -83.1342)
		(size 0.6096)
		(drill 0.3048)
		(layers "F.Cu" "B.Cu")
		(net "FW_RESET_N")
	)
	(via
		(at 78.7908 -85.7504)
		(size 0.508)
		(drill 0.254)
		(layers "F.Cu" "B.Cu")
		(net "FW_RESET_N")
	)
	(segment
		(start 96.807782 -79.98333)
		(end 96.807782 -79.183484)
		(width 0.127)
		(layer "B.Cu")
		(net "FW_RESET_N")
	)
	(segment
		(start 96.807782 -79.98333)
		(end 96.807782 -80.865218)
		(width 0.127)
		(layer "B.Cu")
		(net "FW_RESET_N")
	)
	(segment
		(start 98.084386 -82.141822)
		(end 98.084386 -83.1342)
		(width 0.127)
		(layer "B.Cu")
		(net "FW_RESET_N")
	)
	(segment
		(start 80.26781 -93.34881)
		(end 80.26781 -94.8309)
		(width 0.127)
		(layer "B.Cu")
		(net "FW_RESET_N")
	)
	(segment
		(start 80.1116 -93.159834)
		(end 80.1116 -93.1926)
		(width 0.127)
		(layer "B.Cu")
		(net "FW_RESET_N")
	)
	(segment
		(start 96.807782 -79.183484)
		(end 96.579436 -78.955138)
		(width 0.127)
		(layer "B.Cu")
		(net "FW_RESET_N")
	)
	(segment
		(start 78.7908 -85.7504)
		(end 78.7908 -86.093554)
		(width 0.127)
		(layer "B.Cu")
		(net "FW_RESET_N")
	)
	(segment
		(start 79.0702 -92.118434)
		(end 80.1116 -93.159834)
		(width 0.127)
		(layer "B.Cu")
		(net "FW_RESET_N")
	)
	(segment
		(start 96.807782 -80.865218)
		(end 98.084386 -82.141822)
		(width 0.127)
		(layer "B.Cu")
		(net "FW_RESET_N")
	)
	(segment
		(start 98.084386 -83.1342)
		(end 98.084386 -85.61832)
		(width 0.127)
		(layer "B.Cu")
		(net "FW_RESET_N")
	)
	(segment
		(start 78.7908 -86.093554)
		(end 79.0702 -86.372954)
		(width 0.127)
		(layer "B.Cu")
		(net "FW_RESET_N")
	)
	(segment
		(start 79.0702 -86.372954)
		(end 79.0702 -92.118434)
		(width 0.127)
		(layer "B.Cu")
		(net "FW_RESET_N")
	)
	(segment
		(start 80.1116 -93.1926)
		(end 80.26781 -93.34881)
		(width 0.127)
		(layer "B.Cu")
		(net "FW_RESET_N")
	)
	(segment
		(start 109.038644 -84.140802)
		(end 109.499908 -84.140802)
		(width 0.127)
		(layer "In2.Cu")
		(net "FW_RESET_N")
	)
	(segment
		(start 83.882992 -86.302342)
		(end 87.22233 -86.302342)
		(width 0.127)
		(layer "In2.Cu")
		(net "FW_RESET_N")
	)
	(segment
		(start 97.640902 -85.174836)
		(end 98.084386 -85.61832)
		(width 0.127)
		(layer "In2.Cu")
		(net "FW_RESET_N")
	)
	(segment
		(start 108.450634 -84.728812)
		(end 109.038644 -84.140802)
		(width 0.127)
		(layer "In2.Cu")
		(net "FW_RESET_N")
	)
	(segment
		(start 79.2734 -85.2678)
		(end 80.5688 -85.2678)
		(width 0.127)
		(layer "In2.Cu")
		(net "FW_RESET_N")
	)
	(segment
		(start 105.895648 -84.971636)
		(end 106.138472 -84.728812)
		(width 0.127)
		(layer "In2.Cu")
		(net "FW_RESET_N")
	)
	(segment
		(start 106.138472 -84.728812)
		(end 108.450634 -84.728812)
		(width 0.127)
		(layer "In2.Cu")
		(net "FW_RESET_N")
	)
	(segment
		(start 80.5688 -85.2678)
		(end 81.236058 -85.935058)
		(width 0.127)
		(layer "In2.Cu")
		(net "FW_RESET_N")
	)
	(segment
		(start 98.73107 -84.971636)
		(end 105.895648 -84.971636)
		(width 0.127)
		(layer "In2.Cu")
		(net "FW_RESET_N")
	)
	(segment
		(start 78.7908 -85.7504)
		(end 79.2734 -85.2678)
		(width 0.127)
		(layer "In2.Cu")
		(net "FW_RESET_N")
	)
	(segment
		(start 88.349836 -85.174836)
		(end 97.640902 -85.174836)
		(width 0.127)
		(layer "In2.Cu")
		(net "FW_RESET_N")
	)
	(segment
		(start 83.515708 -85.935058)
		(end 83.882992 -86.302342)
		(width 0.127)
		(layer "In2.Cu")
		(net "FW_RESET_N")
	)
	(segment
		(start 98.084386 -85.61832)
		(end 98.73107 -84.971636)
		(width 0.127)
		(layer "In2.Cu")
		(net "FW_RESET_N")
	)
	(segment
		(start 81.236058 -85.935058)
		(end 83.515708 -85.935058)
		(width 0.127)
		(layer "In2.Cu")
		(net "FW_RESET_N")
	)
	(segment
		(start 87.22233 -86.302342)
		(end 88.349836 -85.174836)
		(width 0.127)
		(layer "In2.Cu")
		(net "FW_RESET_N")
	)
	(segment
		(start 110.499906 -79.500222)
		(end 110.000034 -80.000094)
		(width 0.127)
		(layer "F.Cu")
		(net "EXP_XM_WE_N")
	)
	(via
		(at 77.73924 -85.76056)
		(size 0.508)
		(drill 0.254)
		(layers "F.Cu" "B.Cu")
		(net "EXP_XM_WE_N")
	)
	(via
		(at 110.000034 -80.000094)
		(size 0.4572)
		(drill 0.2032)
		(layers "F.Cu" "B.Cu")
		(net "EXP_XM_WE_N")
	)
	(segment
		(start 78.5622 -92.329)
		(end 79.6036 -93.3704)
		(width 0.127)
		(layer "B.Cu")
		(net "EXP_XM_WE_N")
	)
	(segment
		(start 79.76743 -93.91523)
		(end 79.76743 -94.8309)
		(width 0.127)
		(layer "B.Cu")
		(net "EXP_XM_WE_N")
	)
	(segment
		(start 110.5408 -82.998818)
		(end 109.45876 -81.916778)
		(width 0.127)
		(layer "B.Cu")
		(net "EXP_XM_WE_N")
	)
	(segment
		(start 110.5408 -83.9597)
		(end 110.5408 -82.998818)
		(width 0.127)
		(layer "B.Cu")
		(net "EXP_XM_WE_N")
	)
	(segment
		(start 79.6036 -93.7514)
		(end 79.76743 -93.91523)
		(width 0.127)
		(layer "B.Cu")
		(net "EXP_XM_WE_N")
	)
	(segment
		(start 78.5622 -86.58352)
		(end 78.5622 -92.329)
		(width 0.127)
		(layer "B.Cu")
		(net "EXP_XM_WE_N")
	)
	(segment
		(start 109.45876 -80.541368)
		(end 110.000034 -80.000094)
		(width 0.127)
		(layer "B.Cu")
		(net "EXP_XM_WE_N")
	)
	(segment
		(start 77.73924 -85.76056)
		(end 78.5622 -86.58352)
		(width 0.127)
		(layer "B.Cu")
		(net "EXP_XM_WE_N")
	)
	(segment
		(start 109.45876 -81.916778)
		(end 109.45876 -80.541368)
		(width 0.127)
		(layer "B.Cu")
		(net "EXP_XM_WE_N")
	)
	(segment
		(start 79.6036 -93.3704)
		(end 79.6036 -93.7514)
		(width 0.127)
		(layer "B.Cu")
		(net "EXP_XM_WE_N")
	)
	(segment
		(start 112.761522 -84.2899)
		(end 111.279686 -84.2899)
		(width 0.127)
		(layer "In2.Cu")
		(net "EXP_XM_WE_N")
	)
	(segment
		(start 113.7793 -82.105754)
		(end 113.7793 -83.272122)
		(width 0.127)
		(layer "In2.Cu")
		(net "EXP_XM_WE_N")
	)
	(segment
		(start 111.279686 -84.2899)
		(end 110.178088 -83.188302)
		(width 0.127)
		(layer "In2.Cu")
		(net "EXP_XM_WE_N")
	)
	(segment
		(start 112.5728 -81.01584)
		(end 112.5728 -81.204054)
		(width 0.127)
		(layer "In2.Cu")
		(net "EXP_XM_WE_N")
	)
	(segment
		(start 113.232946 -81.5594)
		(end 113.7793 -82.105754)
		(width 0.127)
		(layer "In2.Cu")
		(net "EXP_XM_WE_N")
	)
	(segment
		(start 110.000034 -80.000094)
		(end 110.378494 -80.000094)
		(width 0.127)
		(layer "In2.Cu")
		(net "EXP_XM_WE_N")
	)
	(segment
		(start 108.770674 -83.188302)
		(end 107.992164 -83.966812)
		(width 0.127)
		(layer "In2.Cu")
		(net "EXP_XM_WE_N")
	)
	(segment
		(start 98.246438 -83.966812)
		(end 97.64395 -83.364324)
		(width 0.127)
		(layer "In2.Cu")
		(net "EXP_XM_WE_N")
	)
	(segment
		(start 112.928146 -81.5594)
		(end 113.232946 -81.5594)
		(width 0.127)
		(layer "In2.Cu")
		(net "EXP_XM_WE_N")
	)
	(segment
		(start 112.02416 -80.4672)
		(end 112.5728 -81.01584)
		(width 0.127)
		(layer "In2.Cu")
		(net "EXP_XM_WE_N")
	)
	(segment
		(start 107.992164 -83.966812)
		(end 98.246438 -83.966812)
		(width 0.127)
		(layer "In2.Cu")
		(net "EXP_XM_WE_N")
	)
	(segment
		(start 78.795372 -84.704428)
		(end 77.73924 -85.76056)
		(width 0.127)
		(layer "In2.Cu")
		(net "EXP_XM_WE_N")
	)
	(segment
		(start 110.178088 -83.188302)
		(end 108.770674 -83.188302)
		(width 0.127)
		(layer "In2.Cu")
		(net "EXP_XM_WE_N")
	)
	(segment
		(start 113.7793 -83.272122)
		(end 112.761522 -84.2899)
		(width 0.127)
		(layer "In2.Cu")
		(net "EXP_XM_WE_N")
	)
	(segment
		(start 112.5728 -81.204054)
		(end 112.928146 -81.5594)
		(width 0.127)
		(layer "In2.Cu")
		(net "EXP_XM_WE_N")
	)
	(segment
		(start 86.664546 -84.704428)
		(end 78.795372 -84.704428)
		(width 0.127)
		(layer "In2.Cu")
		(net "EXP_XM_WE_N")
	)
	(segment
		(start 97.64395 -83.364324)
		(end 88.00465 -83.364324)
		(width 0.127)
		(layer "In2.Cu")
		(net "EXP_XM_WE_N")
	)
	(segment
		(start 110.8456 -80.4672)
		(end 112.02416 -80.4672)
		(width 0.127)
		(layer "In2.Cu")
		(net "EXP_XM_WE_N")
	)
	(segment
		(start 110.378494 -80.000094)
		(end 110.8456 -80.4672)
		(width 0.127)
		(layer "In2.Cu")
		(net "EXP_XM_WE_N")
	)
	(segment
		(start 88.00465 -83.364324)
		(end 86.664546 -84.704428)
		(width 0.127)
		(layer "In2.Cu")
		(net "EXP_XM_WE_N")
	)
	(segment
		(start 111.34852 -86.5505)
		(end 111.8362 -86.06282)
		(width 0.127)
		(layer "F.Cu")
		(net "EXP_XM_OE_N")
	)
	(segment
		(start 111.125 -85.775546)
		(end 111.125 -86.5505)
		(width 0.127)
		(layer "F.Cu")
		(net "EXP_XM_OE_N")
	)
	(segment
		(start 110.499906 -81.81975)
		(end 111.034576 -82.35442)
		(width 0.127)
		(layer "F.Cu")
		(net "EXP_XM_OE_N")
	)
	(segment
		(start 111.034576 -83.709764)
		(end 111.19104 -83.866228)
		(width 0.127)
		(layer "F.Cu")
		(net "EXP_XM_OE_N")
	)
	(segment
		(start 111.034576 -82.35442)
		(end 111.034576 -83.709764)
		(width 0.127)
		(layer "F.Cu")
		(net "EXP_XM_OE_N")
	)
	(segment
		(start 111.19104 -83.866228)
		(end 111.19104 -85.709506)
		(width 0.127)
		(layer "F.Cu")
		(net "EXP_XM_OE_N")
	)
	(segment
		(start 111.19104 -85.709506)
		(end 111.125 -85.775546)
		(width 0.127)
		(layer "F.Cu")
		(net "EXP_XM_OE_N")
	)
	(segment
		(start 110.499906 -81.500218)
		(end 110.499906 -81.81975)
		(width 0.127)
		(layer "F.Cu")
		(net "EXP_XM_OE_N")
	)
	(segment
		(start 111.8362 -86.06282)
		(end 111.8362 -85.725)
		(width 0.127)
		(layer "F.Cu")
		(net "EXP_XM_OE_N")
	)
	(segment
		(start 111.125 -86.5505)
		(end 111.34852 -86.5505)
		(width 0.127)
		(layer "F.Cu")
		(net "EXP_XM_OE_N")
	)
	(via
		(at 111.8362 -85.725)
		(size 0.508)
		(drill 0.254)
		(layers "F.Cu" "B.Cu")
		(net "EXP_XM_OE_N")
	)
	(via
		(at 83.1596 -87.0204)
		(size 0.508)
		(drill 0.254)
		(layers "F.Cu" "B.Cu")
		(net "EXP_XM_OE_N")
	)
	(segment
		(start 84.76742 -78.309978)
		(end 84.76742 -75.6031)
		(width 0.127)
		(layer "B.Cu")
		(net "EXP_XM_OE_N")
	)
	(segment
		(start 83.8708 -86.565232)
		(end 83.8708 -83.797394)
		(width 0.127)
		(layer "B.Cu")
		(net "EXP_XM_OE_N")
	)
	(segment
		(start 83.1596 -87.0204)
		(end 83.415632 -87.0204)
		(width 0.127)
		(layer "B.Cu")
		(net "EXP_XM_OE_N")
	)
	(segment
		(start 84.166456 -83.501738)
		(end 84.166456 -78.910942)
		(width 0.127)
		(layer "B.Cu")
		(net "EXP_XM_OE_N")
	)
	(segment
		(start 83.8708 -83.797394)
		(end 84.166456 -83.501738)
		(width 0.127)
		(layer "B.Cu")
		(net "EXP_XM_OE_N")
	)
	(segment
		(start 84.166456 -78.910942)
		(end 84.76742 -78.309978)
		(width 0.127)
		(layer "B.Cu")
		(net "EXP_XM_OE_N")
	)
	(segment
		(start 83.415632 -87.0204)
		(end 83.8708 -86.565232)
		(width 0.127)
		(layer "B.Cu")
		(net "EXP_XM_OE_N")
	)
	(segment
		(start 88.50757 -87.1728)
		(end 109.405674 -87.1728)
		(width 0.127)
		(layer "In2.Cu")
		(net "EXP_XM_OE_N")
	)
	(segment
		(start 83.163918 -87.0204)
		(end 83.46186 -87.318342)
		(width 0.127)
		(layer "In2.Cu")
		(net "EXP_XM_OE_N")
	)
	(segment
		(start 86.722458 -87.826342)
		(end 87.854028 -87.826342)
		(width 0.127)
		(layer "In2.Cu")
		(net "EXP_XM_OE_N")
	)
	(segment
		(start 87.854028 -87.826342)
		(end 88.50757 -87.1728)
		(width 0.127)
		(layer "In2.Cu")
		(net "EXP_XM_OE_N")
	)
	(segment
		(start 109.405674 -87.1728)
		(end 110.853474 -85.725)
		(width 0.127)
		(layer "In2.Cu")
		(net "EXP_XM_OE_N")
	)
	(segment
		(start 110.853474 -85.725)
		(end 111.8362 -85.725)
		(width 0.127)
		(layer "In2.Cu")
		(net "EXP_XM_OE_N")
	)
	(segment
		(start 83.46186 -87.318342)
		(end 84.101432 -87.318342)
		(width 0.127)
		(layer "In2.Cu")
		(net "EXP_XM_OE_N")
	)
	(segment
		(start 83.1596 -87.0204)
		(end 83.163918 -87.0204)
		(width 0.127)
		(layer "In2.Cu")
		(net "EXP_XM_OE_N")
	)
	(segment
		(start 84.101432 -87.318342)
		(end 84.86013 -88.07704)
		(width 0.127)
		(layer "In2.Cu")
		(net "EXP_XM_OE_N")
	)
	(segment
		(start 84.86013 -88.07704)
		(end 86.47176 -88.07704)
		(width 0.127)
		(layer "In2.Cu")
		(net "EXP_XM_OE_N")
	)
	(segment
		(start 86.47176 -88.07704)
		(end 86.722458 -87.826342)
		(width 0.127)
		(layer "In2.Cu")
		(net "EXP_XM_OE_N")
	)
	(segment
		(start 86.487 -78.695042)
		(end 85.314028 -78.695042)
		(width 0.127)
		(layer "F.Cu")
		(net "EXP_XM_NOR_CS_N")
	)
	(segment
		(start 111.499904 -73.500234)
		(end 111.000032 -74.000106)
		(width 0.127)
		(layer "F.Cu")
		(net "EXP_XM_NOR_CS_N")
	)
	(via
		(at 112.8014 -87.63)
		(size 0.508)
		(drill 0.254)
		(layers "F.Cu" "B.Cu")
		(net "EXP_XM_NOR_CS_N")
	)
	(via
		(at 83.82 -87.8332)
		(size 0.508)
		(drill 0.254)
		(layers "F.Cu" "B.Cu")
		(net "EXP_XM_NOR_CS_N")
	)
	(via
		(at 85.314028 -78.695042)
		(size 0.508)
		(drill 0.254)
		(layers "F.Cu" "B.Cu")
		(net "EXP_XM_NOR_CS_N")
	)
	(via
		(at 111.000032 -74.000106)
		(size 0.4572)
		(drill 0.2032)
		(layers "F.Cu" "B.Cu")
		(net "EXP_XM_NOR_CS_N")
	)
	(segment
		(start 84.7852 -84.16798)
		(end 84.7852 -79.22387)
		(width 0.127)
		(layer "B.Cu")
		(net "EXP_XM_NOR_CS_N")
	)
	(segment
		(start 111.963962 -82.70748)
		(end 111.963962 -84.826348)
		(width 0.127)
		(layer "B.Cu")
		(net "EXP_XM_NOR_CS_N")
	)
	(segment
		(start 110.5154 -79.267304)
		(end 110.796324 -79.548228)
		(width 0.127)
		(layer "B.Cu")
		(net "EXP_XM_NOR_CS_N")
	)
	(segment
		(start 110.5154 -74.484738)
		(end 110.5154 -79.267304)
		(width 0.127)
		(layer "B.Cu")
		(net "EXP_XM_NOR_CS_N")
	)
	(segment
		(start 111.963962 -84.826348)
		(end 112.3061 -85.168486)
		(width 0.127)
		(layer "B.Cu")
		(net "EXP_XM_NOR_CS_N")
	)
	(segment
		(start 85.314028 -77.506068)
		(end 85.314028 -78.695042)
		(width 0.127)
		(layer "B.Cu")
		(net "EXP_XM_NOR_CS_N")
	)
	(segment
		(start 112.3061 -85.168486)
		(end 112.3061 -85.936328)
		(width 0.127)
		(layer "B.Cu")
		(net "EXP_XM_NOR_CS_N")
	)
	(segment
		(start 111.94796 -86.663276)
		(end 112.8014 -87.516716)
		(width 0.127)
		(layer "B.Cu")
		(net "EXP_XM_NOR_CS_N")
	)
	(segment
		(start 85.76818 -77.051916)
		(end 85.314028 -77.506068)
		(width 0.127)
		(layer "B.Cu")
		(net "EXP_XM_NOR_CS_N")
	)
	(segment
		(start 84.7852 -79.22387)
		(end 85.314028 -78.695042)
		(width 0.127)
		(layer "B.Cu")
		(net "EXP_XM_NOR_CS_N")
	)
	(segment
		(start 112.8014 -87.516716)
		(end 112.8014 -87.63)
		(width 0.127)
		(layer "B.Cu")
		(net "EXP_XM_NOR_CS_N")
	)
	(segment
		(start 111.94796 -86.294468)
		(end 111.94796 -86.663276)
		(width 0.127)
		(layer "B.Cu")
		(net "EXP_XM_NOR_CS_N")
	)
	(segment
		(start 111.257334 -79.548228)
		(end 111.59109 -79.881984)
		(width 0.127)
		(layer "B.Cu")
		(net "EXP_XM_NOR_CS_N")
	)
	(segment
		(start 111.59109 -82.334608)
		(end 111.963962 -82.70748)
		(width 0.127)
		(layer "B.Cu")
		(net "EXP_XM_NOR_CS_N")
	)
	(segment
		(start 83.82 -87.4014)
		(end 84.4042 -86.8172)
		(width 0.127)
		(layer "B.Cu")
		(net "EXP_XM_NOR_CS_N")
	)
	(segment
		(start 110.796324 -79.548228)
		(end 111.257334 -79.548228)
		(width 0.127)
		(layer "B.Cu")
		(net "EXP_XM_NOR_CS_N")
	)
	(segment
		(start 112.3061 -85.936328)
		(end 111.94796 -86.294468)
		(width 0.127)
		(layer "B.Cu")
		(net "EXP_XM_NOR_CS_N")
	)
	(segment
		(start 85.76818 -75.6031)
		(end 85.76818 -77.051916)
		(width 0.127)
		(layer "B.Cu")
		(net "EXP_XM_NOR_CS_N")
	)
	(segment
		(start 111.000032 -74.000106)
		(end 110.5154 -74.484738)
		(width 0.127)
		(layer "B.Cu")
		(net "EXP_XM_NOR_CS_N")
	)
	(segment
		(start 111.59109 -79.881984)
		(end 111.59109 -82.334608)
		(width 0.127)
		(layer "B.Cu")
		(net "EXP_XM_NOR_CS_N")
	)
	(segment
		(start 84.4042 -86.8172)
		(end 84.4042 -84.54898)
		(width 0.127)
		(layer "B.Cu")
		(net "EXP_XM_NOR_CS_N")
	)
	(segment
		(start 83.82 -87.8332)
		(end 83.82 -87.4014)
		(width 0.127)
		(layer "B.Cu")
		(net "EXP_XM_NOR_CS_N")
	)
	(segment
		(start 84.4042 -84.54898)
		(end 84.7852 -84.16798)
		(width 0.127)
		(layer "B.Cu")
		(net "EXP_XM_NOR_CS_N")
	)
	(segment
		(start 83.82 -87.8332)
		(end 85.337142 -89.350342)
		(width 0.127)
		(layer "In2.Cu")
		(net "EXP_XM_NOR_CS_N")
	)
	(segment
		(start 85.337142 -89.350342)
		(end 110.145576 -89.350342)
		(width 0.127)
		(layer "In2.Cu")
		(net "EXP_XM_NOR_CS_N")
	)
	(segment
		(start 111.865918 -87.63)
		(end 112.8014 -87.63)
		(width 0.127)
		(layer "In2.Cu")
		(net "EXP_XM_NOR_CS_N")
	)
	(segment
		(start 110.145576 -89.350342)
		(end 111.865918 -87.63)
		(width 0.127)
		(layer "In2.Cu")
		(net "EXP_XM_NOR_CS_N")
	)
	(segment
		(start 111.499904 -75.50023)
		(end 111.000032 -76.000102)
		(width 0.127)
		(layer "F.Cu")
		(net "EXP_XM_CS_N_0")
	)
	(via
		(at 112.499902 -81.499964)
		(size 0.6096)
		(drill 0.3048)
		(layers "F.Cu" "B.Cu")
		(net "EXP_XM_CS_N_0")
	)
	(via
		(at 111.000032 -76.000102)
		(size 0.4572)
		(drill 0.2032)
		(layers "F.Cu" "B.Cu")
		(net "EXP_XM_CS_N_0")
	)
	(segment
		(start 113.21415 -78.606396)
		(end 112.704626 -78.606396)
		(width 0.127)
		(layer "B.Cu")
		(net "EXP_XM_CS_N_0")
	)
	(segment
		(start 112.499902 -78.81112)
		(end 112.499902 -81.499964)
		(width 0.127)
		(layer "B.Cu")
		(net "EXP_XM_CS_N_0")
	)
	(segment
		(start 111.476028 -75.524106)
		(end 112.158272 -75.524106)
		(width 0.127)
		(layer "B.Cu")
		(net "EXP_XM_CS_N_0")
	)
	(segment
		(start 112.591088 -76.499974)
		(end 113.538 -77.446886)
		(width 0.127)
		(layer "B.Cu")
		(net "EXP_XM_CS_N_0")
	)
	(segment
		(start 113.538 -77.446886)
		(end 113.538 -78.282546)
		(width 0.127)
		(layer "B.Cu")
		(net "EXP_XM_CS_N_0")
	)
	(segment
		(start 113.1316 -84.0105)
		(end 112.9284 -83.8073)
		(width 0.127)
		(layer "B.Cu")
		(net "EXP_XM_CS_N_0")
	)
	(segment
		(start 112.9284 -83.8073)
		(end 112.9284 -82.5754)
		(width 0.127)
		(layer "B.Cu")
		(net "EXP_XM_CS_N_0")
	)
	(segment
		(start 112.704626 -78.606396)
		(end 112.499902 -78.81112)
		(width 0.127)
		(layer "B.Cu")
		(net "EXP_XM_CS_N_0")
	)
	(segment
		(start 112.9284 -82.5754)
		(end 112.499902 -82.146902)
		(width 0.127)
		(layer "B.Cu")
		(net "EXP_XM_CS_N_0")
	)
	(segment
		(start 113.538 -78.282546)
		(end 113.21415 -78.606396)
		(width 0.127)
		(layer "B.Cu")
		(net "EXP_XM_CS_N_0")
	)
	(segment
		(start 111.000032 -76.000102)
		(end 111.476028 -75.524106)
		(width 0.127)
		(layer "B.Cu")
		(net "EXP_XM_CS_N_0")
	)
	(segment
		(start 112.499902 -82.146902)
		(end 112.499902 -81.499964)
		(width 0.127)
		(layer "B.Cu")
		(net "EXP_XM_CS_N_0")
	)
	(segment
		(start 112.591088 -75.956922)
		(end 112.591088 -76.499974)
		(width 0.127)
		(layer "B.Cu")
		(net "EXP_XM_CS_N_0")
	)
	(segment
		(start 112.158272 -75.524106)
		(end 112.591088 -75.956922)
		(width 0.127)
		(layer "B.Cu")
		(net "EXP_XM_CS_N_0")
	)
	(segment
		(start 113.4999 -80.50022)
		(end 113.000028 -81.000092)
		(width 0.127)
		(layer "F.Cu")
		(net "EXP_XM_BUSY_N")
	)
	(via
		(at 81.4451 -85.459824)
		(size 0.508)
		(drill 0.254)
		(layers "F.Cu" "B.Cu")
		(net "EXP_XM_BUSY_N")
	)
	(via
		(at 113.000028 -81.000092)
		(size 0.4572)
		(drill 0.2032)
		(layers "F.Cu" "B.Cu")
		(net "EXP_XM_BUSY_N")
	)
	(segment
		(start 113.000028 -81.26349)
		(end 113.000028 -81.000092)
		(width 0.127)
		(layer "B.Cu")
		(net "EXP_XM_BUSY_N")
	)
	(segment
		(start 113.4618 -82.6516)
		(end 113.4618 -81.725262)
		(width 0.127)
		(layer "B.Cu")
		(net "EXP_XM_BUSY_N")
	)
	(segment
		(start 113.4618 -81.725262)
		(end 113.000028 -81.26349)
		(width 0.127)
		(layer "B.Cu")
		(net "EXP_XM_BUSY_N")
	)
	(segment
		(start 113.8682 -83.058)
		(end 113.4618 -82.6516)
		(width 0.127)
		(layer "B.Cu")
		(net "EXP_XM_BUSY_N")
	)
	(segment
		(start 81.424018 -92.981018)
		(end 81.424018 -93.692218)
		(width 0.127)
		(layer "B.Cu")
		(net "EXP_XM_BUSY_N")
	)
	(segment
		(start 81.424018 -93.692218)
		(end 81.76768 -94.03588)
		(width 0.127)
		(layer "B.Cu")
		(net "EXP_XM_BUSY_N")
	)
	(segment
		(start 113.8682 -83.7311)
		(end 113.8682 -83.058)
		(width 0.127)
		(layer "B.Cu")
		(net "EXP_XM_BUSY_N")
	)
	(segment
		(start 81.4451 -85.459824)
		(end 81.299812 -85.605112)
		(width 0.127)
		(layer "B.Cu")
		(net "EXP_XM_BUSY_N")
	)
	(segment
		(start 80.0862 -91.508834)
		(end 81.416652 -92.839286)
		(width 0.127)
		(layer "B.Cu")
		(net "EXP_XM_BUSY_N")
	)
	(segment
		(start 80.0862 -87.884)
		(end 80.0862 -91.508834)
		(width 0.127)
		(layer "B.Cu")
		(net "EXP_XM_BUSY_N")
	)
	(segment
		(start 114.1476 -84.0105)
		(end 113.8682 -83.7311)
		(width 0.127)
		(layer "B.Cu")
		(net "EXP_XM_BUSY_N")
	)
	(segment
		(start 81.299812 -85.605112)
		(end 81.058512 -85.605112)
		(width 0.127)
		(layer "B.Cu")
		(net "EXP_XM_BUSY_N")
	)
	(segment
		(start 81.76768 -94.03588)
		(end 81.76768 -94.8309)
		(width 0.127)
		(layer "B.Cu")
		(net "EXP_XM_BUSY_N")
	)
	(segment
		(start 81.058512 -85.605112)
		(end 80.7466 -85.917024)
		(width 0.127)
		(layer "B.Cu")
		(net "EXP_XM_BUSY_N")
	)
	(segment
		(start 81.416652 -92.839286)
		(end 81.416652 -92.973652)
		(width 0.127)
		(layer "B.Cu")
		(net "EXP_XM_BUSY_N")
	)
	(segment
		(start 80.7466 -87.2236)
		(end 80.0862 -87.884)
		(width 0.127)
		(layer "B.Cu")
		(net "EXP_XM_BUSY_N")
	)
	(segment
		(start 81.416652 -92.973652)
		(end 81.424018 -92.981018)
		(width 0.127)
		(layer "B.Cu")
		(net "EXP_XM_BUSY_N")
	)
	(segment
		(start 80.7466 -85.917024)
		(end 80.7466 -87.2236)
		(width 0.127)
		(layer "B.Cu")
		(net "EXP_XM_BUSY_N")
	)
	(segment
		(start 108.097574 -84.220812)
		(end 98.141028 -84.220812)
		(width 0.127)
		(layer "In2.Cu")
		(net "EXP_XM_BUSY_N")
	)
	(segment
		(start 88.146128 -83.941412)
		(end 86.875112 -85.212428)
		(width 0.127)
		(layer "In2.Cu")
		(net "EXP_XM_BUSY_N")
	)
	(segment
		(start 112.866932 -84.5439)
		(end 111.171228 -84.5439)
		(width 0.127)
		(layer "In2.Cu")
		(net "EXP_XM_BUSY_N")
	)
	(segment
		(start 98.141028 -84.220812)
		(end 97.861628 -83.941412)
		(width 0.127)
		(layer "In2.Cu")
		(net "EXP_XM_BUSY_N")
	)
	(segment
		(start 114.0333 -83.377532)
		(end 112.866932 -84.5439)
		(width 0.127)
		(layer "In2.Cu")
		(net "EXP_XM_BUSY_N")
	)
	(segment
		(start 113.000028 -81.000092)
		(end 113.054892 -81.000092)
		(width 0.127)
		(layer "In2.Cu")
		(net "EXP_XM_BUSY_N")
	)
	(segment
		(start 97.861628 -83.941412)
		(end 88.146128 -83.941412)
		(width 0.127)
		(layer "In2.Cu")
		(net "EXP_XM_BUSY_N")
	)
	(segment
		(start 113.054892 -81.000092)
		(end 114.0333 -81.9785)
		(width 0.127)
		(layer "In2.Cu")
		(net "EXP_XM_BUSY_N")
	)
	(segment
		(start 86.875112 -85.212428)
		(end 81.692496 -85.212428)
		(width 0.127)
		(layer "In2.Cu")
		(net "EXP_XM_BUSY_N")
	)
	(segment
		(start 110.06963 -83.442302)
		(end 108.876084 -83.442302)
		(width 0.127)
		(layer "In2.Cu")
		(net "EXP_XM_BUSY_N")
	)
	(segment
		(start 81.692496 -85.212428)
		(end 81.4451 -85.459824)
		(width 0.127)
		(layer "In2.Cu")
		(net "EXP_XM_BUSY_N")
	)
	(segment
		(start 111.171228 -84.5439)
		(end 110.06963 -83.442302)
		(width 0.127)
		(layer "In2.Cu")
		(net "EXP_XM_BUSY_N")
	)
	(segment
		(start 114.0333 -81.9785)
		(end 114.0333 -83.377532)
		(width 0.127)
		(layer "In2.Cu")
		(net "EXP_XM_BUSY_N")
	)
	(segment
		(start 108.876084 -83.442302)
		(end 108.097574 -84.220812)
		(width 0.127)
		(layer "In2.Cu")
		(net "EXP_XM_BUSY_N")
	)
	(segment
		(start 113.4999 -79.500222)
		(end 113.000028 -80.000094)
		(width 0.127)
		(layer "F.Cu")
		(net "EXP_XM_ADDR_9")
	)
	(via
		(at 76.581 -85.725)
		(size 0.508)
		(drill 0.254)
		(layers "F.Cu" "B.Cu")
		(net "EXP_XM_ADDR_9")
	)
	(via
		(at 113.000028 -80.000094)
		(size 0.4572)
		(drill 0.2032)
		(layers "F.Cu" "B.Cu")
		(net "EXP_XM_ADDR_9")
	)
	(segment
		(start 77.089 -89.2302)
		(end 77.216 -89.3572)
		(width 0.127)
		(layer "B.Cu")
		(net "EXP_XM_ADDR_9")
	)
	(segment
		(start 75.987148 -92.7608)
		(end 75.860148 -92.6338)
		(width 0.127)
		(layer "B.Cu")
		(net "EXP_XM_ADDR_9")
	)
	(segment
		(start 76.749148 -89.9668)
		(end 76.495148 -89.9668)
		(width 0.127)
		(layer "B.Cu")
		(net "EXP_XM_ADDR_9")
	)
	(segment
		(start 77.089 -87.742014)
		(end 77.089 -89.2302)
		(width 0.127)
		(layer "B.Cu")
		(net "EXP_XM_ADDR_9")
	)
	(segment
		(start 77.597 -87.234014)
		(end 76.581 -86.218014)
		(width 0.127)
		(layer "B.Cu")
		(net "EXP_XM_ADDR_9")
	)
	(segment
		(start 76.368148 -90.0938)
		(end 76.368148 -92.6338)
		(width 0.127)
		(layer "B.Cu")
		(net "EXP_XM_ADDR_9")
	)
	(segment
		(start 77.597 -89.2302)
		(end 77.597 -87.234014)
		(width 0.127)
		(layer "B.Cu")
		(net "EXP_XM_ADDR_9")
	)
	(segment
		(start 76.876148 -90.0938)
		(end 76.749148 -89.9668)
		(width 0.127)
		(layer "B.Cu")
		(net "EXP_XM_ADDR_9")
	)
	(segment
		(start 76.241148 -92.7608)
		(end 75.987148 -92.7608)
		(width 0.127)
		(layer "B.Cu")
		(net "EXP_XM_ADDR_9")
	)
	(segment
		(start 76.962 -87.615014)
		(end 77.089 -87.742014)
		(width 0.127)
		(layer "B.Cu")
		(net "EXP_XM_ADDR_9")
	)
	(segment
		(start 75.860148 -89.824052)
		(end 76.581 -89.1032)
		(width 0.127)
		(layer "B.Cu")
		(net "EXP_XM_ADDR_9")
	)
	(segment
		(start 75.860148 -92.6338)
		(end 75.860148 -89.824052)
		(width 0.127)
		(layer "B.Cu")
		(net "EXP_XM_ADDR_9")
	)
	(segment
		(start 76.581 -89.1032)
		(end 76.581 -87.742014)
		(width 0.127)
		(layer "B.Cu")
		(net "EXP_XM_ADDR_9")
	)
	(segment
		(start 76.581 -86.218014)
		(end 76.581 -85.725)
		(width 0.127)
		(layer "B.Cu")
		(net "EXP_XM_ADDR_9")
	)
	(segment
		(start 76.708 -87.615014)
		(end 76.962 -87.615014)
		(width 0.127)
		(layer "B.Cu")
		(net "EXP_XM_ADDR_9")
	)
	(segment
		(start 78.26756 -93.775784)
		(end 76.876148 -92.384372)
		(width 0.127)
		(layer "B.Cu")
		(net "EXP_XM_ADDR_9")
	)
	(segment
		(start 78.26756 -94.8309)
		(end 78.26756 -93.775784)
		(width 0.127)
		(layer "B.Cu")
		(net "EXP_XM_ADDR_9")
	)
	(segment
		(start 76.581 -87.742014)
		(end 76.708 -87.615014)
		(width 0.127)
		(layer "B.Cu")
		(net "EXP_XM_ADDR_9")
	)
	(segment
		(start 76.368148 -92.6338)
		(end 76.241148 -92.7608)
		(width 0.127)
		(layer "B.Cu")
		(net "EXP_XM_ADDR_9")
	)
	(segment
		(start 77.216 -89.3572)
		(end 77.47 -89.3572)
		(width 0.127)
		(layer "B.Cu")
		(net "EXP_XM_ADDR_9")
	)
	(segment
		(start 76.876148 -92.384372)
		(end 76.876148 -90.0938)
		(width 0.127)
		(layer "B.Cu")
		(net "EXP_XM_ADDR_9")
	)
	(segment
		(start 76.495148 -89.9668)
		(end 76.368148 -90.0938)
		(width 0.127)
		(layer "B.Cu")
		(net "EXP_XM_ADDR_9")
	)
	(segment
		(start 77.47 -89.3572)
		(end 77.597 -89.2302)
		(width 0.127)
		(layer "B.Cu")
		(net "EXP_XM_ADDR_9")
	)
	(segment
		(start 106.511344 -85.0519)
		(end 113.077752 -85.0519)
		(width 0.127)
		(layer "In2.Cu")
		(net "EXP_XM_ADDR_9")
	)
	(segment
		(start 80.39989 -85.817456)
		(end 81.025492 -86.443058)
		(width 0.127)
		(layer "In2.Cu")
		(net "EXP_XM_ADDR_9")
	)
	(segment
		(start 77.254354 -83.0834)
		(end 77.254354 -85.940646)
		(width 0.127)
		(layer "In2.Cu")
		(net "EXP_XM_ADDR_9")
	)
	(segment
		(start 105.895648 -85.667596)
		(end 106.511344 -85.0519)
		(width 0.127)
		(layer "In2.Cu")
		(net "EXP_XM_ADDR_9")
	)
	(segment
		(start 114.4016 -81.610454)
		(end 114.4016 -80.844644)
		(width 0.127)
		(layer "In2.Cu")
		(net "EXP_XM_ADDR_9")
	)
	(segment
		(start 76.6572 -83.0834)
		(end 76.7842 -82.9564)
		(width 0.127)
		(layer "In2.Cu")
		(net "EXP_XM_ADDR_9")
	)
	(segment
		(start 113.606326 -80.606392)
		(end 113.000028 -80.000094)
		(width 0.127)
		(layer "In2.Cu")
		(net "EXP_XM_ADDR_9")
	)
	(segment
		(start 85.375496 -87.3252)
		(end 85.375496 -86.937342)
		(width 0.127)
		(layer "In2.Cu")
		(net "EXP_XM_ADDR_9")
	)
	(segment
		(start 76.6572 -84.8868)
		(end 76.6572 -83.0834)
		(width 0.127)
		(layer "In2.Cu")
		(net "EXP_XM_ADDR_9")
	)
	(segment
		(start 84.994496 -87.4522)
		(end 85.248496 -87.4522)
		(width 0.127)
		(layer "In2.Cu")
		(net "EXP_XM_ADDR_9")
	)
	(segment
		(start 75.565 -85.598)
		(end 75.565 -83.1088)
		(width 0.127)
		(layer "In2.Cu")
		(net "EXP_XM_ADDR_9")
	)
	(segment
		(start 88.086438 -86.1568)
		(end 102.362 -86.1568)
		(width 0.127)
		(layer "In2.Cu")
		(net "EXP_XM_ADDR_9")
	)
	(segment
		(start 85.502496 -86.810342)
		(end 87.432896 -86.810342)
		(width 0.127)
		(layer "In2.Cu")
		(net "EXP_XM_ADDR_9")
	)
	(segment
		(start 76.5302 -85.0138)
		(end 76.6572 -84.8868)
		(width 0.127)
		(layer "In2.Cu")
		(net "EXP_XM_ADDR_9")
	)
	(segment
		(start 84.867496 -86.937342)
		(end 84.867496 -87.3252)
		(width 0.127)
		(layer "In2.Cu")
		(net "EXP_XM_ADDR_9")
	)
	(segment
		(start 102.362 -86.1568)
		(end 102.851204 -85.667596)
		(width 0.127)
		(layer "In2.Cu")
		(net "EXP_XM_ADDR_9")
	)
	(segment
		(start 76.1492 -84.8868)
		(end 76.2762 -85.0138)
		(width 0.127)
		(layer "In2.Cu")
		(net "EXP_XM_ADDR_9")
	)
	(segment
		(start 84.867496 -87.3252)
		(end 84.994496 -87.4522)
		(width 0.127)
		(layer "In2.Cu")
		(net "EXP_XM_ADDR_9")
	)
	(segment
		(start 77.756766 -86.443058)
		(end 78.816708 -86.443058)
		(width 0.127)
		(layer "In2.Cu")
		(net "EXP_XM_ADDR_9")
	)
	(segment
		(start 83.672426 -86.810342)
		(end 84.740496 -86.810342)
		(width 0.127)
		(layer "In2.Cu")
		(net "EXP_XM_ADDR_9")
	)
	(segment
		(start 114.5413 -81.750154)
		(end 114.4016 -81.610454)
		(width 0.127)
		(layer "In2.Cu")
		(net "EXP_XM_ADDR_9")
	)
	(segment
		(start 113.077752 -85.0519)
		(end 114.5413 -83.588352)
		(width 0.127)
		(layer "In2.Cu")
		(net "EXP_XM_ADDR_9")
	)
	(segment
		(start 79.44231 -85.817456)
		(end 80.39989 -85.817456)
		(width 0.127)
		(layer "In2.Cu")
		(net "EXP_XM_ADDR_9")
	)
	(segment
		(start 85.248496 -87.4522)
		(end 85.375496 -87.3252)
		(width 0.127)
		(layer "In2.Cu")
		(net "EXP_XM_ADDR_9")
	)
	(segment
		(start 77.127354 -82.9564)
		(end 77.254354 -83.0834)
		(width 0.127)
		(layer "In2.Cu")
		(net "EXP_XM_ADDR_9")
	)
	(segment
		(start 114.5413 -83.588352)
		(end 114.5413 -81.750154)
		(width 0.127)
		(layer "In2.Cu")
		(net "EXP_XM_ADDR_9")
	)
	(segment
		(start 83.305142 -86.443058)
		(end 83.672426 -86.810342)
		(width 0.127)
		(layer "In2.Cu")
		(net "EXP_XM_ADDR_9")
	)
	(segment
		(start 75.565 -83.1088)
		(end 75.692 -82.9818)
		(width 0.127)
		(layer "In2.Cu")
		(net "EXP_XM_ADDR_9")
	)
	(segment
		(start 84.740496 -86.810342)
		(end 84.867496 -86.937342)
		(width 0.127)
		(layer "In2.Cu")
		(net "EXP_XM_ADDR_9")
	)
	(segment
		(start 102.851204 -85.667596)
		(end 105.895648 -85.667596)
		(width 0.127)
		(layer "In2.Cu")
		(net "EXP_XM_ADDR_9")
	)
	(segment
		(start 76.1492 -83.1088)
		(end 76.1492 -84.8868)
		(width 0.127)
		(layer "In2.Cu")
		(net "EXP_XM_ADDR_9")
	)
	(segment
		(start 75.692 -85.725)
		(end 75.565 -85.598)
		(width 0.127)
		(layer "In2.Cu")
		(net "EXP_XM_ADDR_9")
	)
	(segment
		(start 87.432896 -86.810342)
		(end 88.086438 -86.1568)
		(width 0.127)
		(layer "In2.Cu")
		(net "EXP_XM_ADDR_9")
	)
	(segment
		(start 85.375496 -86.937342)
		(end 85.502496 -86.810342)
		(width 0.127)
		(layer "In2.Cu")
		(net "EXP_XM_ADDR_9")
	)
	(segment
		(start 81.025492 -86.443058)
		(end 83.305142 -86.443058)
		(width 0.127)
		(layer "In2.Cu")
		(net "EXP_XM_ADDR_9")
	)
	(segment
		(start 76.2762 -85.0138)
		(end 76.5302 -85.0138)
		(width 0.127)
		(layer "In2.Cu")
		(net "EXP_XM_ADDR_9")
	)
	(segment
		(start 75.692 -82.9818)
		(end 76.0222 -82.9818)
		(width 0.127)
		(layer "In2.Cu")
		(net "EXP_XM_ADDR_9")
	)
	(segment
		(start 76.0222 -82.9818)
		(end 76.1492 -83.1088)
		(width 0.127)
		(layer "In2.Cu")
		(net "EXP_XM_ADDR_9")
	)
	(segment
		(start 76.7842 -82.9564)
		(end 77.127354 -82.9564)
		(width 0.127)
		(layer "In2.Cu")
		(net "EXP_XM_ADDR_9")
	)
	(segment
		(start 114.163348 -80.606392)
		(end 113.606326 -80.606392)
		(width 0.127)
		(layer "In2.Cu")
		(net "EXP_XM_ADDR_9")
	)
	(segment
		(start 114.4016 -80.844644)
		(end 114.163348 -80.606392)
		(width 0.127)
		(layer "In2.Cu")
		(net "EXP_XM_ADDR_9")
	)
	(segment
		(start 78.816708 -86.443058)
		(end 79.44231 -85.817456)
		(width 0.127)
		(layer "In2.Cu")
		(net "EXP_XM_ADDR_9")
	)
	(segment
		(start 77.254354 -85.940646)
		(end 77.756766 -86.443058)
		(width 0.127)
		(layer "In2.Cu")
		(net "EXP_XM_ADDR_9")
	)
	(segment
		(start 76.581 -85.725)
		(end 75.692 -85.725)
		(width 0.127)
		(layer "In2.Cu")
		(net "EXP_XM_ADDR_9")
	)
	(segment
		(start 113.4999 -77.500226)
		(end 113.999772 -77.000354)
		(width 0.127)
		(layer "F.Cu")
		(net "EXP_XM_ADDR_8")
	)
	(via
		(at 81.915 -89.8398)
		(size 0.508)
		(drill 0.254)
		(layers "F.Cu" "B.Cu")
		(net "EXP_XM_ADDR_8")
	)
	(via
		(at 113.999772 -77.000354)
		(size 0.4572)
		(drill 0.2032)
		(layers "F.Cu" "B.Cu")
		(net "EXP_XM_ADDR_8")
	)
	(segment
		(start 82.698082 -89.834974)
		(end 82.877406 -89.834974)
		(width 0.127)
		(layer "B.Cu")
		(net "EXP_XM_ADDR_8")
	)
	(segment
		(start 83.3628 -84.994496)
		(end 83.3628 -85.248496)
		(width 0.127)
		(layer "B.Cu")
		(net "EXP_XM_ADDR_8")
	)
	(segment
		(start 83.73618 -93.472508)
		(end 83.26755 -93.941138)
		(width 0.127)
		(layer "B.Cu")
		(net "EXP_XM_ADDR_8")
	)
	(segment
		(start 81.661 -83.4644)
		(end 81.0768 -83.4644)
		(width 0.127)
		(layer "B.Cu")
		(net "EXP_XM_ADDR_8")
	)
	(segment
		(start 80.9498 -83.3374)
		(end 80.9498 -82.9818)
		(width 0.127)
		(layer "B.Cu")
		(net "EXP_XM_ADDR_8")
	)
	(segment
		(start 81.3816 -87.170514)
		(end 81.788 -87.170514)
		(width 0.127)
		(layer "B.Cu")
		(net "EXP_XM_ADDR_8")
	)
	(segment
		(start 81.915 -86.027514)
		(end 81.915 -85.1916)
		(width 0.127)
		(layer "B.Cu")
		(net "EXP_XM_ADDR_8")
	)
	(segment
		(start 80.5688 -84.481924)
		(end 81.8388 -84.481924)
		(width 0.127)
		(layer "B.Cu")
		(net "EXP_XM_ADDR_8")
	)
	(segment
		(start 82.6516 -83.4644)
		(end 82.6516 -84.740496)
		(width 0.127)
		(layer "B.Cu")
		(net "EXP_XM_ADDR_8")
	)
	(segment
		(start 82.877406 -89.834974)
		(end 83.290918 -89.421208)
		(width 0.127)
		(layer "B.Cu")
		(net "EXP_XM_ADDR_8")
	)
	(segment
		(start 83.470242 -89.421208)
		(end 83.73618 -89.687146)
		(width 0.127)
		(layer "B.Cu")
		(net "EXP_XM_ADDR_8")
	)
	(segment
		(start 82.6516 -85.756496)
		(end 82.7786 -85.883496)
		(width 0.127)
		(layer "B.Cu")
		(net "EXP_XM_ADDR_8")
	)
	(segment
		(start 81.915 -87.043514)
		(end 81.915 -86.789514)
		(width 0.127)
		(layer "B.Cu")
		(net "EXP_XM_ADDR_8")
	)
	(segment
		(start 81.0768 -82.8548)
		(end 82.042 -82.8548)
		(width 0.127)
		(layer "B.Cu")
		(net "EXP_XM_ADDR_8")
	)
	(segment
		(start 81.915 -89.8398)
		(end 81.915 -87.805514)
		(width 0.127)
		(layer "B.Cu")
		(net "EXP_XM_ADDR_8")
	)
	(segment
		(start 81.915 -87.805514)
		(end 81.788 -87.678514)
		(width 0.127)
		(layer "B.Cu")
		(net "EXP_XM_ADDR_8")
	)
	(segment
		(start 81.915 -84.405724)
		(end 81.915 -83.7184)
		(width 0.127)
		(layer "B.Cu")
		(net "EXP_XM_ADDR_8")
	)
	(segment
		(start 81.2546 -86.535514)
		(end 81.2546 -86.281514)
		(width 0.127)
		(layer "B.Cu")
		(net "EXP_XM_ADDR_8")
	)
	(segment
		(start 83.2358 -86.391496)
		(end 82.7786 -86.391496)
		(width 0.127)
		(layer "B.Cu")
		(net "EXP_XM_ADDR_8")
	)
	(segment
		(start 81.788 -87.170514)
		(end 81.915 -87.043514)
		(width 0.127)
		(layer "B.Cu")
		(net "EXP_XM_ADDR_8")
	)
	(segment
		(start 82.517996 -89.475564)
		(end 82.517996 -89.654888)
		(width 0.127)
		(layer "B.Cu")
		(net "EXP_XM_ADDR_8")
	)
	(segment
		(start 81.915 -83.7184)
		(end 81.661 -83.4644)
		(width 0.127)
		(layer "B.Cu")
		(net "EXP_XM_ADDR_8")
	)
	(segment
		(start 81.0768 -83.4644)
		(end 80.9498 -83.3374)
		(width 0.127)
		(layer "B.Cu")
		(net "EXP_XM_ADDR_8")
	)
	(segment
		(start 81.788 -86.662514)
		(end 81.3816 -86.662514)
		(width 0.127)
		(layer "B.Cu")
		(net "EXP_XM_ADDR_8")
	)
	(segment
		(start 81.2546 -87.551514)
		(end 81.2546 -87.297514)
		(width 0.127)
		(layer "B.Cu")
		(net "EXP_XM_ADDR_8")
	)
	(segment
		(start 81.2546 -86.281514)
		(end 81.3816 -86.154514)
		(width 0.127)
		(layer "B.Cu")
		(net "EXP_XM_ADDR_8")
	)
	(segment
		(start 83.3628 -85.248496)
		(end 83.2358 -85.375496)
		(width 0.127)
		(layer "B.Cu")
		(net "EXP_XM_ADDR_8")
	)
	(segment
		(start 83.3628 -86.010496)
		(end 83.3628 -86.264496)
		(width 0.127)
		(layer "B.Cu")
		(net "EXP_XM_ADDR_8")
	)
	(segment
		(start 81.3816 -86.154514)
		(end 81.788 -86.154514)
		(width 0.127)
		(layer "B.Cu")
		(net "EXP_XM_ADDR_8")
	)
	(segment
		(start 80.4418 -84.608924)
		(end 80.5688 -84.481924)
		(width 0.127)
		(layer "B.Cu")
		(net "EXP_XM_ADDR_8")
	)
	(segment
		(start 82.6516 -86.518496)
		(end 82.6516 -88.602566)
		(width 0.127)
		(layer "B.Cu")
		(net "EXP_XM_ADDR_8")
	)
	(segment
		(start 83.290918 -89.421208)
		(end 83.470242 -89.421208)
		(width 0.127)
		(layer "B.Cu")
		(net "EXP_XM_ADDR_8")
	)
	(segment
		(start 82.042 -82.8548)
		(end 82.6516 -83.4644)
		(width 0.127)
		(layer "B.Cu")
		(net "EXP_XM_ADDR_8")
	)
	(segment
		(start 83.2358 -85.883496)
		(end 83.3628 -86.010496)
		(width 0.127)
		(layer "B.Cu")
		(net "EXP_XM_ADDR_8")
	)
	(segment
		(start 82.931508 -88.882474)
		(end 82.931508 -89.061798)
		(width 0.127)
		(layer "B.Cu")
		(net "EXP_XM_ADDR_8")
	)
	(segment
		(start 81.915 -86.789514)
		(end 81.788 -86.662514)
		(width 0.127)
		(layer "B.Cu")
		(net "EXP_XM_ADDR_8")
	)
	(segment
		(start 82.7786 -85.375496)
		(end 82.6516 -85.502496)
		(width 0.127)
		(layer "B.Cu")
		(net "EXP_XM_ADDR_8")
	)
	(segment
		(start 81.788 -86.154514)
		(end 81.915 -86.027514)
		(width 0.127)
		(layer "B.Cu")
		(net "EXP_XM_ADDR_8")
	)
	(segment
		(start 83.2358 -84.867496)
		(end 83.3628 -84.994496)
		(width 0.127)
		(layer "B.Cu")
		(net "EXP_XM_ADDR_8")
	)
	(segment
		(start 82.7786 -84.867496)
		(end 83.2358 -84.867496)
		(width 0.127)
		(layer "B.Cu")
		(net "EXP_XM_ADDR_8")
	)
	(segment
		(start 81.3816 -87.678514)
		(end 81.2546 -87.551514)
		(width 0.127)
		(layer "B.Cu")
		(net "EXP_XM_ADDR_8")
	)
	(segment
		(start 82.7786 -86.391496)
		(end 82.6516 -86.518496)
		(width 0.127)
		(layer "B.Cu")
		(net "EXP_XM_ADDR_8")
	)
	(segment
		(start 82.7786 -85.883496)
		(end 83.2358 -85.883496)
		(width 0.127)
		(layer "B.Cu")
		(net "EXP_XM_ADDR_8")
	)
	(segment
		(start 82.6516 -88.602566)
		(end 82.931508 -88.882474)
		(width 0.127)
		(layer "B.Cu")
		(net "EXP_XM_ADDR_8")
	)
	(segment
		(start 81.3816 -86.662514)
		(end 81.2546 -86.535514)
		(width 0.127)
		(layer "B.Cu")
		(net "EXP_XM_ADDR_8")
	)
	(segment
		(start 81.915 -85.1916)
		(end 81.713324 -84.989924)
		(width 0.127)
		(layer "B.Cu")
		(net "EXP_XM_ADDR_8")
	)
	(segment
		(start 81.788 -87.678514)
		(end 81.3816 -87.678514)
		(width 0.127)
		(layer "B.Cu")
		(net "EXP_XM_ADDR_8")
	)
	(segment
		(start 80.9498 -82.9818)
		(end 81.0768 -82.8548)
		(width 0.127)
		(layer "B.Cu")
		(net "EXP_XM_ADDR_8")
	)
	(segment
		(start 81.8388 -84.481924)
		(end 81.915 -84.405724)
		(width 0.127)
		(layer "B.Cu")
		(net "EXP_XM_ADDR_8")
	)
	(segment
		(start 81.713324 -84.989924)
		(end 80.5688 -84.989924)
		(width 0.127)
		(layer "B.Cu")
		(net "EXP_XM_ADDR_8")
	)
	(segment
		(start 83.2358 -85.375496)
		(end 82.7786 -85.375496)
		(width 0.127)
		(layer "B.Cu")
		(net "EXP_XM_ADDR_8")
	)
	(segment
		(start 82.6516 -85.502496)
		(end 82.6516 -85.756496)
		(width 0.127)
		(layer "B.Cu")
		(net "EXP_XM_ADDR_8")
	)
	(segment
		(start 83.3628 -86.264496)
		(end 83.2358 -86.391496)
		(width 0.127)
		(layer "B.Cu")
		(net "EXP_XM_ADDR_8")
	)
	(segment
		(start 82.6516 -84.740496)
		(end 82.7786 -84.867496)
		(width 0.127)
		(layer "B.Cu")
		(net "EXP_XM_ADDR_8")
	)
	(segment
		(start 80.4418 -84.862924)
		(end 80.4418 -84.608924)
		(width 0.127)
		(layer "B.Cu")
		(net "EXP_XM_ADDR_8")
	)
	(segment
		(start 83.73618 -89.687146)
		(end 83.73618 -93.472508)
		(width 0.127)
		(layer "B.Cu")
		(net "EXP_XM_ADDR_8")
	)
	(segment
		(start 82.517996 -89.654888)
		(end 82.698082 -89.834974)
		(width 0.127)
		(layer "B.Cu")
		(net "EXP_XM_ADDR_8")
	)
	(segment
		(start 80.5688 -84.989924)
		(end 80.4418 -84.862924)
		(width 0.127)
		(layer "B.Cu")
		(net "EXP_XM_ADDR_8")
	)
	(segment
		(start 82.931508 -89.061798)
		(end 82.517996 -89.475564)
		(width 0.127)
		(layer "B.Cu")
		(net "EXP_XM_ADDR_8")
	)
	(segment
		(start 83.26755 -93.941138)
		(end 83.26755 -94.8309)
		(width 0.127)
		(layer "B.Cu")
		(net "EXP_XM_ADDR_8")
	)
	(segment
		(start 81.2546 -87.297514)
		(end 81.3816 -87.170514)
		(width 0.127)
		(layer "B.Cu")
		(net "EXP_XM_ADDR_8")
	)
	(segment
		(start 112.642142 -90.927174)
		(end 84.696808 -90.927174)
		(width 0.127)
		(layer "In2.Cu")
		(net "EXP_XM_ADDR_8")
	)
	(segment
		(start 82.042 -88.9)
		(end 81.915 -89.027)
		(width 0.127)
		(layer "In2.Cu")
		(net "EXP_XM_ADDR_8")
	)
	(segment
		(start 82.713576 -89.8398)
		(end 82.586576 -89.7128)
		(width 0.127)
		(layer "In2.Cu")
		(net "EXP_XM_ADDR_8")
	)
	(segment
		(start 114.560858 -78.207362)
		(end 115.0112 -78.657704)
		(width 0.127)
		(layer "In2.Cu")
		(net "EXP_XM_ADDR_8")
	)
	(segment
		(start 115.1636 -81.1784)
		(end 115.4303 -81.4451)
		(width 0.127)
		(layer "In2.Cu")
		(net "EXP_XM_ADDR_8")
	)
	(segment
		(start 82.586576 -89.027)
		(end 82.459576 -88.9)
		(width 0.127)
		(layer "In2.Cu")
		(net "EXP_XM_ADDR_8")
	)
	(segment
		(start 81.915 -89.027)
		(end 81.915 -89.8398)
		(width 0.127)
		(layer "In2.Cu")
		(net "EXP_XM_ADDR_8")
	)
	(segment
		(start 82.586576 -89.7128)
		(end 82.586576 -89.027)
		(width 0.127)
		(layer "In2.Cu")
		(net "EXP_XM_ADDR_8")
	)
	(segment
		(start 82.459576 -88.9)
		(end 82.042 -88.9)
		(width 0.127)
		(layer "In2.Cu")
		(net "EXP_XM_ADDR_8")
	)
	(segment
		(start 115.0112 -78.657704)
		(end 115.0112 -80.376014)
		(width 0.127)
		(layer "In2.Cu")
		(net "EXP_XM_ADDR_8")
	)
	(segment
		(start 114.3762 -85.514434)
		(end 114.3762 -89.193116)
		(width 0.127)
		(layer "In2.Cu")
		(net "EXP_XM_ADDR_8")
	)
	(segment
		(start 83.609434 -89.8398)
		(end 82.713576 -89.8398)
		(width 0.127)
		(layer "In2.Cu")
		(net "EXP_XM_ADDR_8")
	)
	(segment
		(start 114.560858 -77.56144)
		(end 114.560858 -78.207362)
		(width 0.127)
		(layer "In2.Cu")
		(net "EXP_XM_ADDR_8")
	)
	(segment
		(start 115.1636 -80.528414)
		(end 115.1636 -81.1784)
		(width 0.127)
		(layer "In2.Cu")
		(net "EXP_XM_ADDR_8")
	)
	(segment
		(start 115.4303 -84.6963)
		(end 114.909854 -85.216746)
		(width 0.127)
		(layer "In2.Cu")
		(net "EXP_XM_ADDR_8")
	)
	(segment
		(start 115.0112 -80.376014)
		(end 115.1636 -80.528414)
		(width 0.127)
		(layer "In2.Cu")
		(net "EXP_XM_ADDR_8")
	)
	(segment
		(start 115.4303 -81.4451)
		(end 115.4303 -84.6963)
		(width 0.127)
		(layer "In2.Cu")
		(net "EXP_XM_ADDR_8")
	)
	(segment
		(start 114.673888 -85.216746)
		(end 114.3762 -85.514434)
		(width 0.127)
		(layer "In2.Cu")
		(net "EXP_XM_ADDR_8")
	)
	(segment
		(start 114.909854 -85.216746)
		(end 114.673888 -85.216746)
		(width 0.127)
		(layer "In2.Cu")
		(net "EXP_XM_ADDR_8")
	)
	(segment
		(start 113.999772 -77.000354)
		(end 114.560858 -77.56144)
		(width 0.127)
		(layer "In2.Cu")
		(net "EXP_XM_ADDR_8")
	)
	(segment
		(start 84.696808 -90.927174)
		(end 83.609434 -89.8398)
		(width 0.127)
		(layer "In2.Cu")
		(net "EXP_XM_ADDR_8")
	)
	(segment
		(start 114.3762 -89.193116)
		(end 112.642142 -90.927174)
		(width 0.127)
		(layer "In2.Cu")
		(net "EXP_XM_ADDR_8")
	)
	(segment
		(start 113.4999 -78.500224)
		(end 113.999772 -79.000096)
		(width 0.127)
		(layer "F.Cu")
		(net "EXP_XM_ADDR_7")
	)
	(via
		(at 86.106 -87.5538)
		(size 0.508)
		(drill 0.254)
		(layers "F.Cu" "B.Cu")
		(net "EXP_XM_ADDR_7")
	)
	(via
		(at 113.999772 -79.000096)
		(size 0.4572)
		(drill 0.2032)
		(layers "F.Cu" "B.Cu")
		(net "EXP_XM_ADDR_7")
	)
	(segment
		(start 90.551 -86.7664)
		(end 93.6752 -89.8906)
		(width 0.127)
		(layer "B.Cu")
		(net "EXP_XM_ADDR_7")
	)
	(segment
		(start 92.8878 -90.551)
		(end 89.6366 -87.2998)
		(width 0.127)
		(layer "B.Cu")
		(net "EXP_XM_ADDR_7")
	)
	(segment
		(start 84.24418 -93.683074)
		(end 84.24418 -88.151462)
		(width 0.127)
		(layer "B.Cu")
		(net "EXP_XM_ADDR_7")
	)
	(segment
		(start 93.6752 -95.9866)
		(end 93.5482 -96.1136)
		(width 0.127)
		(layer "B.Cu")
		(net "EXP_XM_ADDR_7")
	)
	(segment
		(start 93.6752 -89.8906)
		(end 93.6752 -95.9866)
		(width 0.127)
		(layer "B.Cu")
		(net "EXP_XM_ADDR_7")
	)
	(segment
		(start 89.6366 -87.2998)
		(end 86.36 -87.2998)
		(width 0.127)
		(layer "B.Cu")
		(net "EXP_XM_ADDR_7")
	)
	(segment
		(start 84.458048 -87.937848)
		(end 85.629496 -86.7664)
		(width 0.127)
		(layer "B.Cu")
		(net "EXP_XM_ADDR_7")
	)
	(segment
		(start 85.629496 -86.7664)
		(end 90.551 -86.7664)
		(width 0.127)
		(layer "B.Cu")
		(net "EXP_XM_ADDR_7")
	)
	(segment
		(start 86.36 -87.2998)
		(end 86.106 -87.5538)
		(width 0.127)
		(layer "B.Cu")
		(net "EXP_XM_ADDR_7")
	)
	(segment
		(start 93.5482 -96.1136)
		(end 93.0148 -96.1136)
		(width 0.127)
		(layer "B.Cu")
		(net "EXP_XM_ADDR_7")
	)
	(segment
		(start 83.76793 -94.159324)
		(end 84.24418 -93.683074)
		(width 0.127)
		(layer "B.Cu")
		(net "EXP_XM_ADDR_7")
	)
	(segment
		(start 93.0148 -96.1136)
		(end 92.8878 -95.9866)
		(width 0.127)
		(layer "B.Cu")
		(net "EXP_XM_ADDR_7")
	)
	(segment
		(start 83.76793 -94.8309)
		(end 83.76793 -94.159324)
		(width 0.127)
		(layer "B.Cu")
		(net "EXP_XM_ADDR_7")
	)
	(segment
		(start 84.24418 -88.151462)
		(end 84.458048 -87.937848)
		(width 0.127)
		(layer "B.Cu")
		(net "EXP_XM_ADDR_7")
	)
	(segment
		(start 92.8878 -95.9866)
		(end 92.8878 -90.551)
		(width 0.127)
		(layer "B.Cu")
		(net "EXP_XM_ADDR_7")
	)
	(segment
		(start 107.38358 -86.6648)
		(end 107.25658 -86.5378)
		(width 0.127)
		(layer "In2.Cu")
		(net "EXP_XM_ADDR_7")
	)
	(segment
		(start 113.183162 -85.3059)
		(end 109.80928 -85.3059)
		(width 0.127)
		(layer "In2.Cu")
		(net "EXP_XM_ADDR_7")
	)
	(segment
		(start 105.35158 -86.6648)
		(end 105.22458 -86.5378)
		(width 0.127)
		(layer "In2.Cu")
		(net "EXP_XM_ADDR_7")
	)
	(segment
		(start 107.76458 -86.1568)
		(end 107.76458 -86.5378)
		(width 0.127)
		(layer "In2.Cu")
		(net "EXP_XM_ADDR_7")
	)
	(segment
		(start 114.6556 -81.4832)
		(end 114.7953 -81.6229)
		(width 0.127)
		(layer "In2.Cu")
		(net "EXP_XM_ADDR_7")
	)
	(segment
		(start 114.427 -80.510634)
		(end 114.6556 -80.739234)
		(width 0.127)
		(layer "In2.Cu")
		(net "EXP_XM_ADDR_7")
	)
	(segment
		(start 104.20858 -86.5378)
		(end 104.20858 -86.3346)
		(width 0.127)
		(layer "In2.Cu")
		(net "EXP_XM_ADDR_7")
	)
	(segment
		(start 103.57358 -86.6648)
		(end 88.297004 -86.6648)
		(width 0.127)
		(layer "In2.Cu")
		(net "EXP_XM_ADDR_7")
	)
	(segment
		(start 88.297004 -86.6648)
		(end 87.643462 -87.318342)
		(width 0.127)
		(layer "In2.Cu")
		(net "EXP_XM_ADDR_7")
	)
	(segment
		(start 114.6556 -80.739234)
		(end 114.6556 -81.4832)
		(width 0.127)
		(layer "In2.Cu")
		(net "EXP_XM_ADDR_7")
	)
	(segment
		(start 107.76458 -86.5378)
		(end 107.63758 -86.6648)
		(width 0.127)
		(layer "In2.Cu")
		(net "EXP_XM_ADDR_7")
	)
	(segment
		(start 106.24058 -86.3346)
		(end 106.11358 -86.2076)
		(width 0.127)
		(layer "In2.Cu")
		(net "EXP_XM_ADDR_7")
	)
	(segment
		(start 104.71658 -86.5378)
		(end 104.58958 -86.6648)
		(width 0.127)
		(layer "In2.Cu")
		(net "EXP_XM_ADDR_7")
	)
	(segment
		(start 113.999772 -79.000096)
		(end 114.427 -79.427324)
		(width 0.127)
		(layer "In2.Cu")
		(net "EXP_XM_ADDR_7")
	)
	(segment
		(start 106.36758 -86.6648)
		(end 106.24058 -86.5378)
		(width 0.127)
		(layer "In2.Cu")
		(net "EXP_XM_ADDR_7")
	)
	(segment
		(start 107.25658 -86.3346)
		(end 107.12958 -86.2076)
		(width 0.127)
		(layer "In2.Cu")
		(net "EXP_XM_ADDR_7")
	)
	(segment
		(start 108.39958 -86.6648)
		(end 108.27258 -86.5378)
		(width 0.127)
		(layer "In2.Cu")
		(net "EXP_XM_ADDR_7")
	)
	(segment
		(start 86.341458 -87.318342)
		(end 86.106 -87.5538)
		(width 0.127)
		(layer "In2.Cu")
		(net "EXP_XM_ADDR_7")
	)
	(segment
		(start 104.20858 -86.3346)
		(end 104.08158 -86.2076)
		(width 0.127)
		(layer "In2.Cu")
		(net "EXP_XM_ADDR_7")
	)
	(segment
		(start 108.27258 -86.1568)
		(end 108.14558 -86.0298)
		(width 0.127)
		(layer "In2.Cu")
		(net "EXP_XM_ADDR_7")
	)
	(segment
		(start 106.87558 -86.2076)
		(end 106.74858 -86.3346)
		(width 0.127)
		(layer "In2.Cu")
		(net "EXP_XM_ADDR_7")
	)
	(segment
		(start 105.85958 -86.2076)
		(end 105.73258 -86.3346)
		(width 0.127)
		(layer "In2.Cu")
		(net "EXP_XM_ADDR_7")
	)
	(segment
		(start 108.78058 -86.3346)
		(end 108.78058 -86.5378)
		(width 0.127)
		(layer "In2.Cu")
		(net "EXP_XM_ADDR_7")
	)
	(segment
		(start 104.33558 -86.6648)
		(end 104.20858 -86.5378)
		(width 0.127)
		(layer "In2.Cu")
		(net "EXP_XM_ADDR_7")
	)
	(segment
		(start 103.70058 -86.3346)
		(end 103.70058 -86.5378)
		(width 0.127)
		(layer "In2.Cu")
		(net "EXP_XM_ADDR_7")
	)
	(segment
		(start 104.71658 -86.3346)
		(end 104.71658 -86.5378)
		(width 0.127)
		(layer "In2.Cu")
		(net "EXP_XM_ADDR_7")
	)
	(segment
		(start 105.73258 -86.3346)
		(end 105.73258 -86.5378)
		(width 0.127)
		(layer "In2.Cu")
		(net "EXP_XM_ADDR_7")
	)
	(segment
		(start 106.24058 -86.5378)
		(end 106.24058 -86.3346)
		(width 0.127)
		(layer "In2.Cu")
		(net "EXP_XM_ADDR_7")
	)
	(segment
		(start 105.22458 -86.5378)
		(end 105.22458 -86.3346)
		(width 0.127)
		(layer "In2.Cu")
		(net "EXP_XM_ADDR_7")
	)
	(segment
		(start 106.11358 -86.2076)
		(end 105.85958 -86.2076)
		(width 0.127)
		(layer "In2.Cu")
		(net "EXP_XM_ADDR_7")
	)
	(segment
		(start 114.427 -79.427324)
		(end 114.427 -80.510634)
		(width 0.127)
		(layer "In2.Cu")
		(net "EXP_XM_ADDR_7")
	)
	(segment
		(start 108.78058 -86.5378)
		(end 108.65358 -86.6648)
		(width 0.127)
		(layer "In2.Cu")
		(net "EXP_XM_ADDR_7")
	)
	(segment
		(start 108.14558 -86.0298)
		(end 107.89158 -86.0298)
		(width 0.127)
		(layer "In2.Cu")
		(net "EXP_XM_ADDR_7")
	)
	(segment
		(start 106.62158 -86.6648)
		(end 106.36758 -86.6648)
		(width 0.127)
		(layer "In2.Cu")
		(net "EXP_XM_ADDR_7")
	)
	(segment
		(start 87.643462 -87.318342)
		(end 86.341458 -87.318342)
		(width 0.127)
		(layer "In2.Cu")
		(net "EXP_XM_ADDR_7")
	)
	(segment
		(start 106.74858 -86.3346)
		(end 106.74858 -86.5378)
		(width 0.127)
		(layer "In2.Cu")
		(net "EXP_XM_ADDR_7")
	)
	(segment
		(start 114.7953 -83.693762)
		(end 113.183162 -85.3059)
		(width 0.127)
		(layer "In2.Cu")
		(net "EXP_XM_ADDR_7")
	)
	(segment
		(start 104.08158 -86.2076)
		(end 103.82758 -86.2076)
		(width 0.127)
		(layer "In2.Cu")
		(net "EXP_XM_ADDR_7")
	)
	(segment
		(start 107.12958 -86.2076)
		(end 106.87558 -86.2076)
		(width 0.127)
		(layer "In2.Cu")
		(net "EXP_XM_ADDR_7")
	)
	(segment
		(start 108.27258 -86.5378)
		(end 108.27258 -86.1568)
		(width 0.127)
		(layer "In2.Cu")
		(net "EXP_XM_ADDR_7")
	)
	(segment
		(start 105.22458 -86.3346)
		(end 105.09758 -86.2076)
		(width 0.127)
		(layer "In2.Cu")
		(net "EXP_XM_ADDR_7")
	)
	(segment
		(start 107.63758 -86.6648)
		(end 107.38358 -86.6648)
		(width 0.127)
		(layer "In2.Cu")
		(net "EXP_XM_ADDR_7")
	)
	(segment
		(start 104.84358 -86.2076)
		(end 104.71658 -86.3346)
		(width 0.127)
		(layer "In2.Cu")
		(net "EXP_XM_ADDR_7")
	)
	(segment
		(start 103.70058 -86.5378)
		(end 103.57358 -86.6648)
		(width 0.127)
		(layer "In2.Cu")
		(net "EXP_XM_ADDR_7")
	)
	(segment
		(start 107.25658 -86.5378)
		(end 107.25658 -86.3346)
		(width 0.127)
		(layer "In2.Cu")
		(net "EXP_XM_ADDR_7")
	)
	(segment
		(start 104.58958 -86.6648)
		(end 104.33558 -86.6648)
		(width 0.127)
		(layer "In2.Cu")
		(net "EXP_XM_ADDR_7")
	)
	(segment
		(start 105.09758 -86.2076)
		(end 104.84358 -86.2076)
		(width 0.127)
		(layer "In2.Cu")
		(net "EXP_XM_ADDR_7")
	)
	(segment
		(start 103.82758 -86.2076)
		(end 103.70058 -86.3346)
		(width 0.127)
		(layer "In2.Cu")
		(net "EXP_XM_ADDR_7")
	)
	(segment
		(start 107.89158 -86.0298)
		(end 107.76458 -86.1568)
		(width 0.127)
		(layer "In2.Cu")
		(net "EXP_XM_ADDR_7")
	)
	(segment
		(start 109.80928 -85.3059)
		(end 108.78058 -86.3346)
		(width 0.127)
		(layer "In2.Cu")
		(net "EXP_XM_ADDR_7")
	)
	(segment
		(start 105.60558 -86.6648)
		(end 105.35158 -86.6648)
		(width 0.127)
		(layer "In2.Cu")
		(net "EXP_XM_ADDR_7")
	)
	(segment
		(start 114.7953 -81.6229)
		(end 114.7953 -83.693762)
		(width 0.127)
		(layer "In2.Cu")
		(net "EXP_XM_ADDR_7")
	)
	(segment
		(start 108.65358 -86.6648)
		(end 108.39958 -86.6648)
		(width 0.127)
		(layer "In2.Cu")
		(net "EXP_XM_ADDR_7")
	)
	(segment
		(start 106.74858 -86.5378)
		(end 106.62158 -86.6648)
		(width 0.127)
		(layer "In2.Cu")
		(net "EXP_XM_ADDR_7")
	)
	(segment
		(start 105.73258 -86.5378)
		(end 105.60558 -86.6648)
		(width 0.127)
		(layer "In2.Cu")
		(net "EXP_XM_ADDR_7")
	)
	(segment
		(start 113.4999 -74.500232)
		(end 113.999772 -75.000104)
		(width 0.127)
		(layer "F.Cu")
		(net "EXP_XM_ADDR_6")
	)
	(via
		(at 113.999772 -75.000104)
		(size 0.4572)
		(drill 0.2032)
		(layers "F.Cu" "B.Cu")
		(net "EXP_XM_ADDR_6")
	)
	(via
		(at 84.26831 -98.17989)
		(size 0.508)
		(drill 0.254)
		(layers "F.Cu" "B.Cu")
		(net "EXP_XM_ADDR_6")
	)
	(segment
		(start 84.26831 -94.8309)
		(end 84.26831 -98.17989)
		(width 0.127)
		(layer "B.Cu")
		(net "EXP_XM_ADDR_6")
	)
	(segment
		(start 84.726272 -98.022156)
		(end 84.426044 -98.022156)
		(width 0.127)
		(layer "In2.Cu")
		(net "EXP_XM_ADDR_6")
	)
	(segment
		(start 118.708424 -97.404174)
		(end 118.581424 -97.531174)
		(width 0.127)
		(layer "In2.Cu")
		(net "EXP_XM_ADDR_6")
	)
	(segment
		(start 85.787738 -98.022156)
		(end 85.488272 -98.022156)
		(width 0.127)
		(layer "In2.Cu")
		(net "EXP_XM_ADDR_6")
	)
	(segment
		(start 116.21516 -75.5396)
		(end 116.5352 -75.85964)
		(width 0.127)
		(layer "In2.Cu")
		(net "EXP_XM_ADDR_6")
	)
	(segment
		(start 114.126772 -74.442574)
		(end 115.088162 -74.442574)
		(width 0.127)
		(layer "In2.Cu")
		(net "EXP_XM_ADDR_6")
	)
	(segment
		(start 120.980454 -95.23603)
		(end 120.980454 -95.415862)
		(width 0.127)
		(layer "In2.Cu")
		(net "EXP_XM_ADDR_6")
	)
	(segment
		(start 85.234272 -98.679)
		(end 84.980272 -98.679)
		(width 0.127)
		(layer "In2.Cu")
		(net "EXP_XM_ADDR_6")
	)
	(segment
		(start 121.539 -80.69707)
		(end 121.539 -83.2866)
		(width 0.127)
		(layer "In2.Cu")
		(net "EXP_XM_ADDR_6")
	)
	(segment
		(start 86.295738 -98.679)
		(end 86.041738 -98.679)
		(width 0.127)
		(layer "In2.Cu")
		(net "EXP_XM_ADDR_6")
	)
	(segment
		(start 119.303038 -96.254062)
		(end 119.303038 -96.433894)
		(width 0.127)
		(layer "In2.Cu")
		(net "EXP_XM_ADDR_6")
	)
	(segment
		(start 118.491 -76.835)
		(end 118.491 -77.3176)
		(width 0.127)
		(layer "In2.Cu")
		(net "EXP_XM_ADDR_6")
	)
	(segment
		(start 116.5352 -75.85964)
		(end 116.5352 -76.187808)
		(width 0.127)
		(layer "In2.Cu")
		(net "EXP_XM_ADDR_6")
	)
	(segment
		(start 86.422738 -98.552)
		(end 86.295738 -98.679)
		(width 0.127)
		(layer "In2.Cu")
		(net "EXP_XM_ADDR_6")
	)
	(segment
		(start 122.228102 -94.327218)
		(end 121.818908 -93.918024)
		(width 0.127)
		(layer "In2.Cu")
		(net "EXP_XM_ADDR_6")
	)
	(segment
		(start 119.183404 -97.03308)
		(end 118.943628 -96.793304)
		(width 0.127)
		(layer "In2.Cu")
		(net "EXP_XM_ADDR_6")
	)
	(segment
		(start 119.542814 -96.853502)
		(end 119.363236 -97.03308)
		(width 0.127)
		(layer "In2.Cu")
		(net "EXP_XM_ADDR_6")
	)
	(segment
		(start 120.201436 -95.355664)
		(end 120.021858 -95.535242)
		(width 0.127)
		(layer "In2.Cu")
		(net "EXP_XM_ADDR_6")
	)
	(segment
		(start 86.549738 -98.022156)
		(end 86.422738 -98.149156)
		(width 0.127)
		(layer "In2.Cu")
		(net "EXP_XM_ADDR_6")
	)
	(segment
		(start 120.4976 -79.663798)
		(end 120.4976 -80.147668)
		(width 0.127)
		(layer "In2.Cu")
		(net "EXP_XM_ADDR_6")
	)
	(segment
		(start 84.853272 -98.149156)
		(end 84.726272 -98.022156)
		(width 0.127)
		(layer "In2.Cu")
		(net "EXP_XM_ADDR_6")
	)
	(segment
		(start 121.459498 -94.277434)
		(end 121.699274 -94.51721)
		(width 0.127)
		(layer "In2.Cu")
		(net "EXP_XM_ADDR_6")
	)
	(segment
		(start 86.422738 -98.149156)
		(end 86.422738 -98.552)
		(width 0.127)
		(layer "In2.Cu")
		(net "EXP_XM_ADDR_6")
	)
	(segment
		(start 119.303038 -96.433894)
		(end 119.542814 -96.67367)
		(width 0.127)
		(layer "In2.Cu")
		(net "EXP_XM_ADDR_6")
	)
	(segment
		(start 118.581424 -97.531174)
		(end 89.710514 -97.531174)
		(width 0.127)
		(layer "In2.Cu")
		(net "EXP_XM_ADDR_6")
	)
	(segment
		(start 120.800876 -95.59544)
		(end 120.621044 -95.59544)
		(width 0.127)
		(layer "In2.Cu")
		(net "EXP_XM_ADDR_6")
	)
	(segment
		(start 84.426044 -98.022156)
		(end 84.26831 -98.17989)
		(width 0.127)
		(layer "In2.Cu")
		(net "EXP_XM_ADDR_6")
	)
	(segment
		(start 120.621044 -95.59544)
		(end 120.381268 -95.355664)
		(width 0.127)
		(layer "In2.Cu")
		(net "EXP_XM_ADDR_6")
	)
	(segment
		(start 118.2116 -76.5556)
		(end 118.491 -76.835)
		(width 0.127)
		(layer "In2.Cu")
		(net "EXP_XM_ADDR_6")
	)
	(segment
		(start 122.227848 -93.608144)
		(end 122.587512 -93.967808)
		(width 0.127)
		(layer "In2.Cu")
		(net "EXP_XM_ADDR_6")
	)
	(segment
		(start 117.13972 -76.441808)
		(end 117.253512 -76.5556)
		(width 0.127)
		(layer "In2.Cu")
		(net "EXP_XM_ADDR_6")
	)
	(segment
		(start 119.662448 -96.074484)
		(end 119.482616 -96.074484)
		(width 0.127)
		(layer "In2.Cu")
		(net "EXP_XM_ADDR_6")
	)
	(segment
		(start 118.763796 -96.793304)
		(end 118.584218 -96.972882)
		(width 0.127)
		(layer "In2.Cu")
		(net "EXP_XM_ADDR_6")
	)
	(segment
		(start 113.999772 -74.569574)
		(end 114.126772 -74.442574)
		(width 0.127)
		(layer "In2.Cu")
		(net "EXP_XM_ADDR_6")
	)
	(segment
		(start 118.708424 -97.277174)
		(end 118.708424 -97.404174)
		(width 0.127)
		(layer "In2.Cu")
		(net "EXP_XM_ADDR_6")
	)
	(segment
		(start 121.639076 -93.918024)
		(end 121.459498 -94.097602)
		(width 0.127)
		(layer "In2.Cu")
		(net "EXP_XM_ADDR_6")
	)
	(segment
		(start 118.7196 -77.5462)
		(end 119.2022 -77.5462)
		(width 0.127)
		(layer "In2.Cu")
		(net "EXP_XM_ADDR_6")
	)
	(segment
		(start 120.381268 -95.355664)
		(end 120.201436 -95.355664)
		(width 0.127)
		(layer "In2.Cu")
		(net "EXP_XM_ADDR_6")
	)
	(segment
		(start 85.361272 -98.149156)
		(end 85.361272 -98.552)
		(width 0.127)
		(layer "In2.Cu")
		(net "EXP_XM_ADDR_6")
	)
	(segment
		(start 118.584218 -96.972882)
		(end 118.584218 -97.152714)
		(width 0.127)
		(layer "In2.Cu")
		(net "EXP_XM_ADDR_6")
	)
	(segment
		(start 121.699274 -94.51721)
		(end 121.699274 -94.697042)
		(width 0.127)
		(layer "In2.Cu")
		(net "EXP_XM_ADDR_6")
	)
	(segment
		(start 115.7478 -75.5396)
		(end 116.21516 -75.5396)
		(width 0.127)
		(layer "In2.Cu")
		(net "EXP_XM_ADDR_6")
	)
	(segment
		(start 119.2022 -77.5462)
		(end 119.54383 -77.88783)
		(width 0.127)
		(layer "In2.Cu")
		(net "EXP_XM_ADDR_6")
	)
	(segment
		(start 85.914738 -98.149156)
		(end 85.787738 -98.022156)
		(width 0.127)
		(layer "In2.Cu")
		(net "EXP_XM_ADDR_6")
	)
	(segment
		(start 121.459498 -94.097602)
		(end 121.459498 -94.277434)
		(width 0.127)
		(layer "In2.Cu")
		(net "EXP_XM_ADDR_6")
	)
	(segment
		(start 119.54383 -77.88783)
		(end 119.54383 -79.257398)
		(width 0.127)
		(layer "In2.Cu")
		(net "EXP_XM_ADDR_6")
	)
	(segment
		(start 120.3452 -79.511398)
		(end 120.4976 -79.663798)
		(width 0.127)
		(layer "In2.Cu")
		(net "EXP_XM_ADDR_6")
	)
	(segment
		(start 119.542814 -96.67367)
		(end 119.542814 -96.853502)
		(width 0.127)
		(layer "In2.Cu")
		(net "EXP_XM_ADDR_6")
	)
	(segment
		(start 84.853272 -98.552)
		(end 84.853272 -98.149156)
		(width 0.127)
		(layer "In2.Cu")
		(net "EXP_XM_ADDR_6")
	)
	(segment
		(start 123.2789 -89.837514)
		(end 123.2789 -90.522552)
		(width 0.127)
		(layer "In2.Cu")
		(net "EXP_XM_ADDR_6")
	)
	(segment
		(start 117.253512 -76.5556)
		(end 118.2116 -76.5556)
		(width 0.127)
		(layer "In2.Cu")
		(net "EXP_XM_ADDR_6")
	)
	(segment
		(start 119.54383 -79.257398)
		(end 119.79783 -79.511398)
		(width 0.127)
		(layer "In2.Cu")
		(net "EXP_XM_ADDR_6")
	)
	(segment
		(start 123.2789 -90.522552)
		(end 122.227848 -91.573604)
		(width 0.127)
		(layer "In2.Cu")
		(net "EXP_XM_ADDR_6")
	)
	(segment
		(start 120.021858 -95.535242)
		(end 120.021858 -95.715074)
		(width 0.127)
		(layer "In2.Cu")
		(net "EXP_XM_ADDR_6")
	)
	(segment
		(start 120.4976 -80.147668)
		(end 120.860312 -80.51038)
		(width 0.127)
		(layer "In2.Cu")
		(net "EXP_XM_ADDR_6")
	)
	(segment
		(start 121.35231 -80.51038)
		(end 121.539 -80.69707)
		(width 0.127)
		(layer "In2.Cu")
		(net "EXP_XM_ADDR_6")
	)
	(segment
		(start 120.920256 -94.636844)
		(end 120.740678 -94.816422)
		(width 0.127)
		(layer "In2.Cu")
		(net "EXP_XM_ADDR_6")
	)
	(segment
		(start 116.7892 -76.441808)
		(end 117.13972 -76.441808)
		(width 0.127)
		(layer "In2.Cu")
		(net "EXP_XM_ADDR_6")
	)
	(segment
		(start 121.339864 -94.87662)
		(end 121.100088 -94.636844)
		(width 0.127)
		(layer "In2.Cu")
		(net "EXP_XM_ADDR_6")
	)
	(segment
		(start 121.699274 -94.697042)
		(end 121.519696 -94.87662)
		(width 0.127)
		(layer "In2.Cu")
		(net "EXP_XM_ADDR_6")
	)
	(segment
		(start 120.261634 -95.95485)
		(end 120.261634 -96.134682)
		(width 0.127)
		(layer "In2.Cu")
		(net "EXP_XM_ADDR_6")
	)
	(segment
		(start 120.740678 -94.816422)
		(end 120.740678 -94.996254)
		(width 0.127)
		(layer "In2.Cu")
		(net "EXP_XM_ADDR_6")
	)
	(segment
		(start 118.491 -77.3176)
		(end 118.7196 -77.5462)
		(width 0.127)
		(layer "In2.Cu")
		(net "EXP_XM_ADDR_6")
	)
	(segment
		(start 115.088162 -74.442574)
		(end 115.527328 -74.88174)
		(width 0.127)
		(layer "In2.Cu")
		(net "EXP_XM_ADDR_6")
	)
	(segment
		(start 116.5352 -76.187808)
		(end 116.7892 -76.441808)
		(width 0.127)
		(layer "In2.Cu")
		(net "EXP_XM_ADDR_6")
	)
	(segment
		(start 113.999772 -75.000104)
		(end 113.999772 -74.569574)
		(width 0.127)
		(layer "In2.Cu")
		(net "EXP_XM_ADDR_6")
	)
	(segment
		(start 122.407934 -94.327218)
		(end 122.228102 -94.327218)
		(width 0.127)
		(layer "In2.Cu")
		(net "EXP_XM_ADDR_6")
	)
	(segment
		(start 119.79783 -79.511398)
		(end 120.3452 -79.511398)
		(width 0.127)
		(layer "In2.Cu")
		(net "EXP_XM_ADDR_6")
	)
	(segment
		(start 120.860312 -80.51038)
		(end 121.35231 -80.51038)
		(width 0.127)
		(layer "In2.Cu")
		(net "EXP_XM_ADDR_6")
	)
	(segment
		(start 124.428758 -88.687656)
		(end 123.2789 -89.837514)
		(width 0.127)
		(layer "In2.Cu")
		(net "EXP_XM_ADDR_6")
	)
	(segment
		(start 122.587512 -94.14764)
		(end 122.407934 -94.327218)
		(width 0.127)
		(layer "In2.Cu")
		(net "EXP_XM_ADDR_6")
	)
	(segment
		(start 115.527328 -74.88174)
		(end 115.527328 -75.319128)
		(width 0.127)
		(layer "In2.Cu")
		(net "EXP_XM_ADDR_6")
	)
	(segment
		(start 120.021858 -95.715074)
		(end 120.261634 -95.95485)
		(width 0.127)
		(layer "In2.Cu")
		(net "EXP_XM_ADDR_6")
	)
	(segment
		(start 121.519696 -94.87662)
		(end 121.339864 -94.87662)
		(width 0.127)
		(layer "In2.Cu")
		(net "EXP_XM_ADDR_6")
	)
	(segment
		(start 119.902224 -96.31426)
		(end 119.662448 -96.074484)
		(width 0.127)
		(layer "In2.Cu")
		(net "EXP_XM_ADDR_6")
	)
	(segment
		(start 121.100088 -94.636844)
		(end 120.920256 -94.636844)
		(width 0.127)
		(layer "In2.Cu")
		(net "EXP_XM_ADDR_6")
	)
	(segment
		(start 86.041738 -98.679)
		(end 85.914738 -98.552)
		(width 0.127)
		(layer "In2.Cu")
		(net "EXP_XM_ADDR_6")
	)
	(segment
		(start 124.428758 -86.176358)
		(end 124.428758 -88.687656)
		(width 0.127)
		(layer "In2.Cu")
		(net "EXP_XM_ADDR_6")
	)
	(segment
		(start 85.488272 -98.022156)
		(end 85.361272 -98.149156)
		(width 0.127)
		(layer "In2.Cu")
		(net "EXP_XM_ADDR_6")
	)
	(segment
		(start 115.527328 -75.319128)
		(end 115.7478 -75.5396)
		(width 0.127)
		(layer "In2.Cu")
		(net "EXP_XM_ADDR_6")
	)
	(segment
		(start 118.584218 -97.152714)
		(end 118.708424 -97.277174)
		(width 0.127)
		(layer "In2.Cu")
		(net "EXP_XM_ADDR_6")
	)
	(segment
		(start 121.539 -83.2866)
		(end 124.428758 -86.176358)
		(width 0.127)
		(layer "In2.Cu")
		(net "EXP_XM_ADDR_6")
	)
	(segment
		(start 89.219532 -98.022156)
		(end 86.549738 -98.022156)
		(width 0.127)
		(layer "In2.Cu")
		(net "EXP_XM_ADDR_6")
	)
	(segment
		(start 89.710514 -97.531174)
		(end 89.219532 -98.022156)
		(width 0.127)
		(layer "In2.Cu")
		(net "EXP_XM_ADDR_6")
	)
	(segment
		(start 120.980454 -95.415862)
		(end 120.800876 -95.59544)
		(width 0.127)
		(layer "In2.Cu")
		(net "EXP_XM_ADDR_6")
	)
	(segment
		(start 120.082056 -96.31426)
		(end 119.902224 -96.31426)
		(width 0.127)
		(layer "In2.Cu")
		(net "EXP_XM_ADDR_6")
	)
	(segment
		(start 120.740678 -94.996254)
		(end 120.980454 -95.23603)
		(width 0.127)
		(layer "In2.Cu")
		(net "EXP_XM_ADDR_6")
	)
	(segment
		(start 122.587512 -93.967808)
		(end 122.587512 -94.14764)
		(width 0.127)
		(layer "In2.Cu")
		(net "EXP_XM_ADDR_6")
	)
	(segment
		(start 121.818908 -93.918024)
		(end 121.639076 -93.918024)
		(width 0.127)
		(layer "In2.Cu")
		(net "EXP_XM_ADDR_6")
	)
	(segment
		(start 85.361272 -98.552)
		(end 85.234272 -98.679)
		(width 0.127)
		(layer "In2.Cu")
		(net "EXP_XM_ADDR_6")
	)
	(segment
		(start 118.943628 -96.793304)
		(end 118.763796 -96.793304)
		(width 0.127)
		(layer "In2.Cu")
		(net "EXP_XM_ADDR_6")
	)
	(segment
		(start 85.914738 -98.552)
		(end 85.914738 -98.149156)
		(width 0.127)
		(layer "In2.Cu")
		(net "EXP_XM_ADDR_6")
	)
	(segment
		(start 119.482616 -96.074484)
		(end 119.303038 -96.254062)
		(width 0.127)
		(layer "In2.Cu")
		(net "EXP_XM_ADDR_6")
	)
	(segment
		(start 122.227848 -91.573604)
		(end 122.227848 -93.608144)
		(width 0.127)
		(layer "In2.Cu")
		(net "EXP_XM_ADDR_6")
	)
	(segment
		(start 84.980272 -98.679)
		(end 84.853272 -98.552)
		(width 0.127)
		(layer "In2.Cu")
		(net "EXP_XM_ADDR_6")
	)
	(segment
		(start 119.363236 -97.03308)
		(end 119.183404 -97.03308)
		(width 0.127)
		(layer "In2.Cu")
		(net "EXP_XM_ADDR_6")
	)
	(segment
		(start 120.261634 -96.134682)
		(end 120.082056 -96.31426)
		(width 0.127)
		(layer "In2.Cu")
		(net "EXP_XM_ADDR_6")
	)
	(segment
		(start 112.8268 -84.3788)
		(end 114.499898 -82.705702)
		(width 0.127)
		(layer "F.Cu")
		(net "EXP_XM_ADDR_5")
	)
	(segment
		(start 114.499898 -82.705702)
		(end 114.499898 -82.500216)
		(width 0.127)
		(layer "F.Cu")
		(net "EXP_XM_ADDR_5")
	)
	(segment
		(start 112.8268 -85.7504)
		(end 112.8268 -84.3788)
		(width 0.127)
		(layer "F.Cu")
		(net "EXP_XM_ADDR_5")
	)
	(via
		(at 112.8268 -85.7504)
		(size 0.508)
		(drill 0.254)
		(layers "F.Cu" "B.Cu")
		(net "EXP_XM_ADDR_5")
	)
	(via
		(at 85.7504 -88.7984)
		(size 0.508)
		(drill 0.254)
		(layers "F.Cu" "B.Cu")
		(net "EXP_XM_ADDR_5")
	)
	(segment
		(start 89.7128 -98.481896)
		(end 89.5858 -98.608896)
		(width 0.127)
		(layer "B.Cu")
		(net "EXP_XM_ADDR_5")
	)
	(segment
		(start 91.5416 -97.338896)
		(end 91.4146 -97.465896)
		(width 0.127)
		(layer "B.Cu")
		(net "EXP_XM_ADDR_5")
	)
	(segment
		(start 91.4146 -97.973896)
		(end 91.5416 -98.100896)
		(width 0.127)
		(layer "B.Cu")
		(net "EXP_XM_ADDR_5")
	)
	(segment
		(start 84.76742 -94.078806)
		(end 84.76742 -94.8309)
		(width 0.127)
		(layer "B.Cu")
		(net "EXP_XM_ADDR_5")
	)
	(segment
		(start 92.3798 -98.862896)
		(end 92.3798 -90.805)
		(width 0.127)
		(layer "B.Cu")
		(net "EXP_XM_ADDR_5")
	)
	(segment
		(start 89.7128 -98.989896)
		(end 92.2528 -98.989896)
		(width 0.127)
		(layer "B.Cu")
		(net "EXP_XM_ADDR_5")
	)
	(segment
		(start 86.233 -88.7984)
		(end 86.36 -88.6714)
		(width 0.127)
		(layer "B.Cu")
		(net "EXP_XM_ADDR_5")
	)
	(segment
		(start 89.5858 -97.846896)
		(end 89.7128 -97.973896)
		(width 0.127)
		(layer "B.Cu")
		(net "EXP_XM_ADDR_5")
	)
	(segment
		(start 89.5858 -98.608896)
		(end 89.5858 -98.862896)
		(width 0.127)
		(layer "B.Cu")
		(net "EXP_XM_ADDR_5")
	)
	(segment
		(start 91.5416 -98.100896)
		(end 91.5416 -98.354896)
		(width 0.127)
		(layer "B.Cu")
		(net "EXP_XM_ADDR_5")
	)
	(segment
		(start 91.5416 -98.354896)
		(end 91.4146 -98.481896)
		(width 0.127)
		(layer "B.Cu")
		(net "EXP_XM_ADDR_5")
	)
	(segment
		(start 89.7128 -97.465896)
		(end 89.5858 -97.592896)
		(width 0.127)
		(layer "B.Cu")
		(net "EXP_XM_ADDR_5")
	)
	(segment
		(start 89.059766 -88.3158)
		(end 91.5416 -90.797634)
		(width 0.127)
		(layer "B.Cu")
		(net "EXP_XM_ADDR_5")
	)
	(segment
		(start 92.3798 -90.805)
		(end 89.3826 -87.8078)
		(width 0.127)
		(layer "B.Cu")
		(net "EXP_XM_ADDR_5")
	)
	(segment
		(start 91.4146 -97.465896)
		(end 89.7128 -97.465896)
		(width 0.127)
		(layer "B.Cu")
		(net "EXP_XM_ADDR_5")
	)
	(segment
		(start 89.5858 -98.862896)
		(end 89.7128 -98.989896)
		(width 0.127)
		(layer "B.Cu")
		(net "EXP_XM_ADDR_5")
	)
	(segment
		(start 91.4146 -98.481896)
		(end 89.7128 -98.481896)
		(width 0.127)
		(layer "B.Cu")
		(net "EXP_XM_ADDR_5")
	)
	(segment
		(start 86.36 -88.6714)
		(end 87.1728 -88.6714)
		(width 0.127)
		(layer "B.Cu")
		(net "EXP_XM_ADDR_5")
	)
	(segment
		(start 92.2528 -98.989896)
		(end 92.3798 -98.862896)
		(width 0.127)
		(layer "B.Cu")
		(net "EXP_XM_ADDR_5")
	)
	(segment
		(start 85.1916 -88.1126)
		(end 84.75218 -88.55202)
		(width 0.127)
		(layer "B.Cu")
		(net "EXP_XM_ADDR_5")
	)
	(segment
		(start 87.122 -87.8078)
		(end 86.8172 -88.1126)
		(width 0.127)
		(layer "B.Cu")
		(net "EXP_XM_ADDR_5")
	)
	(segment
		(start 89.3826 -87.8078)
		(end 87.122 -87.8078)
		(width 0.127)
		(layer "B.Cu")
		(net "EXP_XM_ADDR_5")
	)
	(segment
		(start 89.5858 -97.592896)
		(end 89.5858 -97.846896)
		(width 0.127)
		(layer "B.Cu")
		(net "EXP_XM_ADDR_5")
	)
	(segment
		(start 86.8172 -88.1126)
		(end 85.1916 -88.1126)
		(width 0.127)
		(layer "B.Cu")
		(net "EXP_XM_ADDR_5")
	)
	(segment
		(start 84.75218 -94.063566)
		(end 84.76742 -94.078806)
		(width 0.127)
		(layer "B.Cu")
		(net "EXP_XM_ADDR_5")
	)
	(segment
		(start 87.5284 -88.3158)
		(end 89.059766 -88.3158)
		(width 0.127)
		(layer "B.Cu")
		(net "EXP_XM_ADDR_5")
	)
	(segment
		(start 84.75218 -88.55202)
		(end 84.75218 -94.063566)
		(width 0.127)
		(layer "B.Cu")
		(net "EXP_XM_ADDR_5")
	)
	(segment
		(start 89.7128 -97.973896)
		(end 91.4146 -97.973896)
		(width 0.127)
		(layer "B.Cu")
		(net "EXP_XM_ADDR_5")
	)
	(segment
		(start 85.7504 -88.7984)
		(end 86.233 -88.7984)
		(width 0.127)
		(layer "B.Cu")
		(net "EXP_XM_ADDR_5")
	)
	(segment
		(start 87.1728 -88.6714)
		(end 87.5284 -88.3158)
		(width 0.127)
		(layer "B.Cu")
		(net "EXP_XM_ADDR_5")
	)
	(segment
		(start 91.5416 -90.797634)
		(end 91.5416 -97.338896)
		(width 0.127)
		(layer "B.Cu")
		(net "EXP_XM_ADDR_5")
	)
	(segment
		(start 87.027258 -88.334342)
		(end 88.111584 -88.334342)
		(width 0.127)
		(layer "In2.Cu")
		(net "EXP_XM_ADDR_5")
	)
	(segment
		(start 86.5632 -88.7984)
		(end 87.027258 -88.334342)
		(width 0.127)
		(layer "In2.Cu")
		(net "EXP_XM_ADDR_5")
	)
	(segment
		(start 88.111584 -88.334342)
		(end 88.765126 -87.6808)
		(width 0.127)
		(layer "In2.Cu")
		(net "EXP_XM_ADDR_5")
	)
	(segment
		(start 111.9632 -86.614)
		(end 112.8268 -85.7504)
		(width 0.127)
		(layer "In2.Cu")
		(net "EXP_XM_ADDR_5")
	)
	(segment
		(start 88.765126 -87.6808)
		(end 109.6518 -87.6808)
		(width 0.127)
		(layer "In2.Cu")
		(net "EXP_XM_ADDR_5")
	)
	(segment
		(start 85.7504 -88.7984)
		(end 86.5632 -88.7984)
		(width 0.127)
		(layer "In2.Cu")
		(net "EXP_XM_ADDR_5")
	)
	(segment
		(start 110.7186 -86.614)
		(end 111.9632 -86.614)
		(width 0.127)
		(layer "In2.Cu")
		(net "EXP_XM_ADDR_5")
	)
	(segment
		(start 109.6518 -87.6808)
		(end 110.7186 -86.614)
		(width 0.127)
		(layer "In2.Cu")
		(net "EXP_XM_ADDR_5")
	)
	(segment
		(start 113.406428 -84.357972)
		(end 113.58626 -84.357972)
		(width 0.127)
		(layer "F.Cu")
		(net "EXP_XM_ADDR_4")
	)
	(segment
		(start 114.966496 -82.365342)
		(end 114.499898 -81.898744)
		(width 0.127)
		(layer "F.Cu")
		(net "EXP_XM_ADDR_4")
	)
	(segment
		(start 113.94567 -83.81873)
		(end 114.125248 -83.639152)
		(width 0.127)
		(layer "F.Cu")
		(net "EXP_XM_ADDR_4")
	)
	(segment
		(start 114.182652 -84.415376)
		(end 114.182652 -84.235544)
		(width 0.127)
		(layer "F.Cu")
		(net "EXP_XM_ADDR_4")
	)
	(segment
		(start 114.721894 -83.876134)
		(end 114.966496 -83.631532)
		(width 0.127)
		(layer "F.Cu")
		(net "EXP_XM_ADDR_4")
	)
	(segment
		(start 114.182652 -84.235544)
		(end 113.94567 -83.998562)
		(width 0.127)
		(layer "F.Cu")
		(net "EXP_XM_ADDR_4")
	)
	(segment
		(start 112.8014 -86.487)
		(end 113.375948 -85.912452)
		(width 0.127)
		(layer "F.Cu")
		(net "EXP_XM_ADDR_4")
	)
	(segment
		(start 113.463832 -85.134196)
		(end 113.463832 -84.954364)
		(width 0.127)
		(layer "F.Cu")
		(net "EXP_XM_ADDR_4")
	)
	(segment
		(start 113.58626 -84.357972)
		(end 113.823242 -84.594954)
		(width 0.127)
		(layer "F.Cu")
		(net "EXP_XM_ADDR_4")
	)
	(segment
		(start 114.966496 -83.631532)
		(end 114.966496 -82.365342)
		(width 0.127)
		(layer "F.Cu")
		(net "EXP_XM_ADDR_4")
	)
	(segment
		(start 112.8014 -86.614)
		(end 112.8014 -86.487)
		(width 0.127)
		(layer "F.Cu")
		(net "EXP_XM_ADDR_4")
	)
	(segment
		(start 114.003074 -84.594954)
		(end 114.182652 -84.415376)
		(width 0.127)
		(layer "F.Cu")
		(net "EXP_XM_ADDR_4")
	)
	(segment
		(start 114.30508 -83.639152)
		(end 114.542062 -83.876134)
		(width 0.127)
		(layer "F.Cu")
		(net "EXP_XM_ADDR_4")
	)
	(segment
		(start 114.499898 -81.898744)
		(end 114.499898 -81.500218)
		(width 0.127)
		(layer "F.Cu")
		(net "EXP_XM_ADDR_4")
	)
	(segment
		(start 113.463832 -84.954364)
		(end 113.22685 -84.717382)
		(width 0.127)
		(layer "F.Cu")
		(net "EXP_XM_ADDR_4")
	)
	(segment
		(start 114.125248 -83.639152)
		(end 114.30508 -83.639152)
		(width 0.127)
		(layer "F.Cu")
		(net "EXP_XM_ADDR_4")
	)
	(segment
		(start 113.22685 -84.53755)
		(end 113.406428 -84.357972)
		(width 0.127)
		(layer "F.Cu")
		(net "EXP_XM_ADDR_4")
	)
	(segment
		(start 113.22685 -84.717382)
		(end 113.22685 -84.53755)
		(width 0.127)
		(layer "F.Cu")
		(net "EXP_XM_ADDR_4")
	)
	(segment
		(start 113.375948 -85.912452)
		(end 113.375948 -85.22208)
		(width 0.127)
		(layer "F.Cu")
		(net "EXP_XM_ADDR_4")
	)
	(segment
		(start 113.823242 -84.594954)
		(end 114.003074 -84.594954)
		(width 0.127)
		(layer "F.Cu")
		(net "EXP_XM_ADDR_4")
	)
	(segment
		(start 113.375948 -85.22208)
		(end 113.463832 -85.134196)
		(width 0.127)
		(layer "F.Cu")
		(net "EXP_XM_ADDR_4")
	)
	(segment
		(start 114.542062 -83.876134)
		(end 114.721894 -83.876134)
		(width 0.127)
		(layer "F.Cu")
		(net "EXP_XM_ADDR_4")
	)
	(segment
		(start 113.94567 -83.998562)
		(end 113.94567 -83.81873)
		(width 0.127)
		(layer "F.Cu")
		(net "EXP_XM_ADDR_4")
	)
	(via
		(at 112.8014 -86.614)
		(size 0.508)
		(drill 0.254)
		(layers "F.Cu" "B.Cu")
		(net "EXP_XM_ADDR_4")
	)
	(via
		(at 87.8078 -88.842342)
		(size 0.508)
		(drill 0.254)
		(layers "F.Cu" "B.Cu")
		(net "EXP_XM_ADDR_4")
	)
	(segment
		(start 85.9282 -91.790012)
		(end 85.9282 -92.044012)
		(width 0.127)
		(layer "B.Cu")
		(net "EXP_XM_ADDR_4")
	)
	(segment
		(start 89.126822 -90.269822)
		(end 88.5952 -89.7382)
		(width 0.127)
		(layer "B.Cu")
		(net "EXP_XM_ADDR_4")
	)
	(segment
		(start 86.742524 -89.281)
		(end 86.742524 -89.5858)
		(width 0.127)
		(layer "B.Cu")
		(net "EXP_XM_ADDR_4")
	)
	(segment
		(start 85.26018 -93.314012)
		(end 85.26018 -93.925898)
		(width 0.127)
		(layer "B.Cu")
		(net "EXP_XM_ADDR_4")
	)
	(segment
		(start 85.26018 -91.536012)
		(end 85.38718 -91.663012)
		(width 0.127)
		(layer "B.Cu")
		(net "EXP_XM_ADDR_4")
	)
	(segment
		(start 85.471 -89.7382)
		(end 85.26018 -89.94902)
		(width 0.127)
		(layer "B.Cu")
		(net "EXP_XM_ADDR_4")
	)
	(segment
		(start 85.38718 -91.663012)
		(end 85.8012 -91.663012)
		(width 0.127)
		(layer "B.Cu")
		(net "EXP_XM_ADDR_4")
	)
	(segment
		(start 87.250524 -89.281)
		(end 87.148924 -89.1794)
		(width 0.127)
		(layer "B.Cu")
		(net "EXP_XM_ADDR_4")
	)
	(segment
		(start 85.8012 -91.663012)
		(end 85.9282 -91.790012)
		(width 0.127)
		(layer "B.Cu")
		(net "EXP_XM_ADDR_4")
	)
	(segment
		(start 85.9282 -91.028012)
		(end 85.8012 -91.155012)
		(width 0.127)
		(layer "B.Cu")
		(net "EXP_XM_ADDR_4")
	)
	(segment
		(start 87.148924 -89.1794)
		(end 86.844124 -89.1794)
		(width 0.127)
		(layer "B.Cu")
		(net "EXP_XM_ADDR_4")
	)
	(segment
		(start 89.666064 -90.809064)
		(end 89.486232 -90.809064)
		(width 0.127)
		(layer "B.Cu")
		(net "EXP_XM_ADDR_4")
	)
	(segment
		(start 89.181432 -90.934032)
		(end 89.001854 -90.754454)
		(width 0.127)
		(layer "B.Cu")
		(net "EXP_XM_ADDR_4")
	)
	(segment
		(start 89.361264 -90.934032)
		(end 89.181432 -90.934032)
		(width 0.127)
		(layer "B.Cu")
		(net "EXP_XM_ADDR_4")
	)
	(segment
		(start 85.38718 -91.155012)
		(end 85.26018 -91.282012)
		(width 0.127)
		(layer "B.Cu")
		(net "EXP_XM_ADDR_4")
	)
	(segment
		(start 90.043 -91.186)
		(end 89.666064 -90.809064)
		(width 0.127)
		(layer "B.Cu")
		(net "EXP_XM_ADDR_4")
	)
	(segment
		(start 90.043 -96.7994)
		(end 90.043 -91.186)
		(width 0.127)
		(layer "B.Cu")
		(net "EXP_XM_ADDR_4")
	)
	(segment
		(start 85.2678 -93.933518)
		(end 85.2678 -94.8309)
		(width 0.127)
		(layer "B.Cu")
		(net "EXP_XM_ADDR_4")
	)
	(segment
		(start 85.38718 -92.679012)
		(end 85.8012 -92.679012)
		(width 0.127)
		(layer "B.Cu")
		(net "EXP_XM_ADDR_4")
	)
	(segment
		(start 91.0336 -91.0082)
		(end 91.0336 -96.7994)
		(width 0.127)
		(layer "B.Cu")
		(net "EXP_XM_ADDR_4")
	)
	(segment
		(start 85.38718 -93.187012)
		(end 85.26018 -93.314012)
		(width 0.127)
		(layer "B.Cu")
		(net "EXP_XM_ADDR_4")
	)
	(segment
		(start 85.9282 -93.060012)
		(end 85.8012 -93.187012)
		(width 0.127)
		(layer "B.Cu")
		(net "EXP_XM_ADDR_4")
	)
	(segment
		(start 85.9282 -92.044012)
		(end 85.8012 -92.171012)
		(width 0.127)
		(layer "B.Cu")
		(net "EXP_XM_ADDR_4")
	)
	(segment
		(start 86.742524 -89.5858)
		(end 86.590124 -89.7382)
		(width 0.127)
		(layer "B.Cu")
		(net "EXP_XM_ADDR_4")
	)
	(segment
		(start 85.38718 -92.171012)
		(end 85.26018 -92.298012)
		(width 0.127)
		(layer "B.Cu")
		(net "EXP_XM_ADDR_4")
	)
	(segment
		(start 85.8012 -91.155012)
		(end 85.38718 -91.155012)
		(width 0.127)
		(layer "B.Cu")
		(net "EXP_XM_ADDR_4")
	)
	(segment
		(start 86.844124 -89.1794)
		(end 86.742524 -89.281)
		(width 0.127)
		(layer "B.Cu")
		(net "EXP_XM_ADDR_4")
	)
	(segment
		(start 85.26018 -91.282012)
		(end 85.26018 -91.536012)
		(width 0.127)
		(layer "B.Cu")
		(net "EXP_XM_ADDR_4")
	)
	(segment
		(start 88.5952 -89.7382)
		(end 87.402924 -89.7382)
		(width 0.127)
		(layer "B.Cu")
		(net "EXP_XM_ADDR_4")
	)
	(segment
		(start 85.26018 -90.520012)
		(end 85.38718 -90.647012)
		(width 0.127)
		(layer "B.Cu")
		(net "EXP_XM_ADDR_4")
	)
	(segment
		(start 85.8012 -90.647012)
		(end 85.9282 -90.774012)
		(width 0.127)
		(layer "B.Cu")
		(net "EXP_XM_ADDR_4")
	)
	(segment
		(start 89.001854 -90.574622)
		(end 89.126822 -90.449654)
		(width 0.127)
		(layer "B.Cu")
		(net "EXP_XM_ADDR_4")
	)
	(segment
		(start 87.402924 -89.7382)
		(end 87.250524 -89.5858)
		(width 0.127)
		(layer "B.Cu")
		(net "EXP_XM_ADDR_4")
	)
	(segment
		(start 87.250524 -89.5858)
		(end 87.250524 -89.281)
		(width 0.127)
		(layer "B.Cu")
		(net "EXP_XM_ADDR_4")
	)
	(segment
		(start 85.8012 -93.187012)
		(end 85.38718 -93.187012)
		(width 0.127)
		(layer "B.Cu")
		(net "EXP_XM_ADDR_4")
	)
	(segment
		(start 91.0336 -96.7994)
		(end 90.9066 -96.9264)
		(width 0.127)
		(layer "B.Cu")
		(net "EXP_XM_ADDR_4")
	)
	(segment
		(start 87.8078 -88.842342)
		(end 88.867742 -88.842342)
		(width 0.127)
		(layer "B.Cu")
		(net "EXP_XM_ADDR_4")
	)
	(segment
		(start 89.001854 -90.754454)
		(end 89.001854 -90.574622)
		(width 0.127)
		(layer "B.Cu")
		(net "EXP_XM_ADDR_4")
	)
	(segment
		(start 85.38718 -90.647012)
		(end 85.8012 -90.647012)
		(width 0.127)
		(layer "B.Cu")
		(net "EXP_XM_ADDR_4")
	)
	(segment
		(start 86.590124 -89.7382)
		(end 85.471 -89.7382)
		(width 0.127)
		(layer "B.Cu")
		(net "EXP_XM_ADDR_4")
	)
	(segment
		(start 90.9066 -96.9264)
		(end 90.17 -96.9264)
		(width 0.127)
		(layer "B.Cu")
		(net "EXP_XM_ADDR_4")
	)
	(segment
		(start 85.9282 -92.806012)
		(end 85.9282 -93.060012)
		(width 0.127)
		(layer "B.Cu")
		(net "EXP_XM_ADDR_4")
	)
	(segment
		(start 85.8012 -92.171012)
		(end 85.38718 -92.171012)
		(width 0.127)
		(layer "B.Cu")
		(net "EXP_XM_ADDR_4")
	)
	(segment
		(start 85.9282 -90.774012)
		(end 85.9282 -91.028012)
		(width 0.127)
		(layer "B.Cu")
		(net "EXP_XM_ADDR_4")
	)
	(segment
		(start 85.26018 -93.925898)
		(end 85.2678 -93.933518)
		(width 0.127)
		(layer "B.Cu")
		(net "EXP_XM_ADDR_4")
	)
	(segment
		(start 89.126822 -90.449654)
		(end 89.126822 -90.269822)
		(width 0.127)
		(layer "B.Cu")
		(net "EXP_XM_ADDR_4")
	)
	(segment
		(start 88.867742 -88.842342)
		(end 91.0336 -91.0082)
		(width 0.127)
		(layer "B.Cu")
		(net "EXP_XM_ADDR_4")
	)
	(segment
		(start 85.8012 -92.679012)
		(end 85.9282 -92.806012)
		(width 0.127)
		(layer "B.Cu")
		(net "EXP_XM_ADDR_4")
	)
	(segment
		(start 85.26018 -89.94902)
		(end 85.26018 -90.520012)
		(width 0.127)
		(layer "B.Cu")
		(net "EXP_XM_ADDR_4")
	)
	(segment
		(start 85.26018 -92.552012)
		(end 85.38718 -92.679012)
		(width 0.127)
		(layer "B.Cu")
		(net "EXP_XM_ADDR_4")
	)
	(segment
		(start 89.486232 -90.809064)
		(end 89.361264 -90.934032)
		(width 0.127)
		(layer "B.Cu")
		(net "EXP_XM_ADDR_4")
	)
	(segment
		(start 90.17 -96.9264)
		(end 90.043 -96.7994)
		(width 0.127)
		(layer "B.Cu")
		(net "EXP_XM_ADDR_4")
	)
	(segment
		(start 85.26018 -92.298012)
		(end 85.26018 -92.552012)
		(width 0.127)
		(layer "B.Cu")
		(net "EXP_XM_ADDR_4")
	)
	(segment
		(start 89.829386 -88.842342)
		(end 89.956386 -88.715342)
		(width 0.127)
		(layer "In2.Cu")
		(net "EXP_XM_ADDR_4")
	)
	(segment
		(start 102.49027 -88.842342)
		(end 103.533702 -88.842342)
		(width 0.127)
		(layer "In2.Cu")
		(net "EXP_XM_ADDR_4")
	)
	(segment
		(start 91.652852 -88.842342)
		(end 91.779852 -88.715342)
		(width 0.127)
		(layer "In2.Cu")
		(net "EXP_XM_ADDR_4")
	)
	(segment
		(start 101.22027 -88.1888)
		(end 101.34727 -88.3158)
		(width 0.127)
		(layer "In2.Cu")
		(net "EXP_XM_ADDR_4")
	)
	(segment
		(start 103.533702 -88.842342)
		(end 103.660702 -88.715342)
		(width 0.127)
		(layer "In2.Cu")
		(net "EXP_XM_ADDR_4")
	)
	(segment
		(start 101.85527 -88.715342)
		(end 101.85527 -88.3158)
		(width 0.127)
		(layer "In2.Cu")
		(net "EXP_XM_ADDR_4")
	)
	(segment
		(start 98.68027 -88.842342)
		(end 98.80727 -88.715342)
		(width 0.127)
		(layer "In2.Cu")
		(net "EXP_XM_ADDR_4")
	)
	(segment
		(start 98.80727 -88.3158)
		(end 98.93427 -88.1888)
		(width 0.127)
		(layer "In2.Cu")
		(net "EXP_XM_ADDR_4")
	)
	(segment
		(start 97.66427 -88.842342)
		(end 97.79127 -88.715342)
		(width 0.127)
		(layer "In2.Cu")
		(net "EXP_XM_ADDR_4")
	)
	(segment
		(start 87.8078 -88.842342)
		(end 88.813386 -88.842342)
		(width 0.127)
		(layer "In2.Cu")
		(net "EXP_XM_ADDR_4")
	)
	(segment
		(start 92.795852 -88.715342)
		(end 92.795852 -88.3158)
		(width 0.127)
		(layer "In2.Cu")
		(net "EXP_XM_ADDR_4")
	)
	(segment
		(start 106.193082 -88.842342)
		(end 106.320082 -88.715342)
		(width 0.127)
		(layer "In2.Cu")
		(net "EXP_XM_ADDR_4")
	)
	(segment
		(start 99.95027 -88.1888)
		(end 100.20427 -88.1888)
		(width 0.127)
		(layer "In2.Cu")
		(net "EXP_XM_ADDR_4")
	)
	(segment
		(start 89.448386 -88.715342)
		(end 89.575386 -88.842342)
		(width 0.127)
		(layer "In2.Cu")
		(net "EXP_XM_ADDR_4")
	)
	(segment
		(start 95.947738 -88.2142)
		(end 96.201738 -88.2142)
		(width 0.127)
		(layer "In2.Cu")
		(net "EXP_XM_ADDR_4")
	)
	(segment
		(start 97.79127 -88.3158)
		(end 97.91827 -88.1888)
		(width 0.127)
		(layer "In2.Cu")
		(net "EXP_XM_ADDR_4")
	)
	(segment
		(start 98.80727 -88.715342)
		(end 98.80727 -88.3158)
		(width 0.127)
		(layer "In2.Cu")
		(net "EXP_XM_ADDR_4")
	)
	(segment
		(start 107.463082 -88.1888)
		(end 107.717082 -88.1888)
		(width 0.127)
		(layer "In2.Cu")
		(net "EXP_XM_ADDR_4")
	)
	(segment
		(start 93.430852 -88.842342)
		(end 95.693738 -88.842342)
		(width 0.127)
		(layer "In2.Cu")
		(net "EXP_XM_ADDR_4")
	)
	(segment
		(start 90.083386 -88.1888)
		(end 90.337386 -88.1888)
		(width 0.127)
		(layer "In2.Cu")
		(net "EXP_XM_ADDR_4")
	)
	(segment
		(start 91.906852 -88.1888)
		(end 92.160852 -88.1888)
		(width 0.127)
		(layer "In2.Cu")
		(net "EXP_XM_ADDR_4")
	)
	(segment
		(start 107.717082 -88.1888)
		(end 107.844082 -88.3158)
		(width 0.127)
		(layer "In2.Cu")
		(net "EXP_XM_ADDR_4")
	)
	(segment
		(start 88.940386 -88.3158)
		(end 89.067386 -88.1888)
		(width 0.127)
		(layer "In2.Cu")
		(net "EXP_XM_ADDR_4")
	)
	(segment
		(start 106.701082 -88.1888)
		(end 106.828082 -88.3158)
		(width 0.127)
		(layer "In2.Cu")
		(net "EXP_XM_ADDR_4")
	)
	(segment
		(start 89.575386 -88.842342)
		(end 89.829386 -88.842342)
		(width 0.127)
		(layer "In2.Cu")
		(net "EXP_XM_ADDR_4")
	)
	(segment
		(start 96.328738 -88.715342)
		(end 96.455738 -88.842342)
		(width 0.127)
		(layer "In2.Cu")
		(net "EXP_XM_ADDR_4")
	)
	(segment
		(start 106.828082 -88.3158)
		(end 106.828082 -88.715342)
		(width 0.127)
		(layer "In2.Cu")
		(net "EXP_XM_ADDR_4")
	)
	(segment
		(start 103.660702 -88.3412)
		(end 103.787702 -88.2142)
		(width 0.127)
		(layer "In2.Cu")
		(net "EXP_XM_ADDR_4")
	)
	(segment
		(start 106.447082 -88.1888)
		(end 106.701082 -88.1888)
		(width 0.127)
		(layer "In2.Cu")
		(net "EXP_XM_ADDR_4")
	)
	(segment
		(start 109.9439 -88.370918)
		(end 109.9439 -88.222582)
		(width 0.127)
		(layer "In2.Cu")
		(net "EXP_XM_ADDR_4")
	)
	(segment
		(start 102.36327 -88.715342)
		(end 102.49027 -88.842342)
		(width 0.127)
		(layer "In2.Cu")
		(net "EXP_XM_ADDR_4")
	)
	(segment
		(start 107.209082 -88.842342)
		(end 107.336082 -88.715342)
		(width 0.127)
		(layer "In2.Cu")
		(net "EXP_XM_ADDR_4")
	)
	(segment
		(start 96.328738 -88.3412)
		(end 96.328738 -88.715342)
		(width 0.127)
		(layer "In2.Cu")
		(net "EXP_XM_ADDR_4")
	)
	(segment
		(start 100.33127 -88.715342)
		(end 100.45827 -88.842342)
		(width 0.127)
		(layer "In2.Cu")
		(net "EXP_XM_ADDR_4")
	)
	(segment
		(start 102.36327 -88.3158)
		(end 102.36327 -88.715342)
		(width 0.127)
		(layer "In2.Cu")
		(net "EXP_XM_ADDR_4")
	)
	(segment
		(start 90.464386 -88.3158)
		(end 90.464386 -88.715342)
		(width 0.127)
		(layer "In2.Cu")
		(net "EXP_XM_ADDR_4")
	)
	(segment
		(start 92.287852 -88.3158)
		(end 92.287852 -88.715342)
		(width 0.127)
		(layer "In2.Cu")
		(net "EXP_XM_ADDR_4")
	)
	(segment
		(start 101.98227 -88.1888)
		(end 102.23627 -88.1888)
		(width 0.127)
		(layer "In2.Cu")
		(net "EXP_XM_ADDR_4")
	)
	(segment
		(start 88.813386 -88.842342)
		(end 88.940386 -88.715342)
		(width 0.127)
		(layer "In2.Cu")
		(net "EXP_XM_ADDR_4")
	)
	(segment
		(start 107.844082 -88.3158)
		(end 107.844082 -88.715342)
		(width 0.127)
		(layer "In2.Cu")
		(net "EXP_XM_ADDR_4")
	)
	(segment
		(start 100.83927 -88.715342)
		(end 100.83927 -88.3158)
		(width 0.127)
		(layer "In2.Cu")
		(net "EXP_XM_ADDR_4")
	)
	(segment
		(start 99.44227 -88.842342)
		(end 99.69627 -88.842342)
		(width 0.127)
		(layer "In2.Cu")
		(net "EXP_XM_ADDR_4")
	)
	(segment
		(start 101.34727 -88.3158)
		(end 101.34727 -88.715342)
		(width 0.127)
		(layer "In2.Cu")
		(net "EXP_XM_ADDR_4")
	)
	(segment
		(start 98.93427 -88.1888)
		(end 99.18827 -88.1888)
		(width 0.127)
		(layer "In2.Cu")
		(net "EXP_XM_ADDR_4")
	)
	(segment
		(start 100.96627 -88.1888)
		(end 101.22027 -88.1888)
		(width 0.127)
		(layer "In2.Cu")
		(net "EXP_XM_ADDR_4")
	)
	(segment
		(start 92.287852 -88.715342)
		(end 92.414852 -88.842342)
		(width 0.127)
		(layer "In2.Cu")
		(net "EXP_XM_ADDR_4")
	)
	(segment
		(start 101.34727 -88.715342)
		(end 101.47427 -88.842342)
		(width 0.127)
		(layer "In2.Cu")
		(net "EXP_XM_ADDR_4")
	)
	(segment
		(start 107.971082 -88.842342)
		(end 109.472476 -88.842342)
		(width 0.127)
		(layer "In2.Cu")
		(net "EXP_XM_ADDR_4")
	)
	(segment
		(start 104.168702 -88.3412)
		(end 104.168702 -88.715342)
		(width 0.127)
		(layer "In2.Cu")
		(net "EXP_XM_ADDR_4")
	)
	(segment
		(start 104.295702 -88.842342)
		(end 106.193082 -88.842342)
		(width 0.127)
		(layer "In2.Cu")
		(net "EXP_XM_ADDR_4")
	)
	(segment
		(start 96.455738 -88.842342)
		(end 97.66427 -88.842342)
		(width 0.127)
		(layer "In2.Cu")
		(net "EXP_XM_ADDR_4")
	)
	(segment
		(start 90.591386 -88.842342)
		(end 91.652852 -88.842342)
		(width 0.127)
		(layer "In2.Cu")
		(net "EXP_XM_ADDR_4")
	)
	(segment
		(start 101.85527 -88.3158)
		(end 101.98227 -88.1888)
		(width 0.127)
		(layer "In2.Cu")
		(net "EXP_XM_ADDR_4")
	)
	(segment
		(start 98.42627 -88.842342)
		(end 98.68027 -88.842342)
		(width 0.127)
		(layer "In2.Cu")
		(net "EXP_XM_ADDR_4")
	)
	(segment
		(start 109.9439 -88.222582)
		(end 111.044482 -87.122)
		(width 0.127)
		(layer "In2.Cu")
		(net "EXP_XM_ADDR_4")
	)
	(segment
		(start 99.31527 -88.3158)
		(end 99.31527 -88.715342)
		(width 0.127)
		(layer "In2.Cu")
		(net "EXP_XM_ADDR_4")
	)
	(segment
		(start 92.922852 -88.1888)
		(end 93.176852 -88.1888)
		(width 0.127)
		(layer "In2.Cu")
		(net "EXP_XM_ADDR_4")
	)
	(segment
		(start 98.29927 -88.715342)
		(end 98.42627 -88.842342)
		(width 0.127)
		(layer "In2.Cu")
		(net "EXP_XM_ADDR_4")
	)
	(segment
		(start 99.18827 -88.1888)
		(end 99.31527 -88.3158)
		(width 0.127)
		(layer "In2.Cu")
		(net "EXP_XM_ADDR_4")
	)
	(segment
		(start 92.414852 -88.842342)
		(end 92.668852 -88.842342)
		(width 0.127)
		(layer "In2.Cu")
		(net "EXP_XM_ADDR_4")
	)
	(segment
		(start 91.779852 -88.3158)
		(end 91.906852 -88.1888)
		(width 0.127)
		(layer "In2.Cu")
		(net "EXP_XM_ADDR_4")
	)
	(segment
		(start 101.72827 -88.842342)
		(end 101.85527 -88.715342)
		(width 0.127)
		(layer "In2.Cu")
		(net "EXP_XM_ADDR_4")
	)
	(segment
		(start 95.820738 -88.3412)
		(end 95.947738 -88.2142)
		(width 0.127)
		(layer "In2.Cu")
		(net "EXP_XM_ADDR_4")
	)
	(segment
		(start 99.82327 -88.715342)
		(end 99.82327 -88.3158)
		(width 0.127)
		(layer "In2.Cu")
		(net "EXP_XM_ADDR_4")
	)
	(segment
		(start 112.2934 -87.122)
		(end 112.8014 -86.614)
		(width 0.127)
		(layer "In2.Cu")
		(net "EXP_XM_ADDR_4")
	)
	(segment
		(start 104.168702 -88.715342)
		(end 104.295702 -88.842342)
		(width 0.127)
		(layer "In2.Cu")
		(net "EXP_XM_ADDR_4")
	)
	(segment
		(start 97.91827 -88.1888)
		(end 98.17227 -88.1888)
		(width 0.127)
		(layer "In2.Cu")
		(net "EXP_XM_ADDR_4")
	)
	(segment
		(start 88.940386 -88.715342)
		(end 88.940386 -88.3158)
		(width 0.127)
		(layer "In2.Cu")
		(net "EXP_XM_ADDR_4")
	)
	(segment
		(start 95.693738 -88.842342)
		(end 95.820738 -88.715342)
		(width 0.127)
		(layer "In2.Cu")
		(net "EXP_XM_ADDR_4")
	)
	(segment
		(start 100.20427 -88.1888)
		(end 100.33127 -88.3158)
		(width 0.127)
		(layer "In2.Cu")
		(net "EXP_XM_ADDR_4")
	)
	(segment
		(start 93.303852 -88.3158)
		(end 93.303852 -88.715342)
		(width 0.127)
		(layer "In2.Cu")
		(net "EXP_XM_ADDR_4")
	)
	(segment
		(start 99.69627 -88.842342)
		(end 99.82327 -88.715342)
		(width 0.127)
		(layer "In2.Cu")
		(net "EXP_XM_ADDR_4")
	)
	(segment
		(start 106.828082 -88.715342)
		(end 106.955082 -88.842342)
		(width 0.127)
		(layer "In2.Cu")
		(net "EXP_XM_ADDR_4")
	)
	(segment
		(start 89.067386 -88.1888)
		(end 89.321386 -88.1888)
		(width 0.127)
		(layer "In2.Cu")
		(net "EXP_XM_ADDR_4")
	)
	(segment
		(start 111.044482 -87.122)
		(end 112.2934 -87.122)
		(width 0.127)
		(layer "In2.Cu")
		(net "EXP_XM_ADDR_4")
	)
	(segment
		(start 103.787702 -88.2142)
		(end 104.041702 -88.2142)
		(width 0.127)
		(layer "In2.Cu")
		(net "EXP_XM_ADDR_4")
	)
	(segment
		(start 103.660702 -88.715342)
		(end 103.660702 -88.3412)
		(width 0.127)
		(layer "In2.Cu")
		(net "EXP_XM_ADDR_4")
	)
	(segment
		(start 92.160852 -88.1888)
		(end 92.287852 -88.3158)
		(width 0.127)
		(layer "In2.Cu")
		(net "EXP_XM_ADDR_4")
	)
	(segment
		(start 104.041702 -88.2142)
		(end 104.168702 -88.3412)
		(width 0.127)
		(layer "In2.Cu")
		(net "EXP_XM_ADDR_4")
	)
	(segment
		(start 97.79127 -88.715342)
		(end 97.79127 -88.3158)
		(width 0.127)
		(layer "In2.Cu")
		(net "EXP_XM_ADDR_4")
	)
	(segment
		(start 100.33127 -88.3158)
		(end 100.33127 -88.715342)
		(width 0.127)
		(layer "In2.Cu")
		(net "EXP_XM_ADDR_4")
	)
	(segment
		(start 93.176852 -88.1888)
		(end 93.303852 -88.3158)
		(width 0.127)
		(layer "In2.Cu")
		(net "EXP_XM_ADDR_4")
	)
	(segment
		(start 96.201738 -88.2142)
		(end 96.328738 -88.3412)
		(width 0.127)
		(layer "In2.Cu")
		(net "EXP_XM_ADDR_4")
	)
	(segment
		(start 107.336082 -88.3158)
		(end 107.463082 -88.1888)
		(width 0.127)
		(layer "In2.Cu")
		(net "EXP_XM_ADDR_4")
	)
	(segment
		(start 100.83927 -88.3158)
		(end 100.96627 -88.1888)
		(width 0.127)
		(layer "In2.Cu")
		(net "EXP_XM_ADDR_4")
	)
	(segment
		(start 89.956386 -88.3158)
		(end 90.083386 -88.1888)
		(width 0.127)
		(layer "In2.Cu")
		(net "EXP_XM_ADDR_4")
	)
	(segment
		(start 91.779852 -88.715342)
		(end 91.779852 -88.3158)
		(width 0.127)
		(layer "In2.Cu")
		(net "EXP_XM_ADDR_4")
	)
	(segment
		(start 107.336082 -88.715342)
		(end 107.336082 -88.3158)
		(width 0.127)
		(layer "In2.Cu")
		(net "EXP_XM_ADDR_4")
	)
	(segment
		(start 106.320082 -88.3158)
		(end 106.447082 -88.1888)
		(width 0.127)
		(layer "In2.Cu")
		(net "EXP_XM_ADDR_4")
	)
	(segment
		(start 101.47427 -88.842342)
		(end 101.72827 -88.842342)
		(width 0.127)
		(layer "In2.Cu")
		(net "EXP_XM_ADDR_4")
	)
	(segment
		(start 106.955082 -88.842342)
		(end 107.209082 -88.842342)
		(width 0.127)
		(layer "In2.Cu")
		(net "EXP_XM_ADDR_4")
	)
	(segment
		(start 106.320082 -88.715342)
		(end 106.320082 -88.3158)
		(width 0.127)
		(layer "In2.Cu")
		(net "EXP_XM_ADDR_4")
	)
	(segment
		(start 102.23627 -88.1888)
		(end 102.36327 -88.3158)
		(width 0.127)
		(layer "In2.Cu")
		(net "EXP_XM_ADDR_4")
	)
	(segment
		(start 109.472476 -88.842342)
		(end 109.9439 -88.370918)
		(width 0.127)
		(layer "In2.Cu")
		(net "EXP_XM_ADDR_4")
	)
	(segment
		(start 92.795852 -88.3158)
		(end 92.922852 -88.1888)
		(width 0.127)
		(layer "In2.Cu")
		(net "EXP_XM_ADDR_4")
	)
	(segment
		(start 89.321386 -88.1888)
		(end 89.448386 -88.3158)
		(width 0.127)
		(layer "In2.Cu")
		(net "EXP_XM_ADDR_4")
	)
	(segment
		(start 90.464386 -88.715342)
		(end 90.591386 -88.842342)
		(width 0.127)
		(layer "In2.Cu")
		(net "EXP_XM_ADDR_4")
	)
	(segment
		(start 93.303852 -88.715342)
		(end 93.430852 -88.842342)
		(width 0.127)
		(layer "In2.Cu")
		(net "EXP_XM_ADDR_4")
	)
	(segment
		(start 107.844082 -88.715342)
		(end 107.971082 -88.842342)
		(width 0.127)
		(layer "In2.Cu")
		(net "EXP_XM_ADDR_4")
	)
	(segment
		(start 89.956386 -88.715342)
		(end 89.956386 -88.3158)
		(width 0.127)
		(layer "In2.Cu")
		(net "EXP_XM_ADDR_4")
	)
	(segment
		(start 90.337386 -88.1888)
		(end 90.464386 -88.3158)
		(width 0.127)
		(layer "In2.Cu")
		(net "EXP_XM_ADDR_4")
	)
	(segment
		(start 95.820738 -88.715342)
		(end 95.820738 -88.3412)
		(width 0.127)
		(layer "In2.Cu")
		(net "EXP_XM_ADDR_4")
	)
	(segment
		(start 98.29927 -88.3158)
		(end 98.29927 -88.715342)
		(width 0.127)
		(layer "In2.Cu")
		(net "EXP_XM_ADDR_4")
	)
	(segment
		(start 100.45827 -88.842342)
		(end 100.71227 -88.842342)
		(width 0.127)
		(layer "In2.Cu")
		(net "EXP_XM_ADDR_4")
	)
	(segment
		(start 92.668852 -88.842342)
		(end 92.795852 -88.715342)
		(width 0.127)
		(layer "In2.Cu")
		(net "EXP_XM_ADDR_4")
	)
	(segment
		(start 89.448386 -88.3158)
		(end 89.448386 -88.715342)
		(width 0.127)
		(layer "In2.Cu")
		(net "EXP_XM_ADDR_4")
	)
	(segment
		(start 99.31527 -88.715342)
		(end 99.44227 -88.842342)
		(width 0.127)
		(layer "In2.Cu")
		(net "EXP_XM_ADDR_4")
	)
	(segment
		(start 98.17227 -88.1888)
		(end 98.29927 -88.3158)
		(width 0.127)
		(layer "In2.Cu")
		(net "EXP_XM_ADDR_4")
	)
	(segment
		(start 100.71227 -88.842342)
		(end 100.83927 -88.715342)
		(width 0.127)
		(layer "In2.Cu")
		(net "EXP_XM_ADDR_4")
	)
	(segment
		(start 99.82327 -88.3158)
		(end 99.95027 -88.1888)
		(width 0.127)
		(layer "In2.Cu")
		(net "EXP_XM_ADDR_4")
	)
	(segment
		(start 116.9162 -85.09)
		(end 116.7892 -85.217)
		(width 0.127)
		(layer "F.Cu")
		(net "EXP_XM_ADDR_3")
	)
	(segment
		(start 116.05514 -82.445352)
		(end 115.50015 -81.890362)
		(width 0.127)
		(layer "F.Cu")
		(net "EXP_XM_ADDR_3")
	)
	(segment
		(start 116.7892 -85.217)
		(end 116.205 -85.217)
		(width 0.127)
		(layer "F.Cu")
		(net "EXP_XM_ADDR_3")
	)
	(segment
		(start 116.9162 -84.709)
		(end 116.9162 -85.09)
		(width 0.127)
		(layer "F.Cu")
		(net "EXP_XM_ADDR_3")
	)
	(segment
		(start 116.05514 -85.06714)
		(end 116.05514 -82.445352)
		(width 0.127)
		(layer "F.Cu")
		(net "EXP_XM_ADDR_3")
	)
	(segment
		(start 115.50015 -81.890362)
		(end 115.50015 -81.500218)
		(width 0.127)
		(layer "F.Cu")
		(net "EXP_XM_ADDR_3")
	)
	(segment
		(start 116.205 -85.217)
		(end 116.05514 -85.06714)
		(width 0.127)
		(layer "F.Cu")
		(net "EXP_XM_ADDR_3")
	)
	(via
		(at 86.45525 -92.949776)
		(size 0.508)
		(drill 0.254)
		(layers "F.Cu" "B.Cu")
		(net "EXP_XM_ADDR_3")
	)
	(via
		(at 116.9162 -84.709)
		(size 0.508)
		(drill 0.254)
		(layers "F.Cu" "B.Cu")
		(net "EXP_XM_ADDR_3")
	)
	(segment
		(start 87.757 -93.7006)
		(end 87.884 -93.8276)
		(width 0.127)
		(layer "B.Cu")
		(net "EXP_XM_ADDR_3")
	)
	(segment
		(start 87.1982 -90.3732)
		(end 87.0712 -90.2462)
		(width 0.127)
		(layer "B.Cu")
		(net "EXP_XM_ADDR_3")
	)
	(segment
		(start 87.884 -96.1898)
		(end 88.011 -96.3168)
		(width 0.127)
		(layer "B.Cu")
		(net "EXP_XM_ADDR_3")
	)
	(segment
		(start 89.535 -96.1898)
		(end 89.535 -91.5924)
		(width 0.127)
		(layer "B.Cu")
		(net "EXP_XM_ADDR_3")
	)
	(segment
		(start 86.45525 -90.3732)
		(end 86.45525 -92.949776)
		(width 0.127)
		(layer "B.Cu")
		(net "EXP_XM_ADDR_3")
	)
	(segment
		(start 88.011 -96.3168)
		(end 89.408 -96.3168)
		(width 0.127)
		(layer "B.Cu")
		(net "EXP_XM_ADDR_3")
	)
	(segment
		(start 89.027 -91.5924)
		(end 89.027 -95.5294)
		(width 0.127)
		(layer "B.Cu")
		(net "EXP_XM_ADDR_3")
	)
	(segment
		(start 89.027 -95.5294)
		(end 88.9 -95.6564)
		(width 0.127)
		(layer "B.Cu")
		(net "EXP_XM_ADDR_3")
	)
	(segment
		(start 87.9348 -90.3732)
		(end 87.9348 -93.0148)
		(width 0.127)
		(layer "B.Cu")
		(net "EXP_XM_ADDR_3")
	)
	(segment
		(start 89.408 -91.4654)
		(end 89.154 -91.4654)
		(width 0.127)
		(layer "B.Cu")
		(net "EXP_XM_ADDR_3")
	)
	(segment
		(start 87.0712 -90.2462)
		(end 86.58225 -90.2462)
		(width 0.127)
		(layer "B.Cu")
		(net "EXP_XM_ADDR_3")
	)
	(segment
		(start 87.3252 -93.1418)
		(end 87.1982 -93.0148)
		(width 0.127)
		(layer "B.Cu")
		(net "EXP_XM_ADDR_3")
	)
	(segment
		(start 86.58225 -90.2462)
		(end 86.45525 -90.3732)
		(width 0.127)
		(layer "B.Cu")
		(net "EXP_XM_ADDR_3")
	)
	(segment
		(start 87.9348 -93.0148)
		(end 87.8078 -93.1418)
		(width 0.127)
		(layer "B.Cu")
		(net "EXP_XM_ADDR_3")
	)
	(segment
		(start 88.5952 -95.6564)
		(end 88.4682 -95.5294)
		(width 0.127)
		(layer "B.Cu")
		(net "EXP_XM_ADDR_3")
	)
	(segment
		(start 87.884 -93.8276)
		(end 87.884 -96.1898)
		(width 0.127)
		(layer "B.Cu")
		(net "EXP_XM_ADDR_3")
	)
	(segment
		(start 89.154 -91.4654)
		(end 89.027 -91.5924)
		(width 0.127)
		(layer "B.Cu")
		(net "EXP_XM_ADDR_3")
	)
	(segment
		(start 85.76818 -93.8276)
		(end 85.89518 -93.7006)
		(width 0.127)
		(layer "B.Cu")
		(net "EXP_XM_ADDR_3")
	)
	(segment
		(start 88.9 -95.6564)
		(end 88.5952 -95.6564)
		(width 0.127)
		(layer "B.Cu")
		(net "EXP_XM_ADDR_3")
	)
	(segment
		(start 87.8078 -93.1418)
		(end 87.3252 -93.1418)
		(width 0.127)
		(layer "B.Cu")
		(net "EXP_XM_ADDR_3")
	)
	(segment
		(start 85.76818 -94.8309)
		(end 85.76818 -93.8276)
		(width 0.127)
		(layer "B.Cu")
		(net "EXP_XM_ADDR_3")
	)
	(segment
		(start 89.535 -91.5924)
		(end 89.408 -91.4654)
		(width 0.127)
		(layer "B.Cu")
		(net "EXP_XM_ADDR_3")
	)
	(segment
		(start 88.3412 -90.2462)
		(end 88.0618 -90.2462)
		(width 0.127)
		(layer "B.Cu")
		(net "EXP_XM_ADDR_3")
	)
	(segment
		(start 87.1982 -93.0148)
		(end 87.1982 -90.3732)
		(width 0.127)
		(layer "B.Cu")
		(net "EXP_XM_ADDR_3")
	)
	(segment
		(start 88.4682 -90.3732)
		(end 88.3412 -90.2462)
		(width 0.127)
		(layer "B.Cu")
		(net "EXP_XM_ADDR_3")
	)
	(segment
		(start 88.4682 -95.5294)
		(end 88.4682 -90.3732)
		(width 0.127)
		(layer "B.Cu")
		(net "EXP_XM_ADDR_3")
	)
	(segment
		(start 88.0618 -90.2462)
		(end 87.9348 -90.3732)
		(width 0.127)
		(layer "B.Cu")
		(net "EXP_XM_ADDR_3")
	)
	(segment
		(start 85.89518 -93.7006)
		(end 87.757 -93.7006)
		(width 0.127)
		(layer "B.Cu")
		(net "EXP_XM_ADDR_3")
	)
	(segment
		(start 89.408 -96.3168)
		(end 89.535 -96.1898)
		(width 0.127)
		(layer "B.Cu")
		(net "EXP_XM_ADDR_3")
	)
	(segment
		(start 116.7892 -83.0326)
		(end 116.9162 -83.1596)
		(width 0.127)
		(layer "In2.Cu")
		(net "EXP_XM_ADDR_3")
	)
	(segment
		(start 116.9162 -83.1596)
		(end 116.9162 -84.709)
		(width 0.127)
		(layer "In2.Cu")
		(net "EXP_XM_ADDR_3")
	)
	(segment
		(start 86.45525 -92.949776)
		(end 86.464648 -92.959174)
		(width 0.127)
		(layer "In2.Cu")
		(net "EXP_XM_ADDR_3")
	)
	(segment
		(start 116.0653 -83.0326)
		(end 116.7892 -83.0326)
		(width 0.127)
		(layer "In2.Cu")
		(net "EXP_XM_ADDR_3")
	)
	(segment
		(start 116.4717 -90.042492)
		(end 116.4717 -85.5218)
		(width 0.127)
		(layer "In2.Cu")
		(net "EXP_XM_ADDR_3")
	)
	(segment
		(start 115.9383 -84.9884)
		(end 115.9383 -83.1596)
		(width 0.127)
		(layer "In2.Cu")
		(net "EXP_XM_ADDR_3")
	)
	(segment
		(start 116.4717 -85.5218)
		(end 115.9383 -84.9884)
		(width 0.127)
		(layer "In2.Cu")
		(net "EXP_XM_ADDR_3")
	)
	(segment
		(start 113.555018 -92.959174)
		(end 116.4717 -90.042492)
		(width 0.127)
		(layer "In2.Cu")
		(net "EXP_XM_ADDR_3")
	)
	(segment
		(start 86.464648 -92.959174)
		(end 113.555018 -92.959174)
		(width 0.127)
		(layer "In2.Cu")
		(net "EXP_XM_ADDR_3")
	)
	(segment
		(start 115.9383 -83.1596)
		(end 116.0653 -83.0326)
		(width 0.127)
		(layer "In2.Cu")
		(net "EXP_XM_ADDR_3")
	)
	(segment
		(start 115.2144 -86.6394)
		(end 115.7986 -86.6394)
		(width 0.127)
		(layer "F.Cu")
		(net "EXP_XM_ADDR_25")
	)
	(segment
		(start 115.7986 -86.6394)
		(end 115.7986 -86.294722)
		(width 0.127)
		(layer "F.Cu")
		(net "EXP_XM_ADDR_25")
	)
	(segment
		(start 115.4938 -85.989922)
		(end 115.4938 -82.506566)
		(width 0.127)
		(layer "F.Cu")
		(net "EXP_XM_ADDR_25")
	)
	(segment
		(start 115.4938 -82.506566)
		(end 115.50015 -82.500216)
		(width 0.127)
		(layer "F.Cu")
		(net "EXP_XM_ADDR_25")
	)
	(segment
		(start 114.6556 -86.5505)
		(end 113.6142 -86.5505)
		(width 0.127)
		(layer "F.Cu")
		(net "EXP_XM_ADDR_25")
	)
	(segment
		(start 115.1255 -86.5505)
		(end 115.2144 -86.6394)
		(width 0.127)
		(layer "F.Cu")
		(net "EXP_XM_ADDR_25")
	)
	(segment
		(start 114.6556 -86.5505)
		(end 115.1255 -86.5505)
		(width 0.127)
		(layer "F.Cu")
		(net "EXP_XM_ADDR_25")
	)
	(segment
		(start 115.7986 -86.294722)
		(end 115.4938 -85.989922)
		(width 0.127)
		(layer "F.Cu")
		(net "EXP_XM_ADDR_25")
	)
	(segment
		(start 113.4999 -73.500234)
		(end 113.999772 -74.000106)
		(width 0.127)
		(layer "F.Cu")
		(net "EXP_XM_ADDR_24")
	)
	(via
		(at 113.999772 -74.000106)
		(size 0.4572)
		(drill 0.2032)
		(layers "F.Cu" "B.Cu")
		(net "EXP_XM_ADDR_24")
	)
	(segment
		(start 112.498632 -74.497692)
		(end 113.502186 -74.497692)
		(width 0.127)
		(layer "B.Cu")
		(net "EXP_XM_ADDR_24")
	)
	(segment
		(start 113.502186 -74.497692)
		(end 113.999772 -74.000106)
		(width 0.127)
		(layer "B.Cu")
		(net "EXP_XM_ADDR_24")
	)
	(segment
		(start 115.50015 -80.50022)
		(end 116.000022 -81.000092)
		(width 0.127)
		(layer "F.Cu")
		(net "EXP_XM_ADDR_23")
	)
	(via
		(at 117.0432 -85.740748)
		(size 0.508)
		(drill 0.254)
		(layers "F.Cu" "B.Cu")
		(net "EXP_XM_ADDR_23")
	)
	(via
		(at 72.9869 -90.8558)
		(size 0.508)
		(drill 0.254)
		(layers "F.Cu" "B.Cu")
		(net "EXP_XM_ADDR_23")
	)
	(via
		(at 116.000022 -81.000092)
		(size 0.4572)
		(drill 0.2032)
		(layers "F.Cu" "B.Cu")
		(net "EXP_XM_ADDR_23")
	)
	(segment
		(start 117.852952 -86.5505)
		(end 117.0432 -85.740748)
		(width 0.127)
		(layer "B.Cu")
		(net "EXP_XM_ADDR_23")
	)
	(segment
		(start 72.9869 -92.577666)
		(end 74.26833 -93.859096)
		(width 0.127)
		(layer "B.Cu")
		(net "EXP_XM_ADDR_23")
	)
	(segment
		(start 74.26833 -93.859096)
		(end 74.26833 -94.8309)
		(width 0.127)
		(layer "B.Cu")
		(net "EXP_XM_ADDR_23")
	)
	(segment
		(start 117.0432 -85.3186)
		(end 117.399562 -84.962238)
		(width 0.127)
		(layer "B.Cu")
		(net "EXP_XM_ADDR_23")
	)
	(segment
		(start 117.399562 -84.21497)
		(end 116.807996 -83.623404)
		(width 0.127)
		(layer "B.Cu")
		(net "EXP_XM_ADDR_23")
	)
	(segment
		(start 117.856 -86.5505)
		(end 117.852952 -86.5505)
		(width 0.127)
		(layer "B.Cu")
		(net "EXP_XM_ADDR_23")
	)
	(segment
		(start 117.0432 -85.740748)
		(end 117.0432 -85.3186)
		(width 0.127)
		(layer "B.Cu")
		(net "EXP_XM_ADDR_23")
	)
	(segment
		(start 116.000022 -81.151222)
		(end 116.000022 -81.000092)
		(width 0.127)
		(layer "B.Cu")
		(net "EXP_XM_ADDR_23")
	)
	(segment
		(start 72.9869 -90.8558)
		(end 72.9869 -92.577666)
		(width 0.127)
		(layer "B.Cu")
		(net "EXP_XM_ADDR_23")
	)
	(segment
		(start 116.807996 -81.959196)
		(end 116.000022 -81.151222)
		(width 0.127)
		(layer "B.Cu")
		(net "EXP_XM_ADDR_23")
	)
	(segment
		(start 117.399562 -84.962238)
		(end 117.399562 -84.21497)
		(width 0.127)
		(layer "B.Cu")
		(net "EXP_XM_ADDR_23")
	)
	(segment
		(start 116.807996 -83.623404)
		(end 116.807996 -81.959196)
		(width 0.127)
		(layer "B.Cu")
		(net "EXP_XM_ADDR_23")
	)
	(segment
		(start 69.5198 -92.369386)
		(end 69.5198 -92.075)
		(width 0.127)
		(layer "In2.Cu")
		(net "EXP_XM_ADDR_23")
	)
	(segment
		(start 74.741786 -91.313)
		(end 73.5584 -92.496386)
		(width 0.127)
		(layer "In2.Cu")
		(net "EXP_XM_ADDR_23")
	)
	(segment
		(start 69.6468 -91.948)
		(end 73.1266 -91.948)
		(width 0.127)
		(layer "In2.Cu")
		(net "EXP_XM_ADDR_23")
	)
	(segment
		(start 68.9102 -90.8558)
		(end 72.9869 -90.8558)
		(width 0.127)
		(layer "In2.Cu")
		(net "EXP_XM_ADDR_23")
	)
	(segment
		(start 80.361536 -91.313)
		(end 74.741786 -91.313)
		(width 0.127)
		(layer "In2.Cu")
		(net "EXP_XM_ADDR_23")
	)
	(segment
		(start 117.0432 -85.740748)
		(end 116.9797 -85.804248)
		(width 0.127)
		(layer "In2.Cu")
		(net "EXP_XM_ADDR_23")
	)
	(segment
		(start 82.542634 -91.874086)
		(end 80.922622 -91.874086)
		(width 0.127)
		(layer "In2.Cu")
		(net "EXP_XM_ADDR_23")
	)
	(segment
		(start 73.5584 -92.496386)
		(end 69.6468 -92.496386)
		(width 0.127)
		(layer "In2.Cu")
		(net "EXP_XM_ADDR_23")
	)
	(segment
		(start 68.7832 -90.9828)
		(end 68.9102 -90.8558)
		(width 0.127)
		(layer "In2.Cu")
		(net "EXP_XM_ADDR_23")
	)
	(segment
		(start 85.720174 -92.959174)
		(end 83.627722 -92.959174)
		(width 0.127)
		(layer "In2.Cu")
		(net "EXP_XM_ADDR_23")
	)
	(segment
		(start 116.9797 -85.804248)
		(end 116.9797 -90.253058)
		(width 0.127)
		(layer "In2.Cu")
		(net "EXP_XM_ADDR_23")
	)
	(segment
		(start 73.1266 -91.44)
		(end 68.9102 -91.44)
		(width 0.127)
		(layer "In2.Cu")
		(net "EXP_XM_ADDR_23")
	)
	(segment
		(start 68.7832 -91.313)
		(end 68.7832 -90.9828)
		(width 0.127)
		(layer "In2.Cu")
		(net "EXP_XM_ADDR_23")
	)
	(segment
		(start 116.9797 -90.253058)
		(end 113.765584 -93.467174)
		(width 0.127)
		(layer "In2.Cu")
		(net "EXP_XM_ADDR_23")
	)
	(segment
		(start 68.9102 -91.44)
		(end 68.7832 -91.313)
		(width 0.127)
		(layer "In2.Cu")
		(net "EXP_XM_ADDR_23")
	)
	(segment
		(start 73.1266 -91.948)
		(end 73.2536 -91.821)
		(width 0.127)
		(layer "In2.Cu")
		(net "EXP_XM_ADDR_23")
	)
	(segment
		(start 113.765584 -93.467174)
		(end 86.228174 -93.467174)
		(width 0.127)
		(layer "In2.Cu")
		(net "EXP_XM_ADDR_23")
	)
	(segment
		(start 83.627722 -92.959174)
		(end 82.542634 -91.874086)
		(width 0.127)
		(layer "In2.Cu")
		(net "EXP_XM_ADDR_23")
	)
	(segment
		(start 73.2536 -91.567)
		(end 73.1266 -91.44)
		(width 0.127)
		(layer "In2.Cu")
		(net "EXP_XM_ADDR_23")
	)
	(segment
		(start 73.2536 -91.821)
		(end 73.2536 -91.567)
		(width 0.127)
		(layer "In2.Cu")
		(net "EXP_XM_ADDR_23")
	)
	(segment
		(start 69.5198 -92.075)
		(end 69.6468 -91.948)
		(width 0.127)
		(layer "In2.Cu")
		(net "EXP_XM_ADDR_23")
	)
	(segment
		(start 69.6468 -92.496386)
		(end 69.5198 -92.369386)
		(width 0.127)
		(layer "In2.Cu")
		(net "EXP_XM_ADDR_23")
	)
	(segment
		(start 86.228174 -93.467174)
		(end 85.720174 -92.959174)
		(width 0.127)
		(layer "In2.Cu")
		(net "EXP_XM_ADDR_23")
	)
	(segment
		(start 80.922622 -91.874086)
		(end 80.361536 -91.313)
		(width 0.127)
		(layer "In2.Cu")
		(net "EXP_XM_ADDR_23")
	)
	(segment
		(start 114.499898 -78.500224)
		(end 114.000026 -78.000352)
		(width 0.127)
		(layer "F.Cu")
		(net "EXP_XM_ADDR_22")
	)
	(via
		(at 114.000026 -78.000352)
		(size 0.4572)
		(drill 0.2032)
		(layers "F.Cu" "B.Cu")
		(net "EXP_XM_ADDR_22")
	)
	(via
		(at 80.2767 -86.9188)
		(size 0.508)
		(drill 0.254)
		(layers "F.Cu" "B.Cu")
		(net "EXP_XM_ADDR_22")
	)
	(segment
		(start 80.77581 -94.063566)
		(end 80.77581 -93.92539)
		(width 0.127)
		(layer "B.Cu")
		(net "EXP_XM_ADDR_22")
	)
	(segment
		(start 76.4032 -84.709)
		(end 76.5302 -84.582)
		(width 0.127)
		(layer "B.Cu")
		(net "EXP_XM_ADDR_22")
	)
	(segment
		(start 77.9272 -84.6074)
		(end 78.1812 -84.6074)
		(width 0.127)
		(layer "B.Cu")
		(net "EXP_XM_ADDR_22")
	)
	(segment
		(start 77.8002 -84.4804)
		(end 77.9272 -84.6074)
		(width 0.127)
		(layer "B.Cu")
		(net "EXP_XM_ADDR_22")
	)
	(segment
		(start 79.9338 -85.07349)
		(end 80.2132 -85.35289)
		(width 0.127)
		(layer "B.Cu")
		(net "EXP_XM_ADDR_22")
	)
	(segment
		(start 76.5302 -84.068666)
		(end 76.4032 -83.941666)
		(width 0.127)
		(layer "B.Cu")
		(net "EXP_XM_ADDR_22")
	)
	(segment
		(start 78.3082 -84.4804)
		(end 78.3082 -80.4164)
		(width 0.127)
		(layer "B.Cu")
		(net "EXP_XM_ADDR_22")
	)
	(segment
		(start 78.1812 -84.6074)
		(end 78.3082 -84.4804)
		(width 0.127)
		(layer "B.Cu")
		(net "EXP_XM_ADDR_22")
	)
	(segment
		(start 77.1398 -83.560666)
		(end 77.2922 -83.408266)
		(width 0.127)
		(layer "B.Cu")
		(net "EXP_XM_ADDR_22")
	)
	(segment
		(start 80.2132 -86.8553)
		(end 80.2767 -86.9188)
		(width 0.127)
		(layer "B.Cu")
		(net "EXP_XM_ADDR_22")
	)
	(segment
		(start 77.1398 -84.068666)
		(end 76.5302 -84.068666)
		(width 0.127)
		(layer "B.Cu")
		(net "EXP_XM_ADDR_22")
	)
	(segment
		(start 77.4192 -82.931)
		(end 77.6732 -82.931)
		(width 0.127)
		(layer "B.Cu")
		(net "EXP_XM_ADDR_22")
	)
	(segment
		(start 78.3082 -80.4164)
		(end 78.4352 -80.2894)
		(width 0.127)
		(layer "B.Cu")
		(net "EXP_XM_ADDR_22")
	)
	(segment
		(start 78.8924 -84.5566)
		(end 79.8068 -84.5566)
		(width 0.127)
		(layer "B.Cu")
		(net "EXP_XM_ADDR_22")
	)
	(segment
		(start 80.2132 -85.35289)
		(end 80.2132 -86.8553)
		(width 0.127)
		(layer "B.Cu")
		(net "EXP_XM_ADDR_22")
	)
	(segment
		(start 77.6732 -82.931)
		(end 77.8002 -83.058)
		(width 0.127)
		(layer "B.Cu")
		(net "EXP_XM_ADDR_22")
	)
	(segment
		(start 77.2668 -84.195666)
		(end 77.1398 -84.068666)
		(width 0.127)
		(layer "B.Cu")
		(net "EXP_XM_ADDR_22")
	)
	(segment
		(start 78.8162 -84.4804)
		(end 78.8924 -84.5566)
		(width 0.127)
		(layer "B.Cu")
		(net "EXP_XM_ADDR_22")
	)
	(segment
		(start 80.77581 -93.92539)
		(end 80.908652 -93.792548)
		(width 0.127)
		(layer "B.Cu")
		(net "EXP_XM_ADDR_22")
	)
	(segment
		(start 80.76819 -94.071186)
		(end 80.77581 -94.063566)
		(width 0.127)
		(layer "B.Cu")
		(net "EXP_XM_ADDR_22")
	)
	(segment
		(start 76.5302 -85.1662)
		(end 76.4032 -85.0392)
		(width 0.127)
		(layer "B.Cu")
		(net "EXP_XM_ADDR_22")
	)
	(segment
		(start 78.6892 -80.2894)
		(end 78.8162 -80.4164)
		(width 0.127)
		(layer "B.Cu")
		(net "EXP_XM_ADDR_22")
	)
	(segment
		(start 76.4032 -83.687666)
		(end 76.5302 -83.560666)
		(width 0.127)
		(layer "B.Cu")
		(net "EXP_XM_ADDR_22")
	)
	(segment
		(start 76.4032 -85.0392)
		(end 76.4032 -84.709)
		(width 0.127)
		(layer "B.Cu")
		(net "EXP_XM_ADDR_22")
	)
	(segment
		(start 78.9686 -85.1662)
		(end 76.5302 -85.1662)
		(width 0.127)
		(layer "B.Cu")
		(net "EXP_XM_ADDR_22")
	)
	(segment
		(start 78.4352 -80.2894)
		(end 78.6892 -80.2894)
		(width 0.127)
		(layer "B.Cu")
		(net "EXP_XM_ADDR_22")
	)
	(segment
		(start 76.4032 -83.941666)
		(end 76.4032 -83.687666)
		(width 0.127)
		(layer "B.Cu")
		(net "EXP_XM_ADDR_22")
	)
	(segment
		(start 80.76819 -94.8309)
		(end 80.76819 -94.071186)
		(width 0.127)
		(layer "B.Cu")
		(net "EXP_XM_ADDR_22")
	)
	(segment
		(start 77.2922 -83.408266)
		(end 77.2922 -83.058)
		(width 0.127)
		(layer "B.Cu")
		(net "EXP_XM_ADDR_22")
	)
	(segment
		(start 77.2922 -83.058)
		(end 77.4192 -82.931)
		(width 0.127)
		(layer "B.Cu")
		(net "EXP_XM_ADDR_22")
	)
	(segment
		(start 78.8162 -80.4164)
		(end 78.8162 -84.4804)
		(width 0.127)
		(layer "B.Cu")
		(net "EXP_XM_ADDR_22")
	)
	(segment
		(start 79.9338 -84.6836)
		(end 79.9338 -85.07349)
		(width 0.127)
		(layer "B.Cu")
		(net "EXP_XM_ADDR_22")
	)
	(segment
		(start 80.908652 -93.792548)
		(end 80.908652 -93.049852)
		(width 0.127)
		(layer "B.Cu")
		(net "EXP_XM_ADDR_22")
	)
	(segment
		(start 79.8068 -84.5566)
		(end 79.9338 -84.6836)
		(width 0.127)
		(layer "B.Cu")
		(net "EXP_XM_ADDR_22")
	)
	(segment
		(start 76.5302 -84.582)
		(end 77.1398 -84.582)
		(width 0.127)
		(layer "B.Cu")
		(net "EXP_XM_ADDR_22")
	)
	(segment
		(start 79.5782 -85.7758)
		(end 78.9686 -85.1662)
		(width 0.127)
		(layer "B.Cu")
		(net "EXP_XM_ADDR_22")
	)
	(segment
		(start 77.1398 -84.582)
		(end 77.2668 -84.455)
		(width 0.127)
		(layer "B.Cu")
		(net "EXP_XM_ADDR_22")
	)
	(segment
		(start 79.5782 -91.7194)
		(end 79.5782 -85.7758)
		(width 0.127)
		(layer "B.Cu")
		(net "EXP_XM_ADDR_22")
	)
	(segment
		(start 77.8002 -83.058)
		(end 77.8002 -84.4804)
		(width 0.127)
		(layer "B.Cu")
		(net "EXP_XM_ADDR_22")
	)
	(segment
		(start 76.5302 -83.560666)
		(end 77.1398 -83.560666)
		(width 0.127)
		(layer "B.Cu")
		(net "EXP_XM_ADDR_22")
	)
	(segment
		(start 80.908652 -93.049852)
		(end 79.5782 -91.7194)
		(width 0.127)
		(layer "B.Cu")
		(net "EXP_XM_ADDR_22")
	)
	(segment
		(start 77.2668 -84.455)
		(end 77.2668 -84.195666)
		(width 0.127)
		(layer "B.Cu")
		(net "EXP_XM_ADDR_22")
	)
	(segment
		(start 114.681 -80.405224)
		(end 114.9096 -80.633824)
		(width 0.127)
		(layer "In2.Cu")
		(net "EXP_XM_ADDR_22")
	)
	(segment
		(start 115.0493 -81.470246)
		(end 115.0493 -83.800442)
		(width 0.127)
		(layer "In2.Cu")
		(net "EXP_XM_ADDR_22")
	)
	(segment
		(start 114.000026 -78.000352)
		(end 114.000026 -78.362302)
		(width 0.127)
		(layer "In2.Cu")
		(net "EXP_XM_ADDR_22")
	)
	(segment
		(start 80.905096 -87.4014)
		(end 80.905096 -87.1474)
		(width 0.127)
		(layer "In2.Cu")
		(net "EXP_XM_ADDR_22")
	)
	(segment
		(start 80.778096 -87.0204)
		(end 80.3783 -87.0204)
		(width 0.127)
		(layer "In2.Cu")
		(net "EXP_XM_ADDR_22")
	)
	(segment
		(start 115.0493 -83.800442)
		(end 113.309654 -85.540088)
		(width 0.127)
		(layer "In2.Cu")
		(net "EXP_XM_ADDR_22")
	)
	(segment
		(start 111.170974 -89.858342)
		(end 85.20049 -89.858342)
		(width 0.127)
		(layer "In2.Cu")
		(net "EXP_XM_ADDR_22")
	)
	(segment
		(start 111.407956 -89.62136)
		(end 111.170974 -89.858342)
		(width 0.127)
		(layer "In2.Cu")
		(net "EXP_XM_ADDR_22")
	)
	(segment
		(start 81.413096 -87.078058)
		(end 81.413096 -87.4014)
		(width 0.127)
		(layer "In2.Cu")
		(net "EXP_XM_ADDR_22")
	)
	(segment
		(start 114.000026 -78.362302)
		(end 114.681 -79.043276)
		(width 0.127)
		(layer "In2.Cu")
		(net "EXP_XM_ADDR_22")
	)
	(segment
		(start 111.379508 -88.874092)
		(end 111.19993 -89.05367)
		(width 0.127)
		(layer "In2.Cu")
		(net "EXP_XM_ADDR_22")
	)
	(segment
		(start 114.681 -79.043276)
		(end 114.681 -80.405224)
		(width 0.127)
		(layer "In2.Cu")
		(net "EXP_XM_ADDR_22")
	)
	(segment
		(start 111.767366 -89.082118)
		(end 111.55934 -88.874092)
		(width 0.127)
		(layer "In2.Cu")
		(net "EXP_XM_ADDR_22")
	)
	(segment
		(start 81.540096 -86.951058)
		(end 81.413096 -87.078058)
		(width 0.127)
		(layer "In2.Cu")
		(net "EXP_XM_ADDR_22")
	)
	(segment
		(start 111.19993 -89.05367)
		(end 111.19993 -89.233502)
		(width 0.127)
		(layer "In2.Cu")
		(net "EXP_XM_ADDR_22")
	)
	(segment
		(start 111.19993 -89.233502)
		(end 111.407956 -89.441528)
		(width 0.127)
		(layer "In2.Cu")
		(net "EXP_XM_ADDR_22")
	)
	(segment
		(start 80.3783 -87.0204)
		(end 80.2767 -86.9188)
		(width 0.127)
		(layer "In2.Cu")
		(net "EXP_XM_ADDR_22")
	)
	(segment
		(start 82.166206 -86.951058)
		(end 81.540096 -86.951058)
		(width 0.127)
		(layer "In2.Cu")
		(net "EXP_XM_ADDR_22")
	)
	(segment
		(start 85.186774 -89.844626)
		(end 85.059774 -89.844626)
		(width 0.127)
		(layer "In2.Cu")
		(net "EXP_XM_ADDR_22")
	)
	(segment
		(start 81.286096 -87.5284)
		(end 81.032096 -87.5284)
		(width 0.127)
		(layer "In2.Cu")
		(net "EXP_XM_ADDR_22")
	)
	(segment
		(start 113.309654 -87.786464)
		(end 112.691418 -88.4047)
		(width 0.127)
		(layer "In2.Cu")
		(net "EXP_XM_ADDR_22")
	)
	(segment
		(start 81.413096 -87.4014)
		(end 81.286096 -87.5284)
		(width 0.127)
		(layer "In2.Cu")
		(net "EXP_XM_ADDR_22")
	)
	(segment
		(start 111.55934 -88.874092)
		(end 111.379508 -88.874092)
		(width 0.127)
		(layer "In2.Cu")
		(net "EXP_XM_ADDR_22")
	)
	(segment
		(start 80.905096 -87.1474)
		(end 80.778096 -87.0204)
		(width 0.127)
		(layer "In2.Cu")
		(net "EXP_XM_ADDR_22")
	)
	(segment
		(start 114.9096 -80.633824)
		(end 114.9096 -81.330546)
		(width 0.127)
		(layer "In2.Cu")
		(net "EXP_XM_ADDR_22")
	)
	(segment
		(start 81.032096 -87.5284)
		(end 80.905096 -87.4014)
		(width 0.127)
		(layer "In2.Cu")
		(net "EXP_XM_ADDR_22")
	)
	(segment
		(start 111.947198 -89.082118)
		(end 111.767366 -89.082118)
		(width 0.127)
		(layer "In2.Cu")
		(net "EXP_XM_ADDR_22")
	)
	(segment
		(start 85.059774 -89.844626)
		(end 82.166206 -86.951058)
		(width 0.127)
		(layer "In2.Cu")
		(net "EXP_XM_ADDR_22")
	)
	(segment
		(start 111.407956 -89.441528)
		(end 111.407956 -89.62136)
		(width 0.127)
		(layer "In2.Cu")
		(net "EXP_XM_ADDR_22")
	)
	(segment
		(start 85.20049 -89.858342)
		(end 85.186774 -89.844626)
		(width 0.127)
		(layer "In2.Cu")
		(net "EXP_XM_ADDR_22")
	)
	(segment
		(start 112.624616 -88.4047)
		(end 111.947198 -89.082118)
		(width 0.127)
		(layer "In2.Cu")
		(net "EXP_XM_ADDR_22")
	)
	(segment
		(start 112.691418 -88.4047)
		(end 112.624616 -88.4047)
		(width 0.127)
		(layer "In2.Cu")
		(net "EXP_XM_ADDR_22")
	)
	(segment
		(start 113.309654 -85.540088)
		(end 113.309654 -87.786464)
		(width 0.127)
		(layer "In2.Cu")
		(net "EXP_XM_ADDR_22")
	)
	(segment
		(start 114.9096 -81.330546)
		(end 115.0493 -81.470246)
		(width 0.127)
		(layer "In2.Cu")
		(net "EXP_XM_ADDR_22")
	)
	(segment
		(start 114.499898 -75.50023)
		(end 114.99977 -75.000358)
		(width 0.127)
		(layer "F.Cu")
		(net "EXP_XM_ADDR_21")
	)
	(via
		(at 114.99977 -75.000358)
		(size 0.4572)
		(drill 0.2032)
		(layers "F.Cu" "B.Cu")
		(net "EXP_XM_ADDR_21")
	)
	(via
		(at 79.349092 -98.165666)
		(size 0.508)
		(drill 0.254)
		(layers "F.Cu" "B.Cu")
		(net "EXP_XM_ADDR_21")
	)
	(segment
		(start 79.9338 -96.810068)
		(end 79.39532 -96.810068)
		(width 0.127)
		(layer "B.Cu")
		(net "EXP_XM_ADDR_21")
	)
	(segment
		(start 79.349092 -98.165666)
		(end 79.349092 -97.470976)
		(width 0.127)
		(layer "B.Cu")
		(net "EXP_XM_ADDR_21")
	)
	(segment
		(start 80.0608 -97.191068)
		(end 80.0608 -96.937068)
		(width 0.127)
		(layer "B.Cu")
		(net "EXP_XM_ADDR_21")
	)
	(segment
		(start 79.26832 -96.683068)
		(end 79.26832 -94.8309)
		(width 0.127)
		(layer "B.Cu")
		(net "EXP_XM_ADDR_21")
	)
	(segment
		(start 79.349092 -97.470976)
		(end 79.502 -97.318068)
		(width 0.127)
		(layer "B.Cu")
		(net "EXP_XM_ADDR_21")
	)
	(segment
		(start 79.39532 -96.810068)
		(end 79.26832 -96.683068)
		(width 0.127)
		(layer "B.Cu")
		(net "EXP_XM_ADDR_21")
	)
	(segment
		(start 79.502 -97.318068)
		(end 79.9338 -97.318068)
		(width 0.127)
		(layer "B.Cu")
		(net "EXP_XM_ADDR_21")
	)
	(segment
		(start 79.9338 -97.318068)
		(end 80.0608 -97.191068)
		(width 0.127)
		(layer "B.Cu")
		(net "EXP_XM_ADDR_21")
	)
	(segment
		(start 80.0608 -96.937068)
		(end 79.9338 -96.810068)
		(width 0.127)
		(layer "B.Cu")
		(net "EXP_XM_ADDR_21")
	)
	(segment
		(start 82.564732 -98.53422)
		(end 82.564732 -98.077782)
		(width 0.127)
		(layer "In2.Cu")
		(net "EXP_XM_ADDR_21")
	)
	(segment
		(start 82.056732 -98.53422)
		(end 82.183732 -98.66122)
		(width 0.127)
		(layer "In2.Cu")
		(net "EXP_XM_ADDR_21")
	)
	(segment
		(start 121.13895 -82.313018)
		(end 120.4468 -81.620868)
		(width 0.127)
		(layer "In2.Cu")
		(net "EXP_XM_ADDR_21")
	)
	(segment
		(start 82.945732 -97.950782)
		(end 83.072732 -98.077782)
		(width 0.127)
		(layer "In2.Cu")
		(net "EXP_XM_ADDR_21")
	)
	(segment
		(start 120.4468 -80.708246)
		(end 120.1928 -80.454246)
		(width 0.127)
		(layer "In2.Cu")
		(net "EXP_XM_ADDR_21")
	)
	(segment
		(start 115.840002 -76.447396)
		(end 115.495578 -76.102972)
		(width 0.127)
		(layer "In2.Cu")
		(net "EXP_XM_ADDR_21")
	)
	(segment
		(start 81.548732 -98.53422)
		(end 81.548732 -98.105722)
		(width 0.127)
		(layer "In2.Cu")
		(net "EXP_XM_ADDR_21")
	)
	(segment
		(start 81.040732 -98.127566)
		(end 81.040732 -98.53422)
		(width 0.127)
		(layer "In2.Cu")
		(net "EXP_XM_ADDR_21")
	)
	(segment
		(start 119.9007 -94.9198)
		(end 119.9007 -94.242382)
		(width 0.127)
		(layer "In2.Cu")
		(net "EXP_XM_ADDR_21")
	)
	(segment
		(start 120.1928 -80.454246)
		(end 119.798846 -80.454246)
		(width 0.127)
		(layer "In2.Cu")
		(net "EXP_XM_ADDR_21")
	)
	(segment
		(start 123.920758 -86.40064)
		(end 121.13895 -83.618832)
		(width 0.127)
		(layer "In2.Cu")
		(net "EXP_XM_ADDR_21")
	)
	(segment
		(start 80.405732 -98.66122)
		(end 80.532732 -98.53422)
		(width 0.127)
		(layer "In2.Cu")
		(net "EXP_XM_ADDR_21")
	)
	(segment
		(start 116.7384 -77.502512)
		(end 116.4844 -77.248512)
		(width 0.127)
		(layer "In2.Cu")
		(net "EXP_XM_ADDR_21")
	)
	(segment
		(start 121.719848 -91.363038)
		(end 122.7709 -90.311986)
		(width 0.127)
		(layer "In2.Cu")
		(net "EXP_XM_ADDR_21")
	)
	(segment
		(start 123.47448 -88.020906)
		(end 123.34748 -87.893906)
		(width 0.127)
		(layer "In2.Cu")
		(net "EXP_XM_ADDR_21")
	)
	(segment
		(start 83.453732 -98.66122)
		(end 83.580732 -98.53422)
		(width 0.127)
		(layer "In2.Cu")
		(net "EXP_XM_ADDR_21")
	)
	(segment
		(start 81.675732 -97.978722)
		(end 81.929732 -97.978722)
		(width 0.127)
		(layer "In2.Cu")
		(net "EXP_XM_ADDR_21")
	)
	(segment
		(start 119.9007 -94.242382)
		(end 120.201182 -93.9419)
		(width 0.127)
		(layer "In2.Cu")
		(net "EXP_XM_ADDR_21")
	)
	(segment
		(start 114.99977 -75.399138)
		(end 114.99977 -75.000358)
		(width 0.127)
		(layer "In2.Cu")
		(net "EXP_XM_ADDR_21")
	)
	(segment
		(start 80.913732 -98.000566)
		(end 81.040732 -98.127566)
		(width 0.127)
		(layer "In2.Cu")
		(net "EXP_XM_ADDR_21")
	)
	(segment
		(start 121.719848 -93.083126)
		(end 121.719848 -91.363038)
		(width 0.127)
		(layer "In2.Cu")
		(net "EXP_XM_ADDR_21")
	)
	(segment
		(start 118.47195 -77.83195)
		(end 118.142512 -77.502512)
		(width 0.127)
		(layer "In2.Cu")
		(net "EXP_XM_ADDR_21")
	)
	(segment
		(start 122.7709 -90.311986)
		(end 122.7709 -89.626948)
		(width 0.127)
		(layer "In2.Cu")
		(net "EXP_XM_ADDR_21")
	)
	(segment
		(start 81.421732 -98.66122)
		(end 81.548732 -98.53422)
		(width 0.127)
		(layer "In2.Cu")
		(net "EXP_XM_ADDR_21")
	)
	(segment
		(start 83.072732 -98.53422)
		(end 83.199732 -98.66122)
		(width 0.127)
		(layer "In2.Cu")
		(net "EXP_XM_ADDR_21")
	)
	(segment
		(start 81.040732 -98.53422)
		(end 81.167732 -98.66122)
		(width 0.127)
		(layer "In2.Cu")
		(net "EXP_XM_ADDR_21")
	)
	(segment
		(start 82.564732 -98.077782)
		(end 82.691732 -97.950782)
		(width 0.127)
		(layer "In2.Cu")
		(net "EXP_XM_ADDR_21")
	)
	(segment
		(start 119.5324 -80.1878)
		(end 119.5324 -79.612998)
		(width 0.127)
		(layer "In2.Cu")
		(net "EXP_XM_ADDR_21")
	)
	(segment
		(start 79.897732 -98.165666)
		(end 80.024732 -98.292666)
		(width 0.127)
		(layer "In2.Cu")
		(net "EXP_XM_ADDR_21")
	)
	(segment
		(start 89.101422 -97.4217)
		(end 89.499948 -97.023174)
		(width 0.127)
		(layer "In2.Cu")
		(net "EXP_XM_ADDR_21")
	)
	(segment
		(start 80.024732 -98.292666)
		(end 80.024732 -98.53422)
		(width 0.127)
		(layer "In2.Cu")
		(net "EXP_XM_ADDR_21")
	)
	(segment
		(start 80.532732 -98.53422)
		(end 80.532732 -98.127566)
		(width 0.127)
		(layer "In2.Cu")
		(net "EXP_XM_ADDR_21")
	)
	(segment
		(start 83.580732 -97.793048)
		(end 83.95208 -97.4217)
		(width 0.127)
		(layer "In2.Cu")
		(net "EXP_XM_ADDR_21")
	)
	(segment
		(start 121.13895 -83.618832)
		(end 121.13895 -82.313018)
		(width 0.127)
		(layer "In2.Cu")
		(net "EXP_XM_ADDR_21")
	)
	(segment
		(start 116.4844 -77.248512)
		(end 116.4844 -76.701396)
		(width 0.127)
		(layer "In2.Cu")
		(net "EXP_XM_ADDR_21")
	)
	(segment
		(start 123.793758 -88.020906)
		(end 123.47448 -88.020906)
		(width 0.127)
		(layer "In2.Cu")
		(net "EXP_XM_ADDR_21")
	)
	(segment
		(start 119.798846 -80.454246)
		(end 119.5324 -80.1878)
		(width 0.127)
		(layer "In2.Cu")
		(net "EXP_XM_ADDR_21")
	)
	(segment
		(start 82.056732 -98.105722)
		(end 82.056732 -98.53422)
		(width 0.127)
		(layer "In2.Cu")
		(net "EXP_XM_ADDR_21")
	)
	(segment
		(start 120.201182 -93.9419)
		(end 120.861074 -93.9419)
		(width 0.127)
		(layer "In2.Cu")
		(net "EXP_XM_ADDR_21")
	)
	(segment
		(start 81.548732 -98.105722)
		(end 81.675732 -97.978722)
		(width 0.127)
		(layer "In2.Cu")
		(net "EXP_XM_ADDR_21")
	)
	(segment
		(start 82.691732 -97.950782)
		(end 82.945732 -97.950782)
		(width 0.127)
		(layer "In2.Cu")
		(net "EXP_XM_ADDR_21")
	)
	(segment
		(start 81.167732 -98.66122)
		(end 81.421732 -98.66122)
		(width 0.127)
		(layer "In2.Cu")
		(net "EXP_XM_ADDR_21")
	)
	(segment
		(start 80.024732 -98.53422)
		(end 80.151732 -98.66122)
		(width 0.127)
		(layer "In2.Cu")
		(net "EXP_XM_ADDR_21")
	)
	(segment
		(start 115.495578 -76.102972)
		(end 115.495578 -75.894946)
		(width 0.127)
		(layer "In2.Cu")
		(net "EXP_XM_ADDR_21")
	)
	(segment
		(start 83.072732 -98.077782)
		(end 83.072732 -98.53422)
		(width 0.127)
		(layer "In2.Cu")
		(net "EXP_XM_ADDR_21")
	)
	(segment
		(start 123.47448 -87.512906)
		(end 123.793758 -87.512906)
		(width 0.127)
		(layer "In2.Cu")
		(net "EXP_XM_ADDR_21")
	)
	(segment
		(start 119.352314 -79.432912)
		(end 118.72595 -79.432912)
		(width 0.127)
		(layer "In2.Cu")
		(net "EXP_XM_ADDR_21")
	)
	(segment
		(start 120.4468 -81.620868)
		(end 120.4468 -80.708246)
		(width 0.127)
		(layer "In2.Cu")
		(net "EXP_XM_ADDR_21")
	)
	(segment
		(start 83.580732 -98.53422)
		(end 83.580732 -97.793048)
		(width 0.127)
		(layer "In2.Cu")
		(net "EXP_XM_ADDR_21")
	)
	(segment
		(start 118.142512 -77.502512)
		(end 116.7384 -77.502512)
		(width 0.127)
		(layer "In2.Cu")
		(net "EXP_XM_ADDR_21")
	)
	(segment
		(start 82.437732 -98.66122)
		(end 82.564732 -98.53422)
		(width 0.127)
		(layer "In2.Cu")
		(net "EXP_XM_ADDR_21")
	)
	(segment
		(start 82.183732 -98.66122)
		(end 82.437732 -98.66122)
		(width 0.127)
		(layer "In2.Cu")
		(net "EXP_XM_ADDR_21")
	)
	(segment
		(start 89.499948 -97.023174)
		(end 117.797326 -97.023174)
		(width 0.127)
		(layer "In2.Cu")
		(net "EXP_XM_ADDR_21")
	)
	(segment
		(start 83.95208 -97.4217)
		(end 89.101422 -97.4217)
		(width 0.127)
		(layer "In2.Cu")
		(net "EXP_XM_ADDR_21")
	)
	(segment
		(start 116.2304 -76.447396)
		(end 115.840002 -76.447396)
		(width 0.127)
		(layer "In2.Cu")
		(net "EXP_XM_ADDR_21")
	)
	(segment
		(start 117.797326 -97.023174)
		(end 119.9007 -94.9198)
		(width 0.127)
		(layer "In2.Cu")
		(net "EXP_XM_ADDR_21")
	)
	(segment
		(start 115.495578 -75.894946)
		(end 114.99977 -75.399138)
		(width 0.127)
		(layer "In2.Cu")
		(net "EXP_XM_ADDR_21")
	)
	(segment
		(start 123.920758 -87.385906)
		(end 123.920758 -86.40064)
		(width 0.127)
		(layer "In2.Cu")
		(net "EXP_XM_ADDR_21")
	)
	(segment
		(start 80.659732 -98.000566)
		(end 80.913732 -98.000566)
		(width 0.127)
		(layer "In2.Cu")
		(net "EXP_XM_ADDR_21")
	)
	(segment
		(start 83.199732 -98.66122)
		(end 83.453732 -98.66122)
		(width 0.127)
		(layer "In2.Cu")
		(net "EXP_XM_ADDR_21")
	)
	(segment
		(start 123.793758 -87.512906)
		(end 123.920758 -87.385906)
		(width 0.127)
		(layer "In2.Cu")
		(net "EXP_XM_ADDR_21")
	)
	(segment
		(start 123.920758 -88.47709)
		(end 123.920758 -88.147906)
		(width 0.127)
		(layer "In2.Cu")
		(net "EXP_XM_ADDR_21")
	)
	(segment
		(start 119.5324 -79.612998)
		(end 119.352314 -79.432912)
		(width 0.127)
		(layer "In2.Cu")
		(net "EXP_XM_ADDR_21")
	)
	(segment
		(start 118.72595 -79.432912)
		(end 118.47195 -79.178912)
		(width 0.127)
		(layer "In2.Cu")
		(net "EXP_XM_ADDR_21")
	)
	(segment
		(start 120.861074 -93.9419)
		(end 121.719848 -93.083126)
		(width 0.127)
		(layer "In2.Cu")
		(net "EXP_XM_ADDR_21")
	)
	(segment
		(start 116.4844 -76.701396)
		(end 116.2304 -76.447396)
		(width 0.127)
		(layer "In2.Cu")
		(net "EXP_XM_ADDR_21")
	)
	(segment
		(start 123.34748 -87.893906)
		(end 123.34748 -87.639906)
		(width 0.127)
		(layer "In2.Cu")
		(net "EXP_XM_ADDR_21")
	)
	(segment
		(start 123.34748 -87.639906)
		(end 123.47448 -87.512906)
		(width 0.127)
		(layer "In2.Cu")
		(net "EXP_XM_ADDR_21")
	)
	(segment
		(start 123.920758 -88.147906)
		(end 123.793758 -88.020906)
		(width 0.127)
		(layer "In2.Cu")
		(net "EXP_XM_ADDR_21")
	)
	(segment
		(start 118.47195 -79.178912)
		(end 118.47195 -77.83195)
		(width 0.127)
		(layer "In2.Cu")
		(net "EXP_XM_ADDR_21")
	)
	(segment
		(start 122.7709 -89.626948)
		(end 123.920758 -88.47709)
		(width 0.127)
		(layer "In2.Cu")
		(net "EXP_XM_ADDR_21")
	)
	(segment
		(start 81.929732 -97.978722)
		(end 82.056732 -98.105722)
		(width 0.127)
		(layer "In2.Cu")
		(net "EXP_XM_ADDR_21")
	)
	(segment
		(start 80.151732 -98.66122)
		(end 80.405732 -98.66122)
		(width 0.127)
		(layer "In2.Cu")
		(net "EXP_XM_ADDR_21")
	)
	(segment
		(start 80.532732 -98.127566)
		(end 80.659732 -98.000566)
		(width 0.127)
		(layer "In2.Cu")
		(net "EXP_XM_ADDR_21")
	)
	(segment
		(start 79.349092 -98.165666)
		(end 79.897732 -98.165666)
		(width 0.127)
		(layer "In2.Cu")
		(net "EXP_XM_ADDR_21")
	)
	(segment
		(start 114.499898 -76.500228)
		(end 114.99977 -77.0001)
		(width 0.127)
		(layer "F.Cu")
		(net "EXP_XM_ADDR_20")
	)
	(via
		(at 77.507338 -90.095324)
		(size 0.508)
		(drill 0.254)
		(layers "F.Cu" "B.Cu")
		(net "EXP_XM_ADDR_20")
	)
	(via
		(at 114.99977 -77.0001)
		(size 0.4572)
		(drill 0.2032)
		(layers "F.Cu" "B.Cu")
		(net "EXP_XM_ADDR_20")
	)
	(segment
		(start 78.77556 -94.063566)
		(end 78.76794 -94.071186)
		(width 0.127)
		(layer "B.Cu")
		(net "EXP_XM_ADDR_20")
	)
	(segment
		(start 78.76794 -93.37294)
		(end 78.76794 -93.557598)
		(width 0.127)
		(layer "B.Cu")
		(net "EXP_XM_ADDR_20")
	)
	(segment
		(start 78.76794 -93.557598)
		(end 78.77556 -93.565218)
		(width 0.127)
		(layer "B.Cu")
		(net "EXP_XM_ADDR_20")
	)
	(segment
		(start 78.76794 -94.071186)
		(end 78.76794 -94.8309)
		(width 0.127)
		(layer "B.Cu")
		(net "EXP_XM_ADDR_20")
	)
	(segment
		(start 78.77556 -93.565218)
		(end 78.77556 -94.063566)
		(width 0.127)
		(layer "B.Cu")
		(net "EXP_XM_ADDR_20")
	)
	(segment
		(start 77.507338 -90.095324)
		(end 77.507338 -92.112338)
		(width 0.127)
		(layer "B.Cu")
		(net "EXP_XM_ADDR_20")
	)
	(segment
		(start 77.507338 -92.112338)
		(end 78.76794 -93.37294)
		(width 0.127)
		(layer "B.Cu")
		(net "EXP_XM_ADDR_20")
	)
	(segment
		(start 80.663288 -89.992454)
		(end 79.977996 -89.992454)
		(width 0.127)
		(layer "In2.Cu")
		(net "EXP_XM_ADDR_20")
	)
	(segment
		(start 84.048854 -91.943174)
		(end 82.963766 -90.858086)
		(width 0.127)
		(layer "In2.Cu")
		(net "EXP_XM_ADDR_20")
	)
	(segment
		(start 115.4176 -81.0514)
		(end 115.6843 -81.3181)
		(width 0.127)
		(layer "In2.Cu")
		(net "EXP_XM_ADDR_20")
	)
	(segment
		(start 115.472972 -78.491334)
		(end 115.2652 -78.699106)
		(width 0.127)
		(layer "In2.Cu")
		(net "EXP_XM_ADDR_20")
	)
	(segment
		(start 74.422 -89.3064)
		(end 74.549 -89.1794)
		(width 0.127)
		(layer "In2.Cu")
		(net "EXP_XM_ADDR_20")
	)
	(segment
		(start 78.5876 -89.1794)
		(end 78.7146 -89.3064)
		(width 0.127)
		(layer "In2.Cu")
		(net "EXP_XM_ADDR_20")
	)
	(segment
		(start 115.2652 -78.699106)
		(end 115.2652 -80.270604)
		(width 0.127)
		(layer "In2.Cu")
		(net "EXP_XM_ADDR_20")
	)
	(segment
		(start 81.526634 -90.8558)
		(end 80.663288 -89.992454)
		(width 0.127)
		(layer "In2.Cu")
		(net "EXP_XM_ADDR_20")
	)
	(segment
		(start 79.368904 -89.882472)
		(end 79.63027 -89.62136)
		(width 0.127)
		(layer "In2.Cu")
		(net "EXP_XM_ADDR_20")
	)
	(segment
		(start 113.063274 -91.943174)
		(end 84.048854 -91.943174)
		(width 0.127)
		(layer "In2.Cu")
		(net "EXP_XM_ADDR_20")
	)
	(segment
		(start 115.6843 -85.285834)
		(end 115.4557 -85.514434)
		(width 0.127)
		(layer "In2.Cu")
		(net "EXP_XM_ADDR_20")
	)
	(segment
		(start 79.368904 -90.061796)
		(end 79.368904 -89.882472)
		(width 0.127)
		(layer "In2.Cu")
		(net "EXP_XM_ADDR_20")
	)
	(segment
		(start 79.63027 -89.62136)
		(end 79.63027 -89.442036)
		(width 0.127)
		(layer "In2.Cu")
		(net "EXP_XM_ADDR_20")
	)
	(segment
		(start 79.54899 -90.241882)
		(end 79.368904 -90.061796)
		(width 0.127)
		(layer "In2.Cu")
		(net "EXP_XM_ADDR_20")
	)
	(segment
		(start 78.7146 -89.968324)
		(end 78.5876 -90.095324)
		(width 0.127)
		(layer "In2.Cu")
		(net "EXP_XM_ADDR_20")
	)
	(segment
		(start 78.5876 -90.095324)
		(end 77.507338 -90.095324)
		(width 0.127)
		(layer "In2.Cu")
		(net "EXP_XM_ADDR_20")
	)
	(segment
		(start 76.7334 -89.7636)
		(end 74.549 -89.7636)
		(width 0.127)
		(layer "In2.Cu")
		(net "EXP_XM_ADDR_20")
	)
	(segment
		(start 114.99977 -77.0001)
		(end 115.472972 -77.473302)
		(width 0.127)
		(layer "In2.Cu")
		(net "EXP_XM_ADDR_20")
	)
	(segment
		(start 74.422 -89.6366)
		(end 74.422 -89.3064)
		(width 0.127)
		(layer "In2.Cu")
		(net "EXP_XM_ADDR_20")
	)
	(segment
		(start 78.81239 -88.624156)
		(end 73.859644 -88.624156)
		(width 0.127)
		(layer "In2.Cu")
		(net "EXP_XM_ADDR_20")
	)
	(segment
		(start 78.7146 -89.3064)
		(end 78.7146 -89.968324)
		(width 0.127)
		(layer "In2.Cu")
		(net "EXP_XM_ADDR_20")
	)
	(segment
		(start 73.859644 -88.624156)
		(end 73.6346 -88.8492)
		(width 0.127)
		(layer "In2.Cu")
		(net "EXP_XM_ADDR_20")
	)
	(segment
		(start 74.549 -89.7636)
		(end 74.422 -89.6366)
		(width 0.127)
		(layer "In2.Cu")
		(net "EXP_XM_ADDR_20")
	)
	(segment
		(start 115.472972 -77.473302)
		(end 115.472972 -78.491334)
		(width 0.127)
		(layer "In2.Cu")
		(net "EXP_XM_ADDR_20")
	)
	(segment
		(start 115.4557 -89.550748)
		(end 113.063274 -91.943174)
		(width 0.127)
		(layer "In2.Cu")
		(net "EXP_XM_ADDR_20")
	)
	(segment
		(start 81.602834 -90.8558)
		(end 81.526634 -90.8558)
		(width 0.127)
		(layer "In2.Cu")
		(net "EXP_XM_ADDR_20")
	)
	(segment
		(start 73.819766 -90.297)
		(end 76.7334 -90.297)
		(width 0.127)
		(layer "In2.Cu")
		(net "EXP_XM_ADDR_20")
	)
	(segment
		(start 79.859632 -90.110818)
		(end 79.728314 -90.241882)
		(width 0.127)
		(layer "In2.Cu")
		(net "EXP_XM_ADDR_20")
	)
	(segment
		(start 115.6843 -81.3181)
		(end 115.6843 -85.285834)
		(width 0.127)
		(layer "In2.Cu")
		(net "EXP_XM_ADDR_20")
	)
	(segment
		(start 74.549 -89.1794)
		(end 78.5876 -89.1794)
		(width 0.127)
		(layer "In2.Cu")
		(net "EXP_XM_ADDR_20")
	)
	(segment
		(start 76.7334 -90.297)
		(end 76.8604 -90.17)
		(width 0.127)
		(layer "In2.Cu")
		(net "EXP_XM_ADDR_20")
	)
	(segment
		(start 115.2652 -80.270604)
		(end 115.4176 -80.423004)
		(width 0.127)
		(layer "In2.Cu")
		(net "EXP_XM_ADDR_20")
	)
	(segment
		(start 79.63027 -89.442036)
		(end 78.81239 -88.624156)
		(width 0.127)
		(layer "In2.Cu")
		(net "EXP_XM_ADDR_20")
	)
	(segment
		(start 115.4176 -80.423004)
		(end 115.4176 -81.0514)
		(width 0.127)
		(layer "In2.Cu")
		(net "EXP_XM_ADDR_20")
	)
	(segment
		(start 79.977996 -89.992454)
		(end 79.859632 -90.110818)
		(width 0.127)
		(layer "In2.Cu")
		(net "EXP_XM_ADDR_20")
	)
	(segment
		(start 73.6346 -88.8492)
		(end 73.6346 -90.111834)
		(width 0.127)
		(layer "In2.Cu")
		(net "EXP_XM_ADDR_20")
	)
	(segment
		(start 82.963766 -90.858086)
		(end 81.60512 -90.858086)
		(width 0.127)
		(layer "In2.Cu")
		(net "EXP_XM_ADDR_20")
	)
	(segment
		(start 76.8604 -89.8906)
		(end 76.7334 -89.7636)
		(width 0.127)
		(layer "In2.Cu")
		(net "EXP_XM_ADDR_20")
	)
	(segment
		(start 115.4557 -85.514434)
		(end 115.4557 -89.550748)
		(width 0.127)
		(layer "In2.Cu")
		(net "EXP_XM_ADDR_20")
	)
	(segment
		(start 76.8604 -90.17)
		(end 76.8604 -89.8906)
		(width 0.127)
		(layer "In2.Cu")
		(net "EXP_XM_ADDR_20")
	)
	(segment
		(start 73.6346 -90.111834)
		(end 73.819766 -90.297)
		(width 0.127)
		(layer "In2.Cu")
		(net "EXP_XM_ADDR_20")
	)
	(segment
		(start 81.60512 -90.858086)
		(end 81.602834 -90.8558)
		(width 0.127)
		(layer "In2.Cu")
		(net "EXP_XM_ADDR_20")
	)
	(segment
		(start 79.728314 -90.241882)
		(end 79.54899 -90.241882)
		(width 0.127)
		(layer "In2.Cu")
		(net "EXP_XM_ADDR_20")
	)
	(segment
		(start 114.499898 -74.500232)
		(end 114.99977 -74.00036)
		(width 0.127)
		(layer "F.Cu")
		(net "EXP_XM_ADDR_2")
	)
	(via
		(at 87.376 -98.679)
		(size 0.508)
		(drill 0.254)
		(layers "F.Cu" "B.Cu")
		(net "EXP_XM_ADDR_2")
	)
	(via
		(at 114.99977 -74.00036)
		(size 0.4572)
		(drill 0.2032)
		(layers "F.Cu" "B.Cu")
		(net "EXP_XM_ADDR_2")
	)
	(segment
		(start 86.26856 -97.57156)
		(end 87.376 -98.679)
		(width 0.127)
		(layer "B.Cu")
		(net "EXP_XM_ADDR_2")
	)
	(segment
		(start 86.26856 -94.8309)
		(end 86.26856 -97.57156)
		(width 0.127)
		(layer "B.Cu")
		(net "EXP_XM_ADDR_2")
	)
	(segment
		(start 87.376 -98.679)
		(end 89.408 -98.679)
		(width 0.127)
		(layer "In2.Cu")
		(net "EXP_XM_ADDR_2")
	)
	(segment
		(start 122.45848 -94.84741)
		(end 122.638566 -95.027242)
		(width 0.127)
		(layer "In2.Cu")
		(net "EXP_XM_ADDR_2")
	)
	(segment
		(start 122.735848 -93.352366)
		(end 122.735848 -91.78417)
		(width 0.127)
		(layer "In2.Cu")
		(net "EXP_XM_ADDR_2")
	)
	(segment
		(start 118.6942 -76.5302)
		(end 118.4656 -76.3016)
		(width 0.127)
		(layer "In2.Cu")
		(net "EXP_XM_ADDR_2")
	)
	(segment
		(start 122.735848 -91.78417)
		(end 123.7869 -90.733118)
		(width 0.127)
		(layer "In2.Cu")
		(net "EXP_XM_ADDR_2")
	)
	(segment
		(start 122.638566 -95.206566)
		(end 120.206262 -97.63887)
		(width 0.127)
		(layer "In2.Cu")
		(net "EXP_XM_ADDR_2")
	)
	(segment
		(start 122.638566 -95.027242)
		(end 122.638566 -95.206566)
		(width 0.127)
		(layer "In2.Cu")
		(net "EXP_XM_ADDR_2")
	)
	(segment
		(start 118.3132 -75.565)
		(end 116.891054 -75.565)
		(width 0.127)
		(layer "In2.Cu")
		(net "EXP_XM_ADDR_2")
	)
	(segment
		(start 124.936758 -88.898222)
		(end 124.936758 -85.9028)
		(width 0.127)
		(layer "In2.Cu")
		(net "EXP_XM_ADDR_2")
	)
	(segment
		(start 119.4308 -76.7588)
		(end 119.2022 -76.5302)
		(width 0.127)
		(layer "In2.Cu")
		(net "EXP_XM_ADDR_2")
	)
	(segment
		(start 123.215654 -93.832172)
		(end 122.735848 -93.352366)
		(width 0.127)
		(layer "In2.Cu")
		(net "EXP_XM_ADDR_2")
	)
	(segment
		(start 115.82908 -74.447146)
		(end 115.382294 -74.00036)
		(width 0.127)
		(layer "In2.Cu")
		(net "EXP_XM_ADDR_2")
	)
	(segment
		(start 123.7869 -90.04808)
		(end 124.936758 -88.898222)
		(width 0.127)
		(layer "In2.Cu")
		(net "EXP_XM_ADDR_2")
	)
	(segment
		(start 116.4844 -75.158346)
		(end 116.4844 -74.7776)
		(width 0.127)
		(layer "In2.Cu")
		(net "EXP_XM_ADDR_2")
	)
	(segment
		(start 120.206262 -97.63887)
		(end 120.206262 -97.818194)
		(width 0.127)
		(layer "In2.Cu")
		(net "EXP_XM_ADDR_2")
	)
	(segment
		(start 119.087138 -98.039174)
		(end 122.278902 -94.84741)
		(width 0.127)
		(layer "In2.Cu")
		(net "EXP_XM_ADDR_2")
	)
	(segment
		(start 123.7869 -90.733118)
		(end 123.7869 -90.04808)
		(width 0.127)
		(layer "In2.Cu")
		(net "EXP_XM_ADDR_2")
	)
	(segment
		(start 122.278902 -94.84741)
		(end 122.45848 -94.84741)
		(width 0.127)
		(layer "In2.Cu")
		(net "EXP_XM_ADDR_2")
	)
	(segment
		(start 116.4844 -74.7776)
		(end 116.153946 -74.447146)
		(width 0.127)
		(layer "In2.Cu")
		(net "EXP_XM_ADDR_2")
	)
	(segment
		(start 121.541794 -79.516986)
		(end 120.740678 -79.516986)
		(width 0.127)
		(layer "In2.Cu")
		(net "EXP_XM_ADDR_2")
	)
	(segment
		(start 90.047826 -98.039174)
		(end 119.087138 -98.039174)
		(width 0.127)
		(layer "In2.Cu")
		(net "EXP_XM_ADDR_2")
	)
	(segment
		(start 116.891054 -75.565)
		(end 116.4844 -75.158346)
		(width 0.127)
		(layer "In2.Cu")
		(net "EXP_XM_ADDR_2")
	)
	(segment
		(start 120.386602 -97.998026)
		(end 120.565926 -97.998026)
		(width 0.127)
		(layer "In2.Cu")
		(net "EXP_XM_ADDR_2")
	)
	(segment
		(start 118.4656 -76.3016)
		(end 118.4656 -75.7174)
		(width 0.127)
		(layer "In2.Cu")
		(net "EXP_XM_ADDR_2")
	)
	(segment
		(start 89.408 -98.679)
		(end 90.047826 -98.039174)
		(width 0.127)
		(layer "In2.Cu")
		(net "EXP_XM_ADDR_2")
	)
	(segment
		(start 124.936758 -85.9028)
		(end 122.4788 -83.444842)
		(width 0.127)
		(layer "In2.Cu")
		(net "EXP_XM_ADDR_2")
	)
	(segment
		(start 120.740678 -79.516986)
		(end 120.486678 -79.262986)
		(width 0.127)
		(layer "In2.Cu")
		(net "EXP_XM_ADDR_2")
	)
	(segment
		(start 120.1928 -77.4954)
		(end 119.6594 -77.4954)
		(width 0.127)
		(layer "In2.Cu")
		(net "EXP_XM_ADDR_2")
	)
	(segment
		(start 120.565926 -97.998026)
		(end 123.215654 -95.348298)
		(width 0.127)
		(layer "In2.Cu")
		(net "EXP_XM_ADDR_2")
	)
	(segment
		(start 122.0724 -81.406746)
		(end 122.0724 -80.047592)
		(width 0.127)
		(layer "In2.Cu")
		(net "EXP_XM_ADDR_2")
	)
	(segment
		(start 119.6594 -77.4954)
		(end 119.4308 -77.2668)
		(width 0.127)
		(layer "In2.Cu")
		(net "EXP_XM_ADDR_2")
	)
	(segment
		(start 120.486678 -79.262986)
		(end 120.486678 -77.789278)
		(width 0.127)
		(layer "In2.Cu")
		(net "EXP_XM_ADDR_2")
	)
	(segment
		(start 119.4308 -77.2668)
		(end 119.4308 -76.7588)
		(width 0.127)
		(layer "In2.Cu")
		(net "EXP_XM_ADDR_2")
	)
	(segment
		(start 122.4788 -83.444842)
		(end 122.4788 -81.813146)
		(width 0.127)
		(layer "In2.Cu")
		(net "EXP_XM_ADDR_2")
	)
	(segment
		(start 122.0724 -80.047592)
		(end 121.541794 -79.516986)
		(width 0.127)
		(layer "In2.Cu")
		(net "EXP_XM_ADDR_2")
	)
	(segment
		(start 123.215654 -95.348298)
		(end 123.215654 -93.832172)
		(width 0.127)
		(layer "In2.Cu")
		(net "EXP_XM_ADDR_2")
	)
	(segment
		(start 122.4788 -81.813146)
		(end 122.0724 -81.406746)
		(width 0.127)
		(layer "In2.Cu")
		(net "EXP_XM_ADDR_2")
	)
	(segment
		(start 118.4656 -75.7174)
		(end 118.3132 -75.565)
		(width 0.127)
		(layer "In2.Cu")
		(net "EXP_XM_ADDR_2")
	)
	(segment
		(start 116.153946 -74.447146)
		(end 115.82908 -74.447146)
		(width 0.127)
		(layer "In2.Cu")
		(net "EXP_XM_ADDR_2")
	)
	(segment
		(start 120.206262 -97.818194)
		(end 120.386602 -97.998026)
		(width 0.127)
		(layer "In2.Cu")
		(net "EXP_XM_ADDR_2")
	)
	(segment
		(start 119.2022 -76.5302)
		(end 118.6942 -76.5302)
		(width 0.127)
		(layer "In2.Cu")
		(net "EXP_XM_ADDR_2")
	)
	(segment
		(start 115.382294 -74.00036)
		(end 114.99977 -74.00036)
		(width 0.127)
		(layer "In2.Cu")
		(net "EXP_XM_ADDR_2")
	)
	(segment
		(start 120.486678 -77.789278)
		(end 120.1928 -77.4954)
		(width 0.127)
		(layer "In2.Cu")
		(net "EXP_XM_ADDR_2")
	)
	(segment
		(start 114.499898 -77.500226)
		(end 114.99977 -78.000098)
		(width 0.127)
		(layer "F.Cu")
		(net "EXP_XM_ADDR_19")
	)
	(via
		(at 81.1657 -88.180926)
		(size 0.508)
		(drill 0.254)
		(layers "F.Cu" "B.Cu")
		(net "EXP_XM_ADDR_19")
	)
	(via
		(at 113.8682 -85.725)
		(size 0.508)
		(drill 0.254)
		(layers "F.Cu" "B.Cu")
		(net "EXP_XM_ADDR_19")
	)
	(via
		(at 114.99977 -78.000098)
		(size 0.4572)
		(drill 0.2032)
		(layers "F.Cu" "B.Cu")
		(net "EXP_XM_ADDR_19")
	)
	(segment
		(start 80.7212 -90.527632)
		(end 80.5942 -90.654632)
		(width 0.127)
		(layer "B.Cu")
		(net "EXP_XM_ADDR_19")
	)
	(segment
		(start 115.455954 -84.265008)
		(end 114.8842 -83.693254)
		(width 0.127)
		(layer "B.Cu")
		(net "EXP_XM_ADDR_19")
	)
	(segment
		(start 114.808 -85.0392)
		(end 115.05565 -85.0392)
		(width 0.127)
		(layer "B.Cu")
		(net "EXP_XM_ADDR_19")
	)
	(segment
		(start 81.4578 -90.146632)
		(end 81.4578 -90.400632)
		(width 0.127)
		(layer "B.Cu")
		(net "EXP_XM_ADDR_19")
	)
	(segment
		(start 80.7212 -91.035632)
		(end 81.8896 -91.035632)
		(width 0.127)
		(layer "B.Cu")
		(net "EXP_XM_ADDR_19")
	)
	(segment
		(start 114.8842 -83.693254)
		(end 114.8842 -83.2485)
		(width 0.127)
		(layer "B.Cu")
		(net "EXP_XM_ADDR_19")
	)
	(segment
		(start 115.455954 -84.638896)
		(end 115.455954 -84.265008)
		(width 0.127)
		(layer "B.Cu")
		(net "EXP_XM_ADDR_19")
	)
	(segment
		(start 114.99977 -79.31023)
		(end 114.8334 -79.4766)
		(width 0.127)
		(layer "B.Cu")
		(net "EXP_XM_ADDR_19")
	)
	(segment
		(start 81.3816 -89.384632)
		(end 81.2546 -89.511632)
		(width 0.127)
		(layer "B.Cu")
		(net "EXP_XM_ADDR_19")
	)
	(segment
		(start 81.2292 -91.670632)
		(end 81.2292 -91.924632)
		(width 0.127)
		(layer "B.Cu")
		(net "EXP_XM_ADDR_19")
	)
	(segment
		(start 113.8682 -85.725)
		(end 114.1222 -85.725)
		(width 0.127)
		(layer "B.Cu")
		(net "EXP_XM_ADDR_19")
	)
	(segment
		(start 80.5942 -90.908632)
		(end 80.7212 -91.035632)
		(width 0.127)
		(layer "B.Cu")
		(net "EXP_XM_ADDR_19")
	)
	(segment
		(start 80.7212 -88.180926)
		(end 80.5942 -88.307926)
		(width 0.127)
		(layer "B.Cu")
		(net "EXP_XM_ADDR_19")
	)
	(segment
		(start 81.3308 -90.527632)
		(end 80.7212 -90.527632)
		(width 0.127)
		(layer "B.Cu")
		(net "EXP_XM_ADDR_19")
	)
	(segment
		(start 113.538 -79.4766)
		(end 113.411 -79.6036)
		(width 0.127)
		(layer "B.Cu")
		(net "EXP_XM_ADDR_19")
	)
	(segment
		(start 81.932018 -92.24645)
		(end 81.932018 -93.463618)
		(width 0.127)
		(layer "B.Cu")
		(net "EXP_XM_ADDR_19")
	)
	(segment
		(start 81.8896 -91.543632)
		(end 81.3562 -91.543632)
		(width 0.127)
		(layer "B.Cu")
		(net "EXP_XM_ADDR_19")
	)
	(segment
		(start 82.26044 -93.79204)
		(end 82.26044 -94.063566)
		(width 0.127)
		(layer "B.Cu")
		(net "EXP_XM_ADDR_19")
	)
	(segment
		(start 81.4578 -90.400632)
		(end 81.3308 -90.527632)
		(width 0.127)
		(layer "B.Cu")
		(net "EXP_XM_ADDR_19")
	)
	(segment
		(start 81.2546 -89.003632)
		(end 81.3816 -89.130632)
		(width 0.127)
		(layer "B.Cu")
		(net "EXP_XM_ADDR_19")
	)
	(segment
		(start 82.26044 -94.063566)
		(end 82.26806 -94.071186)
		(width 0.127)
		(layer "B.Cu")
		(net "EXP_XM_ADDR_19")
	)
	(segment
		(start 113.6142 -86.5759)
		(end 113.6142 -85.979)
		(width 0.127)
		(layer "B.Cu")
		(net "EXP_XM_ADDR_19")
	)
	(segment
		(start 113.754916 -82.119216)
		(end 114.3508 -82.7151)
		(width 0.127)
		(layer "B.Cu")
		(net "EXP_XM_ADDR_19")
	)
	(segment
		(start 80.5942 -88.307926)
		(end 80.5942 -88.876632)
		(width 0.127)
		(layer "B.Cu")
		(net "EXP_XM_ADDR_19")
	)
	(segment
		(start 113.6142 -85.979)
		(end 113.8682 -85.725)
		(width 0.127)
		(layer "B.Cu")
		(net "EXP_XM_ADDR_19")
	)
	(segment
		(start 81.7372 -92.051632)
		(end 81.932018 -92.24645)
		(width 0.127)
		(layer "B.Cu")
		(net "EXP_XM_ADDR_19")
	)
	(segment
		(start 80.7212 -90.019632)
		(end 81.3308 -90.019632)
		(width 0.127)
		(layer "B.Cu")
		(net "EXP_XM_ADDR_19")
	)
	(segment
		(start 113.754916 -81.547716)
		(end 113.754916 -82.119216)
		(width 0.127)
		(layer "B.Cu")
		(net "EXP_XM_ADDR_19")
	)
	(segment
		(start 82.0166 -91.162632)
		(end 82.0166 -91.416632)
		(width 0.127)
		(layer "B.Cu")
		(net "EXP_XM_ADDR_19")
	)
	(segment
		(start 114.8842 -83.2485)
		(end 114.3508 -82.7151)
		(width 0.127)
		(layer "B.Cu")
		(net "EXP_XM_ADDR_19")
	)
	(segment
		(start 81.3562 -92.051632)
		(end 81.7372 -92.051632)
		(width 0.127)
		(layer "B.Cu")
		(net "EXP_XM_ADDR_19")
	)
	(segment
		(start 80.7212 -89.511632)
		(end 80.5942 -89.638632)
		(width 0.127)
		(layer "B.Cu")
		(net "EXP_XM_ADDR_19")
	)
	(segment
		(start 82.26806 -94.071186)
		(end 82.26806 -94.8309)
		(width 0.127)
		(layer "B.Cu")
		(net "EXP_XM_ADDR_19")
	)
	(segment
		(start 81.2292 -91.924632)
		(end 81.3562 -92.051632)
		(width 0.127)
		(layer "B.Cu")
		(net "EXP_XM_ADDR_19")
	)
	(segment
		(start 113.411 -81.2038)
		(end 113.754916 -81.547716)
		(width 0.127)
		(layer "B.Cu")
		(net "EXP_XM_ADDR_19")
	)
	(segment
		(start 81.3816 -89.130632)
		(end 81.3816 -89.384632)
		(width 0.127)
		(layer "B.Cu")
		(net "EXP_XM_ADDR_19")
	)
	(segment
		(start 82.0166 -91.416632)
		(end 81.8896 -91.543632)
		(width 0.127)
		(layer "B.Cu")
		(net "EXP_XM_ADDR_19")
	)
	(segment
		(start 80.5942 -88.876632)
		(end 80.7212 -89.003632)
		(width 0.127)
		(layer "B.Cu")
		(net "EXP_XM_ADDR_19")
	)
	(segment
		(start 114.99977 -78.000098)
		(end 114.99977 -79.31023)
		(width 0.127)
		(layer "B.Cu")
		(net "EXP_XM_ADDR_19")
	)
	(segment
		(start 81.3308 -90.019632)
		(end 81.4578 -90.146632)
		(width 0.127)
		(layer "B.Cu")
		(net "EXP_XM_ADDR_19")
	)
	(segment
		(start 114.1222 -85.725)
		(end 114.808 -85.0392)
		(width 0.127)
		(layer "B.Cu")
		(net "EXP_XM_ADDR_19")
	)
	(segment
		(start 81.1657 -88.180926)
		(end 80.7212 -88.180926)
		(width 0.127)
		(layer "B.Cu")
		(net "EXP_XM_ADDR_19")
	)
	(segment
		(start 81.2546 -89.511632)
		(end 80.7212 -89.511632)
		(width 0.127)
		(layer "B.Cu")
		(net "EXP_XM_ADDR_19")
	)
	(segment
		(start 113.411 -79.6036)
		(end 113.411 -81.2038)
		(width 0.127)
		(layer "B.Cu")
		(net "EXP_XM_ADDR_19")
	)
	(segment
		(start 115.05565 -85.0392)
		(end 115.455954 -84.638896)
		(width 0.127)
		(layer "B.Cu")
		(net "EXP_XM_ADDR_19")
	)
	(segment
		(start 80.5942 -89.892632)
		(end 80.7212 -90.019632)
		(width 0.127)
		(layer "B.Cu")
		(net "EXP_XM_ADDR_19")
	)
	(segment
		(start 80.5942 -89.638632)
		(end 80.5942 -89.892632)
		(width 0.127)
		(layer "B.Cu")
		(net "EXP_XM_ADDR_19")
	)
	(segment
		(start 80.7212 -89.003632)
		(end 81.2546 -89.003632)
		(width 0.127)
		(layer "B.Cu")
		(net "EXP_XM_ADDR_19")
	)
	(segment
		(start 81.932018 -93.463618)
		(end 82.26044 -93.79204)
		(width 0.127)
		(layer "B.Cu")
		(net "EXP_XM_ADDR_19")
	)
	(segment
		(start 114.8334 -79.4766)
		(end 113.538 -79.4766)
		(width 0.127)
		(layer "B.Cu")
		(net "EXP_XM_ADDR_19")
	)
	(segment
		(start 81.3562 -91.543632)
		(end 81.2292 -91.670632)
		(width 0.127)
		(layer "B.Cu")
		(net "EXP_XM_ADDR_19")
	)
	(segment
		(start 80.5942 -90.654632)
		(end 80.5942 -90.908632)
		(width 0.127)
		(layer "B.Cu")
		(net "EXP_XM_ADDR_19")
	)
	(segment
		(start 81.8896 -91.035632)
		(end 82.0166 -91.162632)
		(width 0.127)
		(layer "B.Cu")
		(net "EXP_XM_ADDR_19")
	)
	(segment
		(start 82.199226 -87.711026)
		(end 81.8642 -87.711026)
		(width 0.127)
		(layer "In2.Cu")
		(net "EXP_XM_ADDR_19")
	)
	(segment
		(start 81.247234 -88.9762)
		(end 80.601566 -88.9762)
		(width 0.127)
		(layer "In2.Cu")
		(net "EXP_XM_ADDR_19")
	)
	(segment
		(start 77.070966 -87.503)
		(end 76.512166 -86.9442)
		(width 0.127)
		(layer "In2.Cu")
		(net "EXP_XM_ADDR_19")
	)
	(segment
		(start 112.341914 -90.271854)
		(end 111.99876 -89.928446)
		(width 0.127)
		(layer "In2.Cu")
		(net "EXP_XM_ADDR_19")
	)
	(segment
		(start 81.7372 -88.486234)
		(end 81.247234 -88.9762)
		(width 0.127)
		(layer "In2.Cu")
		(net "EXP_XM_ADDR_19")
	)
	(segment
		(start 111.99876 -89.928446)
		(end 111.819436 -89.928446)
		(width 0.127)
		(layer "In2.Cu")
		(net "EXP_XM_ADDR_19")
	)
	(segment
		(start 80.586326 -88.180926)
		(end 81.1657 -88.180926)
		(width 0.127)
		(layer "In2.Cu")
		(net "EXP_XM_ADDR_19")
	)
	(segment
		(start 111.819436 -89.928446)
		(end 111.38154 -90.366342)
		(width 0.127)
		(layer "In2.Cu")
		(net "EXP_XM_ADDR_19")
	)
	(segment
		(start 74.7776 -86.287102)
		(end 76.882244 -86.287102)
		(width 0.127)
		(layer "In2.Cu")
		(net "EXP_XM_ADDR_19")
	)
	(segment
		(start 76.512166 -86.9442)
		(end 74.7776 -86.9442)
		(width 0.127)
		(layer "In2.Cu")
		(net "EXP_XM_ADDR_19")
	)
	(segment
		(start 79.356458 -86.951058)
		(end 80.586326 -88.180926)
		(width 0.127)
		(layer "In2.Cu")
		(net "EXP_XM_ADDR_19")
	)
	(segment
		(start 82.3214 -87.8332)
		(end 82.199226 -87.711026)
		(width 0.127)
		(layer "In2.Cu")
		(net "EXP_XM_ADDR_19")
	)
	(segment
		(start 81.8642 -87.711026)
		(end 81.7372 -87.838026)
		(width 0.127)
		(layer "In2.Cu")
		(net "EXP_XM_ADDR_19")
	)
	(segment
		(start 112.35817 -89.389712)
		(end 112.35817 -89.569036)
		(width 0.127)
		(layer "In2.Cu")
		(net "EXP_XM_ADDR_19")
	)
	(segment
		(start 79.128366 -87.503)
		(end 77.070966 -87.503)
		(width 0.127)
		(layer "In2.Cu")
		(net "EXP_XM_ADDR_19")
	)
	(segment
		(start 82.3214 -88.265)
		(end 82.3214 -87.8332)
		(width 0.127)
		(layer "In2.Cu")
		(net "EXP_XM_ADDR_19")
	)
	(segment
		(start 112.521238 -90.271854)
		(end 112.341914 -90.271854)
		(width 0.127)
		(layer "In2.Cu")
		(net "EXP_XM_ADDR_19")
	)
	(segment
		(start 82.8802 -88.392)
		(end 82.4484 -88.392)
		(width 0.127)
		(layer "In2.Cu")
		(net "EXP_XM_ADDR_19")
	)
	(segment
		(start 112.835182 -88.9127)
		(end 112.35817 -89.389712)
		(width 0.127)
		(layer "In2.Cu")
		(net "EXP_XM_ADDR_19")
	)
	(segment
		(start 113.8682 -87.946484)
		(end 112.901984 -88.9127)
		(width 0.127)
		(layer "In2.Cu")
		(net "EXP_XM_ADDR_19")
	)
	(segment
		(start 81.7372 -87.838026)
		(end 81.7372 -88.486234)
		(width 0.127)
		(layer "In2.Cu")
		(net "EXP_XM_ADDR_19")
	)
	(segment
		(start 111.38154 -90.366342)
		(end 84.854542 -90.366342)
		(width 0.127)
		(layer "In2.Cu")
		(net "EXP_XM_ADDR_19")
	)
	(segment
		(start 113.8682 -85.725)
		(end 113.8682 -87.946484)
		(width 0.127)
		(layer "In2.Cu")
		(net "EXP_XM_ADDR_19")
	)
	(segment
		(start 74.6506 -86.414102)
		(end 74.7776 -86.287102)
		(width 0.127)
		(layer "In2.Cu")
		(net "EXP_XM_ADDR_19")
	)
	(segment
		(start 112.701324 -90.091768)
		(end 112.521238 -90.271854)
		(width 0.127)
		(layer "In2.Cu")
		(net "EXP_XM_ADDR_19")
	)
	(segment
		(start 112.701324 -89.912444)
		(end 112.701324 -90.091768)
		(width 0.127)
		(layer "In2.Cu")
		(net "EXP_XM_ADDR_19")
	)
	(segment
		(start 112.901984 -88.9127)
		(end 112.835182 -88.9127)
		(width 0.127)
		(layer "In2.Cu")
		(net "EXP_XM_ADDR_19")
	)
	(segment
		(start 77.5462 -86.951058)
		(end 79.356458 -86.951058)
		(width 0.127)
		(layer "In2.Cu")
		(net "EXP_XM_ADDR_19")
	)
	(segment
		(start 76.882244 -86.287102)
		(end 77.5462 -86.951058)
		(width 0.127)
		(layer "In2.Cu")
		(net "EXP_XM_ADDR_19")
	)
	(segment
		(start 84.854542 -90.366342)
		(end 82.8802 -88.392)
		(width 0.127)
		(layer "In2.Cu")
		(net "EXP_XM_ADDR_19")
	)
	(segment
		(start 74.7776 -86.9442)
		(end 74.6506 -86.8172)
		(width 0.127)
		(layer "In2.Cu")
		(net "EXP_XM_ADDR_19")
	)
	(segment
		(start 82.4484 -88.392)
		(end 82.3214 -88.265)
		(width 0.127)
		(layer "In2.Cu")
		(net "EXP_XM_ADDR_19")
	)
	(segment
		(start 112.35817 -89.569036)
		(end 112.701324 -89.912444)
		(width 0.127)
		(layer "In2.Cu")
		(net "EXP_XM_ADDR_19")
	)
	(segment
		(start 80.601566 -88.9762)
		(end 79.128366 -87.503)
		(width 0.127)
		(layer "In2.Cu")
		(net "EXP_XM_ADDR_19")
	)
	(segment
		(start 74.6506 -86.8172)
		(end 74.6506 -86.414102)
		(width 0.127)
		(layer "In2.Cu")
		(net "EXP_XM_ADDR_19")
	)
	(segment
		(start 116.500148 -83.650328)
		(end 116.500148 -82.500216)
		(width 0.127)
		(layer "F.Cu")
		(net "EXP_XM_ADDR_18")
	)
	(segment
		(start 116.923058 -86.550754)
		(end 117.106446 -86.550754)
		(width 0.127)
		(layer "F.Cu")
		(net "EXP_XM_ADDR_18")
	)
	(segment
		(start 117.106446 -86.550754)
		(end 117.9322 -85.725)
		(width 0.127)
		(layer "F.Cu")
		(net "EXP_XM_ADDR_18")
	)
	(segment
		(start 117.9322 -85.08238)
		(end 116.500148 -83.650328)
		(width 0.127)
		(layer "F.Cu")
		(net "EXP_XM_ADDR_18")
	)
	(segment
		(start 117.9322 -85.725)
		(end 117.9322 -85.08238)
		(width 0.127)
		(layer "F.Cu")
		(net "EXP_XM_ADDR_18")
	)
	(via
		(at 117.9322 -85.725)
		(size 0.508)
		(drill 0.254)
		(layers "F.Cu" "B.Cu")
		(net "EXP_XM_ADDR_18")
	)
	(via
		(at 82.6008 -92.7354)
		(size 0.508)
		(drill 0.254)
		(layers "F.Cu" "B.Cu")
		(net "EXP_XM_ADDR_18")
	)
	(segment
		(start 83.22818 -90.5256)
		(end 83.22818 -93.261942)
		(width 0.127)
		(layer "B.Cu")
		(net "EXP_XM_ADDR_18")
	)
	(segment
		(start 83.22818 -93.261942)
		(end 82.76844 -93.721682)
		(width 0.127)
		(layer "B.Cu")
		(net "EXP_XM_ADDR_18")
	)
	(segment
		(start 83.10118 -90.3986)
		(end 83.22818 -90.5256)
		(width 0.127)
		(layer "B.Cu")
		(net "EXP_XM_ADDR_18")
	)
	(segment
		(start 82.6008 -92.7354)
		(end 82.6008 -90.5256)
		(width 0.127)
		(layer "B.Cu")
		(net "EXP_XM_ADDR_18")
	)
	(segment
		(start 82.7278 -90.3986)
		(end 83.10118 -90.3986)
		(width 0.127)
		(layer "B.Cu")
		(net "EXP_XM_ADDR_18")
	)
	(segment
		(start 82.76844 -93.721682)
		(end 82.76844 -94.8309)
		(width 0.127)
		(layer "B.Cu")
		(net "EXP_XM_ADDR_18")
	)
	(segment
		(start 82.6008 -90.5256)
		(end 82.7278 -90.3986)
		(width 0.127)
		(layer "B.Cu")
		(net "EXP_XM_ADDR_18")
	)
	(segment
		(start 76.46797 -92.7354)
		(end 76.21397 -92.7354)
		(width 0.127)
		(layer "In2.Cu")
		(net "EXP_XM_ADDR_18")
	)
	(segment
		(start 87.838026 -94.3737)
		(end 88.236552 -93.975174)
		(width 0.127)
		(layer "In2.Cu")
		(net "EXP_XM_ADDR_18")
	)
	(segment
		(start 76.59497 -91.9734)
		(end 76.59497 -92.6084)
		(width 0.127)
		(layer "In2.Cu")
		(net "EXP_XM_ADDR_18")
	)
	(segment
		(start 82.6008 -92.7354)
		(end 80.27797 -92.7354)
		(width 0.127)
		(layer "In2.Cu")
		(net "EXP_XM_ADDR_18")
	)
	(segment
		(start 83.6295 -94.3483)
		(end 83.923124 -94.3483)
		(width 0.127)
		(layer "In2.Cu")
		(net "EXP_XM_ADDR_18")
	)
	(segment
		(start 85.599524 -93.599)
		(end 85.599524 -94.1324)
		(width 0.127)
		(layer "In2.Cu")
		(net "EXP_XM_ADDR_18")
	)
	(segment
		(start 82.581496 -93.300296)
		(end 83.6295 -94.3483)
		(width 0.127)
		(layer "In2.Cu")
		(net "EXP_XM_ADDR_18")
	)
	(segment
		(start 84.583524 -94.1832)
		(end 84.710524 -94.3102)
		(width 0.127)
		(layer "In2.Cu")
		(net "EXP_XM_ADDR_18")
	)
	(segment
		(start 84.050124 -94.2213)
		(end 84.050124 -93.599)
		(width 0.127)
		(layer "In2.Cu")
		(net "EXP_XM_ADDR_18")
	)
	(segment
		(start 77.48397 -92.7354)
		(end 77.22997 -92.7354)
		(width 0.127)
		(layer "In2.Cu")
		(net "EXP_XM_ADDR_18")
	)
	(segment
		(start 77.10297 -91.9734)
		(end 76.97597 -91.8464)
		(width 0.127)
		(layer "In2.Cu")
		(net "EXP_XM_ADDR_18")
	)
	(segment
		(start 78.75397 -91.8464)
		(end 78.62697 -91.9734)
		(width 0.127)
		(layer "In2.Cu")
		(net "EXP_XM_ADDR_18")
	)
	(segment
		(start 76.21397 -92.7354)
		(end 76.08697 -92.6084)
		(width 0.127)
		(layer "In2.Cu")
		(net "EXP_XM_ADDR_18")
	)
	(segment
		(start 80.27797 -92.7354)
		(end 80.15097 -92.6084)
		(width 0.127)
		(layer "In2.Cu")
		(net "EXP_XM_ADDR_18")
	)
	(segment
		(start 75.57897 -92.6084)
		(end 75.45197 -92.7354)
		(width 0.127)
		(layer "In2.Cu")
		(net "EXP_XM_ADDR_18")
	)
	(segment
		(start 79.13497 -92.6084)
		(end 79.13497 -91.9734)
		(width 0.127)
		(layer "In2.Cu")
		(net "EXP_XM_ADDR_18")
	)
	(segment
		(start 117.4877 -90.463624)
		(end 117.4877 -86.332822)
		(width 0.127)
		(layer "In2.Cu")
		(net "EXP_XM_ADDR_18")
	)
	(segment
		(start 84.710524 -94.3102)
		(end 84.964524 -94.3102)
		(width 0.127)
		(layer "In2.Cu")
		(net "EXP_XM_ADDR_18")
	)
	(segment
		(start 84.583524 -93.599)
		(end 84.583524 -94.1832)
		(width 0.127)
		(layer "In2.Cu")
		(net "EXP_XM_ADDR_18")
	)
	(segment
		(start 84.456524 -93.472)
		(end 84.583524 -93.599)
		(width 0.127)
		(layer "In2.Cu")
		(net "EXP_XM_ADDR_18")
	)
	(segment
		(start 76.08697 -91.9988)
		(end 75.95997 -91.8718)
		(width 0.127)
		(layer "In2.Cu")
		(net "EXP_XM_ADDR_18")
	)
	(segment
		(start 76.97597 -91.8464)
		(end 76.72197 -91.8464)
		(width 0.127)
		(layer "In2.Cu")
		(net "EXP_XM_ADDR_18")
	)
	(segment
		(start 84.177124 -93.472)
		(end 84.456524 -93.472)
		(width 0.127)
		(layer "In2.Cu")
		(net "EXP_XM_ADDR_18")
	)
	(segment
		(start 74.7268 -93.173296)
		(end 74.8538 -93.300296)
		(width 0.127)
		(layer "In2.Cu")
		(net "EXP_XM_ADDR_18")
	)
	(segment
		(start 85.599524 -94.1324)
		(end 85.840824 -94.3737)
		(width 0.127)
		(layer "In2.Cu")
		(net "EXP_XM_ADDR_18")
	)
	(segment
		(start 78.11897 -92.6084)
		(end 78.11897 -91.9734)
		(width 0.127)
		(layer "In2.Cu")
		(net "EXP_XM_ADDR_18")
	)
	(segment
		(start 79.13497 -91.9734)
		(end 79.00797 -91.8464)
		(width 0.127)
		(layer "In2.Cu")
		(net "EXP_XM_ADDR_18")
	)
	(segment
		(start 79.26197 -92.7354)
		(end 79.13497 -92.6084)
		(width 0.127)
		(layer "In2.Cu")
		(net "EXP_XM_ADDR_18")
	)
	(segment
		(start 77.61097 -92.6084)
		(end 77.48397 -92.7354)
		(width 0.127)
		(layer "In2.Cu")
		(net "EXP_XM_ADDR_18")
	)
	(segment
		(start 76.72197 -91.8464)
		(end 76.59497 -91.9734)
		(width 0.127)
		(layer "In2.Cu")
		(net "EXP_XM_ADDR_18")
	)
	(segment
		(start 85.840824 -94.3737)
		(end 87.838026 -94.3737)
		(width 0.127)
		(layer "In2.Cu")
		(net "EXP_XM_ADDR_18")
	)
	(segment
		(start 83.923124 -94.3483)
		(end 84.050124 -94.2213)
		(width 0.127)
		(layer "In2.Cu")
		(net "EXP_XM_ADDR_18")
	)
	(segment
		(start 80.15097 -92.6084)
		(end 80.15097 -91.948)
		(width 0.127)
		(layer "In2.Cu")
		(net "EXP_XM_ADDR_18")
	)
	(segment
		(start 117.4877 -86.332822)
		(end 117.9322 -85.888322)
		(width 0.127)
		(layer "In2.Cu")
		(net "EXP_XM_ADDR_18")
	)
	(segment
		(start 113.97615 -93.975174)
		(end 117.4877 -90.463624)
		(width 0.127)
		(layer "In2.Cu")
		(net "EXP_XM_ADDR_18")
	)
	(segment
		(start 75.57897 -91.9988)
		(end 75.57897 -92.6084)
		(width 0.127)
		(layer "In2.Cu")
		(net "EXP_XM_ADDR_18")
	)
	(segment
		(start 75.95997 -91.8718)
		(end 75.70597 -91.8718)
		(width 0.127)
		(layer "In2.Cu")
		(net "EXP_XM_ADDR_18")
	)
	(segment
		(start 76.08697 -92.6084)
		(end 76.08697 -91.9988)
		(width 0.127)
		(layer "In2.Cu")
		(net "EXP_XM_ADDR_18")
	)
	(segment
		(start 88.236552 -93.975174)
		(end 113.97615 -93.975174)
		(width 0.127)
		(layer "In2.Cu")
		(net "EXP_XM_ADDR_18")
	)
	(segment
		(start 77.10297 -92.6084)
		(end 77.10297 -91.9734)
		(width 0.127)
		(layer "In2.Cu")
		(net "EXP_XM_ADDR_18")
	)
	(segment
		(start 76.59497 -92.6084)
		(end 76.46797 -92.7354)
		(width 0.127)
		(layer "In2.Cu")
		(net "EXP_XM_ADDR_18")
	)
	(segment
		(start 74.8538 -93.300296)
		(end 82.581496 -93.300296)
		(width 0.127)
		(layer "In2.Cu")
		(net "EXP_XM_ADDR_18")
	)
	(segment
		(start 75.45197 -92.7354)
		(end 74.8538 -92.7354)
		(width 0.127)
		(layer "In2.Cu")
		(net "EXP_XM_ADDR_18")
	)
	(segment
		(start 79.64297 -91.948)
		(end 79.64297 -92.6084)
		(width 0.127)
		(layer "In2.Cu")
		(net "EXP_XM_ADDR_18")
	)
	(segment
		(start 78.11897 -91.9734)
		(end 77.99197 -91.8464)
		(width 0.127)
		(layer "In2.Cu")
		(net "EXP_XM_ADDR_18")
	)
	(segment
		(start 78.62697 -92.6084)
		(end 78.49997 -92.7354)
		(width 0.127)
		(layer "In2.Cu")
		(net "EXP_XM_ADDR_18")
	)
	(segment
		(start 77.61097 -91.9734)
		(end 77.61097 -92.6084)
		(width 0.127)
		(layer "In2.Cu")
		(net "EXP_XM_ADDR_18")
	)
	(segment
		(start 79.76997 -91.821)
		(end 79.64297 -91.948)
		(width 0.127)
		(layer "In2.Cu")
		(net "EXP_XM_ADDR_18")
	)
	(segment
		(start 74.7268 -92.8624)
		(end 74.7268 -93.173296)
		(width 0.127)
		(layer "In2.Cu")
		(net "EXP_XM_ADDR_18")
	)
	(segment
		(start 78.24597 -92.7354)
		(end 78.11897 -92.6084)
		(width 0.127)
		(layer "In2.Cu")
		(net "EXP_XM_ADDR_18")
	)
	(segment
		(start 79.00797 -91.8464)
		(end 78.75397 -91.8464)
		(width 0.127)
		(layer "In2.Cu")
		(net "EXP_XM_ADDR_18")
	)
	(segment
		(start 77.73797 -91.8464)
		(end 77.61097 -91.9734)
		(width 0.127)
		(layer "In2.Cu")
		(net "EXP_XM_ADDR_18")
	)
	(segment
		(start 74.8538 -92.7354)
		(end 74.7268 -92.8624)
		(width 0.127)
		(layer "In2.Cu")
		(net "EXP_XM_ADDR_18")
	)
	(segment
		(start 78.62697 -91.9734)
		(end 78.62697 -92.6084)
		(width 0.127)
		(layer "In2.Cu")
		(net "EXP_XM_ADDR_18")
	)
	(segment
		(start 85.091524 -93.599)
		(end 85.218524 -93.472)
		(width 0.127)
		(layer "In2.Cu")
		(net "EXP_XM_ADDR_18")
	)
	(segment
		(start 85.472524 -93.472)
		(end 85.599524 -93.599)
		(width 0.127)
		(layer "In2.Cu")
		(net "EXP_XM_ADDR_18")
	)
	(segment
		(start 85.091524 -94.1832)
		(end 85.091524 -93.599)
		(width 0.127)
		(layer "In2.Cu")
		(net "EXP_XM_ADDR_18")
	)
	(segment
		(start 78.49997 -92.7354)
		(end 78.24597 -92.7354)
		(width 0.127)
		(layer "In2.Cu")
		(net "EXP_XM_ADDR_18")
	)
	(segment
		(start 75.70597 -91.8718)
		(end 75.57897 -91.9988)
		(width 0.127)
		(layer "In2.Cu")
		(net "EXP_XM_ADDR_18")
	)
	(segment
		(start 77.99197 -91.8464)
		(end 77.73797 -91.8464)
		(width 0.127)
		(layer "In2.Cu")
		(net "EXP_XM_ADDR_18")
	)
	(segment
		(start 117.9322 -85.888322)
		(end 117.9322 -85.725)
		(width 0.127)
		(layer "In2.Cu")
		(net "EXP_XM_ADDR_18")
	)
	(segment
		(start 77.22997 -92.7354)
		(end 77.10297 -92.6084)
		(width 0.127)
		(layer "In2.Cu")
		(net "EXP_XM_ADDR_18")
	)
	(segment
		(start 84.050124 -93.599)
		(end 84.177124 -93.472)
		(width 0.127)
		(layer "In2.Cu")
		(net "EXP_XM_ADDR_18")
	)
	(segment
		(start 80.15097 -91.948)
		(end 80.02397 -91.821)
		(width 0.127)
		(layer "In2.Cu")
		(net "EXP_XM_ADDR_18")
	)
	(segment
		(start 79.51597 -92.7354)
		(end 79.26197 -92.7354)
		(width 0.127)
		(layer "In2.Cu")
		(net "EXP_XM_ADDR_18")
	)
	(segment
		(start 85.218524 -93.472)
		(end 85.472524 -93.472)
		(width 0.127)
		(layer "In2.Cu")
		(net "EXP_XM_ADDR_18")
	)
	(segment
		(start 84.964524 -94.3102)
		(end 85.091524 -94.1832)
		(width 0.127)
		(layer "In2.Cu")
		(net "EXP_XM_ADDR_18")
	)
	(segment
		(start 80.02397 -91.821)
		(end 79.76997 -91.821)
		(width 0.127)
		(layer "In2.Cu")
		(net "EXP_XM_ADDR_18")
	)
	(segment
		(start 79.64297 -92.6084)
		(end 79.51597 -92.7354)
		(width 0.127)
		(layer "In2.Cu")
		(net "EXP_XM_ADDR_18")
	)
	(segment
		(start 115.50015 -79.500222)
		(end 116.000022 -80.000094)
		(width 0.127)
		(layer "F.Cu")
		(net "EXP_XM_ADDR_17")
	)
	(via
		(at 115.9637 -85.725)
		(size 0.508)
		(drill 0.254)
		(layers "F.Cu" "B.Cu")
		(net "EXP_XM_ADDR_17")
	)
	(via
		(at 116.000022 -80.000094)
		(size 0.4572)
		(drill 0.2032)
		(layers "F.Cu" "B.Cu")
		(net "EXP_XM_ADDR_17")
	)
	(via
		(at 72.9869 -89.2048)
		(size 0.508)
		(drill 0.254)
		(layers "F.Cu" "B.Cu")
		(net "EXP_XM_ADDR_17")
	)
	(segment
		(start 116.000022 -80.240124)
		(end 116.000022 -80.000094)
		(width 0.127)
		(layer "B.Cu")
		(net "EXP_XM_ADDR_17")
	)
	(segment
		(start 116.84 -86.5505)
		(end 116.84 -86.256114)
		(width 0.127)
		(layer "B.Cu")
		(net "EXP_XM_ADDR_17")
	)
	(segment
		(start 75.8952 -85.5091)
		(end 75.8952 -79.163418)
		(width 0.127)
		(layer "B.Cu")
		(net "EXP_XM_ADDR_17")
	)
	(segment
		(start 72.9869 -89.2048)
		(end 72.9869 -88.4174)
		(width 0.127)
		(layer "B.Cu")
		(net "EXP_XM_ADDR_17")
	)
	(segment
		(start 115.555522 -81.265522)
		(end 115.555522 -80.684624)
		(width 0.127)
		(layer "B.Cu")
		(net "EXP_XM_ADDR_17")
	)
	(segment
		(start 74.76744 -78.035658)
		(end 74.76744 -75.6031)
		(width 0.127)
		(layer "B.Cu")
		(net "EXP_XM_ADDR_17")
	)
	(segment
		(start 72.9869 -88.4174)
		(end 75.8952 -85.5091)
		(width 0.127)
		(layer "B.Cu")
		(net "EXP_XM_ADDR_17")
	)
	(segment
		(start 116.84 -86.256114)
		(end 116.4717 -85.887814)
		(width 0.127)
		(layer "B.Cu")
		(net "EXP_XM_ADDR_17")
	)
	(segment
		(start 115.9637 -85.725)
		(end 115.963446 -85.725254)
		(width 0.127)
		(layer "B.Cu")
		(net "EXP_XM_ADDR_17")
	)
	(segment
		(start 116.4717 -82.1817)
		(end 115.555522 -81.265522)
		(width 0.127)
		(layer "B.Cu")
		(net "EXP_XM_ADDR_17")
	)
	(segment
		(start 115.963446 -85.725254)
		(end 115.963446 -86.12632)
		(width 0.127)
		(layer "B.Cu")
		(net "EXP_XM_ADDR_17")
	)
	(segment
		(start 75.8952 -79.163418)
		(end 74.76744 -78.035658)
		(width 0.127)
		(layer "B.Cu")
		(net "EXP_XM_ADDR_17")
	)
	(segment
		(start 115.963446 -86.12632)
		(end 115.7986 -86.291166)
		(width 0.127)
		(layer "B.Cu")
		(net "EXP_XM_ADDR_17")
	)
	(segment
		(start 116.4717 -85.887814)
		(end 116.4717 -82.1817)
		(width 0.127)
		(layer "B.Cu")
		(net "EXP_XM_ADDR_17")
	)
	(segment
		(start 115.555522 -80.684624)
		(end 116.000022 -80.240124)
		(width 0.127)
		(layer "B.Cu")
		(net "EXP_XM_ADDR_17")
	)
	(segment
		(start 115.7986 -86.5505)
		(end 116.84 -86.5505)
		(width 0.127)
		(layer "B.Cu")
		(net "EXP_XM_ADDR_17")
	)
	(segment
		(start 115.7986 -86.291166)
		(end 115.7986 -86.5505)
		(width 0.127)
		(layer "B.Cu")
		(net "EXP_XM_ADDR_17")
	)
	(segment
		(start 81.17332 -91.366086)
		(end 80.612234 -90.805)
		(width 0.127)
		(layer "In2.Cu")
		(net "EXP_XM_ADDR_17")
	)
	(segment
		(start 115.9637 -89.761314)
		(end 113.27384 -92.451174)
		(width 0.127)
		(layer "In2.Cu")
		(net "EXP_XM_ADDR_17")
	)
	(segment
		(start 70.358 -89.8398)
		(end 70.485 -89.7128)
		(width 0.127)
		(layer "In2.Cu")
		(net "EXP_XM_ADDR_17")
	)
	(segment
		(start 72.8218 -89.7128)
		(end 72.9869 -89.5477)
		(width 0.127)
		(layer "In2.Cu")
		(net "EXP_XM_ADDR_17")
	)
	(segment
		(start 70.485 -90.29065)
		(end 70.358 -90.16365)
		(width 0.127)
		(layer "In2.Cu")
		(net "EXP_XM_ADDR_17")
	)
	(segment
		(start 115.9637 -85.725)
		(end 115.9637 -89.761314)
		(width 0.127)
		(layer "In2.Cu")
		(net "EXP_XM_ADDR_17")
	)
	(segment
		(start 83.838288 -92.451174)
		(end 82.7532 -91.366086)
		(width 0.127)
		(layer "In2.Cu")
		(net "EXP_XM_ADDR_17")
	)
	(segment
		(start 70.485 -89.7128)
		(end 72.8218 -89.7128)
		(width 0.127)
		(layer "In2.Cu")
		(net "EXP_XM_ADDR_17")
	)
	(segment
		(start 73.09485 -90.29065)
		(end 70.485 -90.29065)
		(width 0.127)
		(layer "In2.Cu")
		(net "EXP_XM_ADDR_17")
	)
	(segment
		(start 70.358 -90.16365)
		(end 70.358 -89.8398)
		(width 0.127)
		(layer "In2.Cu")
		(net "EXP_XM_ADDR_17")
	)
	(segment
		(start 82.7532 -91.366086)
		(end 81.17332 -91.366086)
		(width 0.127)
		(layer "In2.Cu")
		(net "EXP_XM_ADDR_17")
	)
	(segment
		(start 72.9869 -89.5477)
		(end 72.9869 -89.2048)
		(width 0.127)
		(layer "In2.Cu")
		(net "EXP_XM_ADDR_17")
	)
	(segment
		(start 113.27384 -92.451174)
		(end 83.838288 -92.451174)
		(width 0.127)
		(layer "In2.Cu")
		(net "EXP_XM_ADDR_17")
	)
	(segment
		(start 80.612234 -90.805)
		(end 73.6092 -90.805)
		(width 0.127)
		(layer "In2.Cu")
		(net "EXP_XM_ADDR_17")
	)
	(segment
		(start 73.6092 -90.805)
		(end 73.09485 -90.29065)
		(width 0.127)
		(layer "In2.Cu")
		(net "EXP_XM_ADDR_17")
	)
	(segment
		(start 117.811804 -83.594194)
		(end 117.624098 -83.7819)
		(width 0.127)
		(layer "F.Cu")
		(net "EXP_XM_ADDR_16")
	)
	(segment
		(start 118.57736 -85.35416)
		(end 118.57736 -84.985098)
		(width 0.127)
		(layer "F.Cu")
		(net "EXP_XM_ADDR_16")
	)
	(segment
		(start 116.500148 -81.700116)
		(end 116.500148 -81.500218)
		(width 0.127)
		(layer "F.Cu")
		(net "EXP_XM_ADDR_16")
	)
	(segment
		(start 118.203726 -84.640166)
		(end 118.024402 -84.640166)
		(width 0.127)
		(layer "F.Cu")
		(net "EXP_XM_ADDR_16")
	)
	(segment
		(start 118.57736 -84.985098)
		(end 118.890034 -84.672424)
		(width 0.127)
		(layer "F.Cu")
		(net "EXP_XM_ADDR_16")
	)
	(segment
		(start 118.710456 -84.313014)
		(end 118.530624 -84.313014)
		(width 0.127)
		(layer "F.Cu")
		(net "EXP_XM_ADDR_16")
	)
	(segment
		(start 117.624098 -83.7819)
		(end 117.444266 -83.7819)
		(width 0.127)
		(layer "F.Cu")
		(net "EXP_XM_ADDR_16")
	)
	(segment
		(start 118.122446 -86.550754)
		(end 118.9482 -85.725)
		(width 0.127)
		(layer "F.Cu")
		(net "EXP_XM_ADDR_16")
	)
	(segment
		(start 118.024402 -84.640166)
		(end 117.844062 -84.459826)
		(width 0.127)
		(layer "F.Cu")
		(net "EXP_XM_ADDR_16")
	)
	(segment
		(start 118.890034 -84.672424)
		(end 118.890034 -84.492592)
		(width 0.127)
		(layer "F.Cu")
		(net "EXP_XM_ADDR_16")
	)
	(segment
		(start 117.844062 -84.459826)
		(end 117.844062 -84.280502)
		(width 0.127)
		(layer "F.Cu")
		(net "EXP_XM_ADDR_16")
	)
	(segment
		(start 117.029484 -83.367118)
		(end 117.029484 -82.229452)
		(width 0.127)
		(layer "F.Cu")
		(net "EXP_XM_ADDR_16")
	)
	(segment
		(start 117.029484 -82.229452)
		(end 116.500148 -81.700116)
		(width 0.127)
		(layer "F.Cu")
		(net "EXP_XM_ADDR_16")
	)
	(segment
		(start 117.991636 -83.594194)
		(end 117.811804 -83.594194)
		(width 0.127)
		(layer "F.Cu")
		(net "EXP_XM_ADDR_16")
	)
	(segment
		(start 117.939058 -86.550754)
		(end 118.122446 -86.550754)
		(width 0.127)
		(layer "F.Cu")
		(net "EXP_XM_ADDR_16")
	)
	(segment
		(start 117.444266 -83.7819)
		(end 117.029484 -83.367118)
		(width 0.127)
		(layer "F.Cu")
		(net "EXP_XM_ADDR_16")
	)
	(segment
		(start 118.9482 -85.725)
		(end 118.57736 -85.35416)
		(width 0.127)
		(layer "F.Cu")
		(net "EXP_XM_ADDR_16")
	)
	(segment
		(start 118.171214 -83.773772)
		(end 117.991636 -83.594194)
		(width 0.127)
		(layer "F.Cu")
		(net "EXP_XM_ADDR_16")
	)
	(segment
		(start 118.530624 -84.313014)
		(end 118.203726 -84.640166)
		(width 0.127)
		(layer "F.Cu")
		(net "EXP_XM_ADDR_16")
	)
	(segment
		(start 118.890034 -84.492592)
		(end 118.710456 -84.313014)
		(width 0.127)
		(layer "F.Cu")
		(net "EXP_XM_ADDR_16")
	)
	(segment
		(start 118.171214 -83.953604)
		(end 118.171214 -83.773772)
		(width 0.127)
		(layer "F.Cu")
		(net "EXP_XM_ADDR_16")
	)
	(segment
		(start 117.844062 -84.280502)
		(end 118.171214 -83.953604)
		(width 0.127)
		(layer "F.Cu")
		(net "EXP_XM_ADDR_16")
	)
	(via
		(at 75.204066 -96.399096)
		(size 0.508)
		(drill 0.254)
		(layers "F.Cu" "B.Cu")
		(net "EXP_XM_ADDR_16")
	)
	(via
		(at 118.9482 -85.725)
		(size 0.508)
		(drill 0.254)
		(layers "F.Cu" "B.Cu")
		(net "EXP_XM_ADDR_16")
	)
	(segment
		(start 74.76744 -94.8309)
		(end 74.76744 -95.96247)
		(width 0.127)
		(layer "B.Cu")
		(net "EXP_XM_ADDR_16")
	)
	(segment
		(start 74.76744 -95.96247)
		(end 75.204066 -96.399096)
		(width 0.127)
		(layer "B.Cu")
		(net "EXP_XM_ADDR_16")
	)
	(segment
		(start 115.069112 -94.986856)
		(end 114.88928 -94.986856)
		(width 0.127)
		(layer "In2.Cu")
		(net "EXP_XM_ADDR_16")
	)
	(segment
		(start 118.864126 -89.292938)
		(end 119.271288 -89.292938)
		(width 0.127)
		(layer "In2.Cu")
		(net "EXP_XM_ADDR_16")
	)
	(segment
		(start 83.132168 -95.3897)
		(end 82.058764 -94.316296)
		(width 0.127)
		(layer "In2.Cu")
		(net "EXP_XM_ADDR_16")
	)
	(segment
		(start 118.599458 -90.181938)
		(end 118.726458 -90.308938)
		(width 0.127)
		(layer "In2.Cu")
		(net "EXP_XM_ADDR_16")
	)
	(segment
		(start 115.24869 -94.627446)
		(end 115.24869 -94.807278)
		(width 0.127)
		(layer "In2.Cu")
		(net "EXP_XM_ADDR_16")
	)
	(segment
		(start 115.24869 -94.807278)
		(end 115.069112 -94.986856)
		(width 0.127)
		(layer "In2.Cu")
		(net "EXP_XM_ADDR_16")
	)
	(segment
		(start 88.259158 -95.3897)
		(end 83.132168 -95.3897)
		(width 0.127)
		(layer "In2.Cu")
		(net "EXP_XM_ADDR_16")
	)
	(segment
		(start 73.771252 -95.418402)
		(end 73.644252 -95.545402)
		(width 0.127)
		(layer "In2.Cu")
		(net "EXP_XM_ADDR_16")
	)
	(segment
		(start 74.29373 -94.910402)
		(end 74.42073 -95.037402)
		(width 0.127)
		(layer "In2.Cu")
		(net "EXP_XM_ADDR_16")
	)
	(segment
		(start 74.411586 -97.162366)
		(end 76.639928 -99.390708)
		(width 0.127)
		(layer "In2.Cu")
		(net "EXP_XM_ADDR_16")
	)
	(segment
		(start 73.771252 -94.910402)
		(end 74.29373 -94.910402)
		(width 0.127)
		(layer "In2.Cu")
		(net "EXP_XM_ADDR_16")
	)
	(segment
		(start 119.398288 -89.419938)
		(end 119.398288 -89.673938)
		(width 0.127)
		(layer "In2.Cu")
		(net "EXP_XM_ADDR_16")
	)
	(segment
		(start 73.644252 -95.545402)
		(end 73.644252 -95.799402)
		(width 0.127)
		(layer "In2.Cu")
		(net "EXP_XM_ADDR_16")
	)
	(segment
		(start 115.094766 -94.29369)
		(end 115.094766 -94.473522)
		(width 0.127)
		(layer "In2.Cu")
		(net "EXP_XM_ADDR_16")
	)
	(segment
		(start 118.649242 -87.473536)
		(end 119.23268 -87.473536)
		(width 0.127)
		(layer "In2.Cu")
		(net "EXP_XM_ADDR_16")
	)
	(segment
		(start 78.212188 -98.800666)
		(end 78.085188 -98.673666)
		(width 0.127)
		(layer "In2.Cu")
		(net "EXP_XM_ADDR_16")
	)
	(segment
		(start 118.726458 -89.800938)
		(end 118.599458 -89.927938)
		(width 0.127)
		(layer "In2.Cu")
		(net "EXP_XM_ADDR_16")
	)
	(segment
		(start 117.136926 -92.25153)
		(end 115.094766 -94.29369)
		(width 0.127)
		(layer "In2.Cu")
		(net "EXP_XM_ADDR_16")
	)
	(segment
		(start 74.284586 -95.926402)
		(end 74.411586 -96.053402)
		(width 0.127)
		(layer "In2.Cu")
		(net "EXP_XM_ADDR_16")
	)
	(segment
		(start 76.950316 -98.673666)
		(end 75.204066 -96.927416)
		(width 0.127)
		(layer "In2.Cu")
		(net "EXP_XM_ADDR_16")
	)
	(segment
		(start 119.02059 -86.654132)
		(end 118.649242 -86.654132)
		(width 0.127)
		(layer "In2.Cu")
		(net "EXP_XM_ADDR_16")
	)
	(segment
		(start 119.271288 -89.292938)
		(end 119.398288 -89.419938)
		(width 0.127)
		(layer "In2.Cu")
		(net "EXP_XM_ADDR_16")
	)
	(segment
		(start 119.139462 -90.471752)
		(end 119.139462 -90.973656)
		(width 0.127)
		(layer "In2.Cu")
		(net "EXP_XM_ADDR_16")
	)
	(segment
		(start 118.522242 -86.781132)
		(end 118.522242 -87.346536)
		(width 0.127)
		(layer "In2.Cu")
		(net "EXP_XM_ADDR_16")
	)
	(segment
		(start 119.4689 -87.709756)
		(end 119.4689 -88.597486)
		(width 0.127)
		(layer "In2.Cu")
		(net "EXP_XM_ADDR_16")
	)
	(segment
		(start 118.649242 -86.654132)
		(end 118.522242 -86.781132)
		(width 0.127)
		(layer "In2.Cu")
		(net "EXP_XM_ADDR_16")
	)
	(segment
		(start 74.42073 -95.037402)
		(end 74.42073 -95.291402)
		(width 0.127)
		(layer "In2.Cu")
		(net "EXP_XM_ADDR_16")
	)
	(segment
		(start 74.29373 -95.418402)
		(end 73.771252 -95.418402)
		(width 0.127)
		(layer "In2.Cu")
		(net "EXP_XM_ADDR_16")
	)
	(segment
		(start 114.397282 -94.991174)
		(end 88.657684 -94.991174)
		(width 0.127)
		(layer "In2.Cu")
		(net "EXP_XM_ADDR_16")
	)
	(segment
		(start 119.4689 -88.597486)
		(end 119.281448 -88.784938)
		(width 0.127)
		(layer "In2.Cu")
		(net "EXP_XM_ADDR_16")
	)
	(segment
		(start 73.771252 -95.926402)
		(end 74.284586 -95.926402)
		(width 0.127)
		(layer "In2.Cu")
		(net "EXP_XM_ADDR_16")
	)
	(segment
		(start 78.212188 -99.263708)
		(end 78.212188 -98.800666)
		(width 0.127)
		(layer "In2.Cu")
		(net "EXP_XM_ADDR_16")
	)
	(segment
		(start 117.861588 -92.25153)
		(end 117.136926 -92.25153)
		(width 0.127)
		(layer "In2.Cu")
		(net "EXP_XM_ADDR_16")
	)
	(segment
		(start 119.139462 -90.973656)
		(end 117.861588 -92.25153)
		(width 0.127)
		(layer "In2.Cu")
		(net "EXP_XM_ADDR_16")
	)
	(segment
		(start 76.639928 -99.390708)
		(end 78.085188 -99.390708)
		(width 0.127)
		(layer "In2.Cu")
		(net "EXP_XM_ADDR_16")
	)
	(segment
		(start 118.737126 -89.165938)
		(end 118.864126 -89.292938)
		(width 0.127)
		(layer "In2.Cu")
		(net "EXP_XM_ADDR_16")
	)
	(segment
		(start 73.644252 -95.799402)
		(end 73.771252 -95.926402)
		(width 0.127)
		(layer "In2.Cu")
		(net "EXP_XM_ADDR_16")
	)
	(segment
		(start 74.411586 -96.053402)
		(end 74.411586 -97.162366)
		(width 0.127)
		(layer "In2.Cu")
		(net "EXP_XM_ADDR_16")
	)
	(segment
		(start 73.771252 -94.316296)
		(end 73.644252 -94.443296)
		(width 0.127)
		(layer "In2.Cu")
		(net "EXP_XM_ADDR_16")
	)
	(segment
		(start 119.271288 -89.800938)
		(end 118.726458 -89.800938)
		(width 0.127)
		(layer "In2.Cu")
		(net "EXP_XM_ADDR_16")
	)
	(segment
		(start 88.657684 -94.991174)
		(end 88.259158 -95.3897)
		(width 0.127)
		(layer "In2.Cu")
		(net "EXP_XM_ADDR_16")
	)
	(segment
		(start 118.976648 -90.308938)
		(end 119.139462 -90.471752)
		(width 0.127)
		(layer "In2.Cu")
		(net "EXP_XM_ADDR_16")
	)
	(segment
		(start 74.42073 -95.291402)
		(end 74.29373 -95.418402)
		(width 0.127)
		(layer "In2.Cu")
		(net "EXP_XM_ADDR_16")
	)
	(segment
		(start 118.522242 -87.346536)
		(end 118.649242 -87.473536)
		(width 0.127)
		(layer "In2.Cu")
		(net "EXP_XM_ADDR_16")
	)
	(segment
		(start 118.599458 -89.927938)
		(end 118.599458 -90.181938)
		(width 0.127)
		(layer "In2.Cu")
		(net "EXP_XM_ADDR_16")
	)
	(segment
		(start 119.281448 -88.784938)
		(end 118.864126 -88.784938)
		(width 0.127)
		(layer "In2.Cu")
		(net "EXP_XM_ADDR_16")
	)
	(segment
		(start 73.644252 -94.443296)
		(end 73.644252 -94.783402)
		(width 0.127)
		(layer "In2.Cu")
		(net "EXP_XM_ADDR_16")
	)
	(segment
		(start 115.094766 -94.473522)
		(end 115.24869 -94.627446)
		(width 0.127)
		(layer "In2.Cu")
		(net "EXP_XM_ADDR_16")
	)
	(segment
		(start 114.555524 -94.832932)
		(end 114.397282 -94.991174)
		(width 0.127)
		(layer "In2.Cu")
		(net "EXP_XM_ADDR_16")
	)
	(segment
		(start 119.14759 -85.92439)
		(end 119.14759 -86.527132)
		(width 0.127)
		(layer "In2.Cu")
		(net "EXP_XM_ADDR_16")
	)
	(segment
		(start 114.735356 -94.832932)
		(end 114.555524 -94.832932)
		(width 0.127)
		(layer "In2.Cu")
		(net "EXP_XM_ADDR_16")
	)
	(segment
		(start 119.398288 -89.673938)
		(end 119.271288 -89.800938)
		(width 0.127)
		(layer "In2.Cu")
		(net "EXP_XM_ADDR_16")
	)
	(segment
		(start 78.085188 -99.390708)
		(end 78.212188 -99.263708)
		(width 0.127)
		(layer "In2.Cu")
		(net "EXP_XM_ADDR_16")
	)
	(segment
		(start 118.726458 -90.308938)
		(end 118.976648 -90.308938)
		(width 0.127)
		(layer "In2.Cu")
		(net "EXP_XM_ADDR_16")
	)
	(segment
		(start 118.737126 -88.911938)
		(end 118.737126 -89.165938)
		(width 0.127)
		(layer "In2.Cu")
		(net "EXP_XM_ADDR_16")
	)
	(segment
		(start 114.88928 -94.986856)
		(end 114.735356 -94.832932)
		(width 0.127)
		(layer "In2.Cu")
		(net "EXP_XM_ADDR_16")
	)
	(segment
		(start 78.085188 -98.673666)
		(end 76.950316 -98.673666)
		(width 0.127)
		(layer "In2.Cu")
		(net "EXP_XM_ADDR_16")
	)
	(segment
		(start 73.644252 -94.783402)
		(end 73.771252 -94.910402)
		(width 0.127)
		(layer "In2.Cu")
		(net "EXP_XM_ADDR_16")
	)
	(segment
		(start 119.14759 -86.527132)
		(end 119.02059 -86.654132)
		(width 0.127)
		(layer "In2.Cu")
		(net "EXP_XM_ADDR_16")
	)
	(segment
		(start 75.204066 -96.927416)
		(end 75.204066 -96.399096)
		(width 0.127)
		(layer "In2.Cu")
		(net "EXP_XM_ADDR_16")
	)
	(segment
		(start 118.864126 -88.784938)
		(end 118.737126 -88.911938)
		(width 0.127)
		(layer "In2.Cu")
		(net "EXP_XM_ADDR_16")
	)
	(segment
		(start 119.23268 -87.473536)
		(end 119.4689 -87.709756)
		(width 0.127)
		(layer "In2.Cu")
		(net "EXP_XM_ADDR_16")
	)
	(segment
		(start 82.058764 -94.316296)
		(end 73.771252 -94.316296)
		(width 0.127)
		(layer "In2.Cu")
		(net "EXP_XM_ADDR_16")
	)
	(segment
		(start 118.9482 -85.725)
		(end 119.14759 -85.92439)
		(width 0.127)
		(layer "In2.Cu")
		(net "EXP_XM_ADDR_16")
	)
	(segment
		(start 114.499898 -73.500234)
		(end 114.000026 -73.000362)
		(width 0.127)
		(layer "F.Cu")
		(net "EXP_XM_ADDR_15")
	)
	(via
		(at 114.000026 -73.000362)
		(size 0.4572)
		(drill 0.2032)
		(layers "F.Cu" "B.Cu")
		(net "EXP_XM_ADDR_15")
	)
	(via
		(at 114.8842 -85.725)
		(size 0.508)
		(drill 0.254)
		(layers "F.Cu" "B.Cu")
		(net "EXP_XM_ADDR_15")
	)
	(via
		(at 75.443334 -88.031066)
		(size 0.508)
		(drill 0.254)
		(layers "F.Cu" "B.Cu")
		(net "EXP_XM_ADDR_15")
	)
	(segment
		(start 114.8842 -85.5091)
		(end 114.8842 -85.725)
		(width 0.127)
		(layer "B.Cu")
		(net "EXP_XM_ADDR_15")
	)
	(segment
		(start 114.6302 -86.5759)
		(end 114.6302 -85.979)
		(width 0.127)
		(layer "B.Cu")
		(net "EXP_XM_ADDR_15")
	)
	(segment
		(start 115.513358 -79.389478)
		(end 114.9223 -79.980536)
		(width 0.127)
		(layer "B.Cu")
		(net "EXP_XM_ADDR_15")
	)
	(segment
		(start 114.9223 -81.5975)
		(end 115.316 -81.9912)
		(width 0.127)
		(layer "B.Cu")
		(net "EXP_XM_ADDR_15")
	)
	(segment
		(start 115.513358 -77.794358)
		(end 115.513358 -79.389478)
		(width 0.127)
		(layer "B.Cu")
		(net "EXP_XM_ADDR_15")
	)
	(segment
		(start 114.5032 -77.165454)
		(end 114.807746 -77.47)
		(width 0.127)
		(layer "B.Cu")
		(net "EXP_XM_ADDR_15")
	)
	(segment
		(start 73.8632 -92.7354)
		(end 73.8632 -89.6112)
		(width 0.127)
		(layer "B.Cu")
		(net "EXP_XM_ADDR_15")
	)
	(segment
		(start 115.7732 -84.1756)
		(end 115.7732 -84.7979)
		(width 0.127)
		(layer "B.Cu")
		(net "EXP_XM_ADDR_15")
	)
	(segment
		(start 115.0747 -85.3186)
		(end 114.8842 -85.5091)
		(width 0.127)
		(layer "B.Cu")
		(net "EXP_XM_ADDR_15")
	)
	(segment
		(start 73.8632 -89.6112)
		(end 75.443334 -88.031066)
		(width 0.127)
		(layer "B.Cu")
		(net "EXP_XM_ADDR_15")
	)
	(segment
		(start 114.6302 -85.979)
		(end 114.8842 -85.725)
		(width 0.127)
		(layer "B.Cu")
		(net "EXP_XM_ADDR_15")
	)
	(segment
		(start 75.26782 -94.14002)
		(end 73.8632 -92.7354)
		(width 0.127)
		(layer "B.Cu")
		(net "EXP_XM_ADDR_15")
	)
	(segment
		(start 114.000026 -73.000362)
		(end 114.5032 -73.503536)
		(width 0.127)
		(layer "B.Cu")
		(net "EXP_XM_ADDR_15")
	)
	(segment
		(start 115.7732 -84.7979)
		(end 115.2525 -85.3186)
		(width 0.127)
		(layer "B.Cu")
		(net "EXP_XM_ADDR_15")
	)
	(segment
		(start 114.807746 -77.47)
		(end 115.189 -77.47)
		(width 0.127)
		(layer "B.Cu")
		(net "EXP_XM_ADDR_15")
	)
	(segment
		(start 115.316 -83.7184)
		(end 115.7732 -84.1756)
		(width 0.127)
		(layer "B.Cu")
		(net "EXP_XM_ADDR_15")
	)
	(segment
		(start 75.26782 -94.8309)
		(end 75.26782 -94.14002)
		(width 0.127)
		(layer "B.Cu")
		(net "EXP_XM_ADDR_15")
	)
	(segment
		(start 115.316 -81.9912)
		(end 115.316 -83.7184)
		(width 0.127)
		(layer "B.Cu")
		(net "EXP_XM_ADDR_15")
	)
	(segment
		(start 115.2525 -85.3186)
		(end 115.0747 -85.3186)
		(width 0.127)
		(layer "B.Cu")
		(net "EXP_XM_ADDR_15")
	)
	(segment
		(start 114.9223 -79.980536)
		(end 114.9223 -81.5975)
		(width 0.127)
		(layer "B.Cu")
		(net "EXP_XM_ADDR_15")
	)
	(segment
		(start 115.189 -77.47)
		(end 115.513358 -77.794358)
		(width 0.127)
		(layer "B.Cu")
		(net "EXP_XM_ADDR_15")
	)
	(segment
		(start 114.5032 -73.503536)
		(end 114.5032 -77.165454)
		(width 0.127)
		(layer "B.Cu")
		(net "EXP_XM_ADDR_15")
	)
	(segment
		(start 83.174332 -90.350086)
		(end 81.815686 -90.350086)
		(width 0.127)
		(layer "In2.Cu")
		(net "EXP_XM_ADDR_15")
	)
	(segment
		(start 70.0278 -87.4522)
		(end 69.9008 -87.5792)
		(width 0.127)
		(layer "In2.Cu")
		(net "EXP_XM_ADDR_15")
	)
	(segment
		(start 80.391254 -89.484454)
		(end 78.9178 -88.011)
		(width 0.127)
		(layer "In2.Cu")
		(net "EXP_XM_ADDR_15")
	)
	(segment
		(start 81.7372 -90.3478)
		(end 80.873854 -89.484454)
		(width 0.127)
		(layer "In2.Cu")
		(net "EXP_XM_ADDR_15")
	)
	(segment
		(start 78.9178 -88.011)
		(end 76.8604 -88.011)
		(width 0.127)
		(layer "In2.Cu")
		(net "EXP_XM_ADDR_15")
	)
	(segment
		(start 81.8134 -90.3478)
		(end 81.7372 -90.3478)
		(width 0.127)
		(layer "In2.Cu")
		(net "EXP_XM_ADDR_15")
	)
	(segment
		(start 70.0278 -88.031066)
		(end 75.443334 -88.031066)
		(width 0.127)
		(layer "In2.Cu")
		(net "EXP_XM_ADDR_15")
	)
	(segment
		(start 76.8604 -88.011)
		(end 76.3016 -87.4522)
		(width 0.127)
		(layer "In2.Cu")
		(net "EXP_XM_ADDR_15")
	)
	(segment
		(start 69.9008 -87.5792)
		(end 69.9008 -87.904066)
		(width 0.127)
		(layer "In2.Cu")
		(net "EXP_XM_ADDR_15")
	)
	(segment
		(start 69.9008 -87.904066)
		(end 70.0278 -88.031066)
		(width 0.127)
		(layer "In2.Cu")
		(net "EXP_XM_ADDR_15")
	)
	(segment
		(start 114.9477 -85.7885)
		(end 114.9477 -89.340182)
		(width 0.127)
		(layer "In2.Cu")
		(net "EXP_XM_ADDR_15")
	)
	(segment
		(start 80.873854 -89.484454)
		(end 80.391254 -89.484454)
		(width 0.127)
		(layer "In2.Cu")
		(net "EXP_XM_ADDR_15")
	)
	(segment
		(start 112.852708 -91.435174)
		(end 84.25942 -91.435174)
		(width 0.127)
		(layer "In2.Cu")
		(net "EXP_XM_ADDR_15")
	)
	(segment
		(start 114.9477 -89.340182)
		(end 112.852708 -91.435174)
		(width 0.127)
		(layer "In2.Cu")
		(net "EXP_XM_ADDR_15")
	)
	(segment
		(start 81.815686 -90.350086)
		(end 81.8134 -90.3478)
		(width 0.127)
		(layer "In2.Cu")
		(net "EXP_XM_ADDR_15")
	)
	(segment
		(start 84.25942 -91.435174)
		(end 83.174332 -90.350086)
		(width 0.127)
		(layer "In2.Cu")
		(net "EXP_XM_ADDR_15")
	)
	(segment
		(start 114.8842 -85.725)
		(end 114.9477 -85.7885)
		(width 0.127)
		(layer "In2.Cu")
		(net "EXP_XM_ADDR_15")
	)
	(segment
		(start 76.3016 -87.4522)
		(end 70.0278 -87.4522)
		(width 0.127)
		(layer "In2.Cu")
		(net "EXP_XM_ADDR_15")
	)
	(segment
		(start 115.50015 -78.500224)
		(end 116.000022 -79.000096)
		(width 0.127)
		(layer "F.Cu")
		(net "EXP_XM_ADDR_14")
	)
	(via
		(at 76.204826 -96.399096)
		(size 0.508)
		(drill 0.254)
		(layers "F.Cu" "B.Cu")
		(net "EXP_XM_ADDR_14")
	)
	(via
		(at 116.000022 -79.000096)
		(size 0.4572)
		(drill 0.2032)
		(layers "F.Cu" "B.Cu")
		(net "EXP_XM_ADDR_14")
	)
	(segment
		(start 75.7682 -94.8309)
		(end 75.7682 -95.96247)
		(width 0.127)
		(layer "B.Cu")
		(net "EXP_XM_ADDR_14")
	)
	(segment
		(start 75.7682 -95.96247)
		(end 76.204826 -96.399096)
		(width 0.127)
		(layer "B.Cu")
		(net "EXP_XM_ADDR_14")
	)
	(segment
		(start 118.429024 -93.023436)
		(end 118.429024 -93.181424)
		(width 0.127)
		(layer "In2.Cu")
		(net "EXP_XM_ADDR_14")
	)
	(segment
		(start 116.789962 -94.820486)
		(end 116.631974 -94.820486)
		(width 0.127)
		(layer "In2.Cu")
		(net "EXP_XM_ADDR_14")
	)
	(segment
		(start 119.712232 -87.091012)
		(end 119.9769 -87.35568)
		(width 0.127)
		(layer "In2.Cu")
		(net "EXP_XM_ADDR_14")
	)
	(segment
		(start 80.985106 -95.459804)
		(end 80.859884 -95.334582)
		(width 0.127)
		(layer "In2.Cu")
		(net "EXP_XM_ADDR_14")
	)
	(segment
		(start 79.843884 -94.962472)
		(end 79.716884 -94.835472)
		(width 0.127)
		(layer "In2.Cu")
		(net "EXP_XM_ADDR_14")
	)
	(segment
		(start 80.351884 -95.334582)
		(end 80.224884 -95.461582)
		(width 0.127)
		(layer "In2.Cu")
		(net "EXP_XM_ADDR_14")
	)
	(segment
		(start 77.684884 -94.835472)
		(end 77.430884 -94.835472)
		(width 0.127)
		(layer "In2.Cu")
		(net "EXP_XM_ADDR_14")
	)
	(segment
		(start 116.454428 -93.92412)
		(end 116.991384 -94.461076)
		(width 0.127)
		(layer "In2.Cu")
		(net "EXP_XM_ADDR_14")
	)
	(segment
		(start 77.811884 -95.334582)
		(end 77.811884 -94.962472)
		(width 0.127)
		(layer "In2.Cu")
		(net "EXP_XM_ADDR_14")
	)
	(segment
		(start 117.508782 -94.101666)
		(end 117.350794 -94.101666)
		(width 0.127)
		(layer "In2.Cu")
		(net "EXP_XM_ADDR_14")
	)
	(segment
		(start 78.827884 -95.334582)
		(end 78.827884 -94.962472)
		(width 0.127)
		(layer "In2.Cu")
		(net "EXP_XM_ADDR_14")
	)
	(segment
		(start 78.319884 -94.962472)
		(end 78.319884 -95.334582)
		(width 0.127)
		(layer "In2.Cu")
		(net "EXP_XM_ADDR_14")
	)
	(segment
		(start 117.6782 -82.677)
		(end 117.965982 -82.964782)
		(width 0.127)
		(layer "In2.Cu")
		(net "EXP_XM_ADDR_14")
	)
	(segment
		(start 78.446884 -94.835472)
		(end 78.319884 -94.962472)
		(width 0.127)
		(layer "In2.Cu")
		(net "EXP_XM_ADDR_14")
	)
	(segment
		(start 117.517672 -92.830904)
		(end 117.33784 -92.830904)
		(width 0.127)
		(layer "In2.Cu")
		(net "EXP_XM_ADDR_14")
	)
	(segment
		(start 78.954884 -95.461582)
		(end 78.827884 -95.334582)
		(width 0.127)
		(layer "In2.Cu")
		(net "EXP_XM_ADDR_14")
	)
	(segment
		(start 116.184426 -95.158052)
		(end 116.184426 -95.31604)
		(width 0.127)
		(layer "In2.Cu")
		(net "EXP_XM_ADDR_14")
	)
	(segment
		(start 80.732884 -94.835472)
		(end 80.478884 -94.835472)
		(width 0.127)
		(layer "In2.Cu")
		(net "EXP_XM_ADDR_14")
	)
	(segment
		(start 79.335884 -95.334582)
		(end 79.208884 -95.461582)
		(width 0.127)
		(layer "In2.Cu")
		(net "EXP_XM_ADDR_14")
	)
	(segment
		(start 78.700884 -94.835472)
		(end 78.446884 -94.835472)
		(width 0.127)
		(layer "In2.Cu")
		(net "EXP_XM_ADDR_14")
	)
	(segment
		(start 76.795884 -94.962472)
		(end 76.668884 -94.835472)
		(width 0.127)
		(layer "In2.Cu")
		(net "EXP_XM_ADDR_14")
	)
	(segment
		(start 81.367884 -94.962472)
		(end 81.367884 -95.334582)
		(width 0.127)
		(layer "In2.Cu")
		(net "EXP_XM_ADDR_14")
	)
	(segment
		(start 116.991384 -94.461076)
		(end 116.991384 -94.619064)
		(width 0.127)
		(layer "In2.Cu")
		(net "EXP_XM_ADDR_14")
	)
	(segment
		(start 80.478884 -94.835472)
		(end 80.351884 -94.962472)
		(width 0.127)
		(layer "In2.Cu")
		(net "EXP_XM_ADDR_14")
	)
	(segment
		(start 118.590568 -92.46616)
		(end 118.410736 -92.46616)
		(width 0.127)
		(layer "In2.Cu")
		(net "EXP_XM_ADDR_14")
	)
	(segment
		(start 81.242662 -95.459804)
		(end 80.985106 -95.459804)
		(width 0.127)
		(layer "In2.Cu")
		(net "EXP_XM_ADDR_14")
	)
	(segment
		(start 79.462884 -94.835472)
		(end 79.335884 -94.962472)
		(width 0.127)
		(layer "In2.Cu")
		(net "EXP_XM_ADDR_14")
	)
	(segment
		(start 75.0062 -94.962472)
		(end 75.0062 -95.46971)
		(width 0.127)
		(layer "In2.Cu")
		(net "EXP_XM_ADDR_14")
	)
	(segment
		(start 117.710204 -93.742256)
		(end 117.710204 -93.900244)
		(width 0.127)
		(layer "In2.Cu")
		(net "EXP_XM_ADDR_14")
	)
	(segment
		(start 75.0062 -95.46971)
		(end 75.1332 -95.59671)
		(width 0.127)
		(layer "In2.Cu")
		(net "EXP_XM_ADDR_14")
	)
	(segment
		(start 79.970884 -95.461582)
		(end 79.843884 -95.334582)
		(width 0.127)
		(layer "In2.Cu")
		(net "EXP_XM_ADDR_14")
	)
	(segment
		(start 118.410736 -92.46616)
		(end 118.231158 -92.645738)
		(width 0.127)
		(layer "In2.Cu")
		(net "EXP_XM_ADDR_14")
	)
	(segment
		(start 117.350794 -94.101666)
		(end 116.813584 -93.564456)
		(width 0.127)
		(layer "In2.Cu")
		(net "EXP_XM_ADDR_14")
	)
	(segment
		(start 117.158262 -93.190314)
		(end 117.710204 -93.742256)
		(width 0.127)
		(layer "In2.Cu")
		(net "EXP_XM_ADDR_14")
	)
	(segment
		(start 76.922884 -95.560388)
		(end 76.795884 -95.433388)
		(width 0.127)
		(layer "In2.Cu")
		(net "EXP_XM_ADDR_14")
	)
	(segment
		(start 116.991384 -94.619064)
		(end 116.789962 -94.820486)
		(width 0.127)
		(layer "In2.Cu")
		(net "EXP_XM_ADDR_14")
	)
	(segment
		(start 118.429024 -93.181424)
		(end 118.227602 -93.382846)
		(width 0.127)
		(layer "In2.Cu")
		(net "EXP_XM_ADDR_14")
	)
	(segment
		(start 116.813584 -93.564456)
		(end 116.63426 -93.564456)
		(width 0.127)
		(layer "In2.Cu")
		(net "EXP_XM_ADDR_14")
	)
	(segment
		(start 117.710204 -93.900244)
		(end 117.508782 -94.101666)
		(width 0.127)
		(layer "In2.Cu")
		(net "EXP_XM_ADDR_14")
	)
	(segment
		(start 116.600224 -82.677)
		(end 117.6782 -82.677)
		(width 0.127)
		(layer "In2.Cu")
		(net "EXP_XM_ADDR_14")
	)
	(segment
		(start 76.668884 -94.835472)
		(end 75.1332 -94.835472)
		(width 0.127)
		(layer "In2.Cu")
		(net "EXP_XM_ADDR_14")
	)
	(segment
		(start 116.63426 -93.564456)
		(end 116.454428 -93.744796)
		(width 0.127)
		(layer "In2.Cu")
		(net "EXP_XM_ADDR_14")
	)
	(segment
		(start 81.848198 -94.824296)
		(end 81.50606 -94.824296)
		(width 0.127)
		(layer "In2.Cu")
		(net "EXP_XM_ADDR_14")
	)
	(segment
		(start 88.86825 -95.499174)
		(end 88.469724 -95.8977)
		(width 0.127)
		(layer "In2.Cu")
		(net "EXP_XM_ADDR_14")
	)
	(segment
		(start 88.469724 -95.8977)
		(end 82.921602 -95.8977)
		(width 0.127)
		(layer "In2.Cu")
		(net "EXP_XM_ADDR_14")
	)
	(segment
		(start 79.335884 -94.962472)
		(end 79.335884 -95.334582)
		(width 0.127)
		(layer "In2.Cu")
		(net "EXP_XM_ADDR_14")
	)
	(segment
		(start 79.716884 -94.835472)
		(end 79.462884 -94.835472)
		(width 0.127)
		(layer "In2.Cu")
		(net "EXP_XM_ADDR_14")
	)
	(segment
		(start 117.158262 -93.010482)
		(end 117.158262 -93.190314)
		(width 0.127)
		(layer "In2.Cu")
		(net "EXP_XM_ADDR_14")
	)
	(segment
		(start 82.921602 -95.8977)
		(end 81.848198 -94.824296)
		(width 0.127)
		(layer "In2.Cu")
		(net "EXP_XM_ADDR_14")
	)
	(segment
		(start 78.319884 -95.334582)
		(end 78.192884 -95.461582)
		(width 0.127)
		(layer "In2.Cu")
		(net "EXP_XM_ADDR_14")
	)
	(segment
		(start 76.204826 -95.72371)
		(end 76.204826 -96.399096)
		(width 0.127)
		(layer "In2.Cu")
		(net "EXP_XM_ADDR_14")
	)
	(segment
		(start 78.192884 -95.461582)
		(end 77.938884 -95.461582)
		(width 0.127)
		(layer "In2.Cu")
		(net "EXP_XM_ADDR_14")
	)
	(segment
		(start 119.712232 -85.770466)
		(end 119.712232 -87.091012)
		(width 0.127)
		(layer "In2.Cu")
		(net "EXP_XM_ADDR_14")
	)
	(segment
		(start 80.351884 -94.962472)
		(end 80.351884 -95.334582)
		(width 0.127)
		(layer "In2.Cu")
		(net "EXP_XM_ADDR_14")
	)
	(segment
		(start 116.631974 -94.820486)
		(end 116.117116 -94.305628)
		(width 0.127)
		(layer "In2.Cu")
		(net "EXP_XM_ADDR_14")
	)
	(segment
		(start 80.859884 -94.962472)
		(end 80.732884 -94.835472)
		(width 0.127)
		(layer "In2.Cu")
		(net "EXP_XM_ADDR_14")
	)
	(segment
		(start 81.50606 -94.824296)
		(end 81.367884 -94.962472)
		(width 0.127)
		(layer "In2.Cu")
		(net "EXP_XM_ADDR_14")
	)
	(segment
		(start 79.208884 -95.461582)
		(end 78.954884 -95.461582)
		(width 0.127)
		(layer "In2.Cu")
		(net "EXP_XM_ADDR_14")
	)
	(segment
		(start 116.473224 -82.55)
		(end 116.600224 -82.677)
		(width 0.127)
		(layer "In2.Cu")
		(net "EXP_XM_ADDR_14")
	)
	(segment
		(start 115.757706 -94.731332)
		(end 116.184426 -95.158052)
		(width 0.127)
		(layer "In2.Cu")
		(net "EXP_XM_ADDR_14")
	)
	(segment
		(start 77.176884 -95.560388)
		(end 76.922884 -95.560388)
		(width 0.127)
		(layer "In2.Cu")
		(net "EXP_XM_ADDR_14")
	)
	(segment
		(start 119.9769 -87.35568)
		(end 119.9769 -89.952576)
		(width 0.127)
		(layer "In2.Cu")
		(net "EXP_XM_ADDR_14")
	)
	(segment
		(start 77.811884 -94.962472)
		(end 77.684884 -94.835472)
		(width 0.127)
		(layer "In2.Cu")
		(net "EXP_XM_ADDR_14")
	)
	(segment
		(start 80.224884 -95.461582)
		(end 79.970884 -95.461582)
		(width 0.127)
		(layer "In2.Cu")
		(net "EXP_XM_ADDR_14")
	)
	(segment
		(start 117.965982 -82.964782)
		(end 117.965982 -84.024216)
		(width 0.127)
		(layer "In2.Cu")
		(net "EXP_XM_ADDR_14")
	)
	(segment
		(start 77.303884 -95.433388)
		(end 77.176884 -95.560388)
		(width 0.127)
		(layer "In2.Cu")
		(net "EXP_XM_ADDR_14")
	)
	(segment
		(start 118.227602 -93.382846)
		(end 118.069614 -93.382846)
		(width 0.127)
		(layer "In2.Cu")
		(net "EXP_XM_ADDR_14")
	)
	(segment
		(start 81.367884 -95.334582)
		(end 81.242662 -95.459804)
		(width 0.127)
		(layer "In2.Cu")
		(net "EXP_XM_ADDR_14")
	)
	(segment
		(start 118.231158 -92.82557)
		(end 118.429024 -93.023436)
		(width 0.127)
		(layer "In2.Cu")
		(net "EXP_XM_ADDR_14")
	)
	(segment
		(start 78.827884 -94.962472)
		(end 78.700884 -94.835472)
		(width 0.127)
		(layer "In2.Cu")
		(net "EXP_XM_ADDR_14")
	)
	(segment
		(start 75.1332 -95.59671)
		(end 76.077826 -95.59671)
		(width 0.127)
		(layer "In2.Cu")
		(net "EXP_XM_ADDR_14")
	)
	(segment
		(start 118.231158 -92.645738)
		(end 118.231158 -92.82557)
		(width 0.127)
		(layer "In2.Cu")
		(net "EXP_XM_ADDR_14")
	)
	(segment
		(start 116.001292 -95.499174)
		(end 88.86825 -95.499174)
		(width 0.127)
		(layer "In2.Cu")
		(net "EXP_XM_ADDR_14")
	)
	(segment
		(start 115.837716 -80.459834)
		(end 116.346224 -80.459834)
		(width 0.127)
		(layer "In2.Cu")
		(net "EXP_XM_ADDR_14")
	)
	(segment
		(start 115.5446 -79.455518)
		(end 115.5446 -80.166718)
		(width 0.127)
		(layer "In2.Cu")
		(net "EXP_XM_ADDR_14")
	)
	(segment
		(start 76.795884 -95.433388)
		(end 76.795884 -94.962472)
		(width 0.127)
		(layer "In2.Cu")
		(net "EXP_XM_ADDR_14")
	)
	(segment
		(start 79.843884 -95.334582)
		(end 79.843884 -94.962472)
		(width 0.127)
		(layer "In2.Cu")
		(net "EXP_XM_ADDR_14")
	)
	(segment
		(start 119.668036 -91.942412)
		(end 118.946422 -92.664026)
		(width 0.127)
		(layer "In2.Cu")
		(net "EXP_XM_ADDR_14")
	)
	(segment
		(start 116.000022 -79.000096)
		(end 115.5446 -79.455518)
		(width 0.127)
		(layer "In2.Cu")
		(net "EXP_XM_ADDR_14")
	)
	(segment
		(start 117.33784 -92.830904)
		(end 117.158262 -93.010482)
		(width 0.127)
		(layer "In2.Cu")
		(net "EXP_XM_ADDR_14")
	)
	(segment
		(start 119.668036 -90.262456)
		(end 119.668036 -91.942412)
		(width 0.127)
		(layer "In2.Cu")
		(net "EXP_XM_ADDR_14")
	)
	(segment
		(start 118.946422 -92.664026)
		(end 118.788434 -92.664026)
		(width 0.127)
		(layer "In2.Cu")
		(net "EXP_XM_ADDR_14")
	)
	(segment
		(start 116.346224 -80.459834)
		(end 116.473224 -80.586834)
		(width 0.127)
		(layer "In2.Cu")
		(net "EXP_XM_ADDR_14")
	)
	(segment
		(start 115.757706 -94.485206)
		(end 115.757706 -94.731332)
		(width 0.127)
		(layer "In2.Cu")
		(net "EXP_XM_ADDR_14")
	)
	(segment
		(start 116.184426 -95.31604)
		(end 116.001292 -95.499174)
		(width 0.127)
		(layer "In2.Cu")
		(net "EXP_XM_ADDR_14")
	)
	(segment
		(start 117.965982 -84.024216)
		(end 119.712232 -85.770466)
		(width 0.127)
		(layer "In2.Cu")
		(net "EXP_XM_ADDR_14")
	)
	(segment
		(start 116.454428 -93.744796)
		(end 116.454428 -93.92412)
		(width 0.127)
		(layer "In2.Cu")
		(net "EXP_XM_ADDR_14")
	)
	(segment
		(start 77.303884 -94.962472)
		(end 77.303884 -95.433388)
		(width 0.127)
		(layer "In2.Cu")
		(net "EXP_XM_ADDR_14")
	)
	(segment
		(start 77.430884 -94.835472)
		(end 77.303884 -94.962472)
		(width 0.127)
		(layer "In2.Cu")
		(net "EXP_XM_ADDR_14")
	)
	(segment
		(start 115.5446 -80.166718)
		(end 115.837716 -80.459834)
		(width 0.127)
		(layer "In2.Cu")
		(net "EXP_XM_ADDR_14")
	)
	(segment
		(start 116.117116 -94.305628)
		(end 115.937284 -94.305628)
		(width 0.127)
		(layer "In2.Cu")
		(net "EXP_XM_ADDR_14")
	)
	(segment
		(start 80.859884 -95.334582)
		(end 80.859884 -94.962472)
		(width 0.127)
		(layer "In2.Cu")
		(net "EXP_XM_ADDR_14")
	)
	(segment
		(start 119.9769 -89.952576)
		(end 119.668036 -90.262456)
		(width 0.127)
		(layer "In2.Cu")
		(net "EXP_XM_ADDR_14")
	)
	(segment
		(start 76.077826 -95.59671)
		(end 76.204826 -95.72371)
		(width 0.127)
		(layer "In2.Cu")
		(net "EXP_XM_ADDR_14")
	)
	(segment
		(start 118.069614 -93.382846)
		(end 117.517672 -92.830904)
		(width 0.127)
		(layer "In2.Cu")
		(net "EXP_XM_ADDR_14")
	)
	(segment
		(start 115.937284 -94.305628)
		(end 115.757706 -94.485206)
		(width 0.127)
		(layer "In2.Cu")
		(net "EXP_XM_ADDR_14")
	)
	(segment
		(start 118.788434 -92.664026)
		(end 118.590568 -92.46616)
		(width 0.127)
		(layer "In2.Cu")
		(net "EXP_XM_ADDR_14")
	)
	(segment
		(start 77.938884 -95.461582)
		(end 77.811884 -95.334582)
		(width 0.127)
		(layer "In2.Cu")
		(net "EXP_XM_ADDR_14")
	)
	(segment
		(start 75.1332 -94.835472)
		(end 75.0062 -94.962472)
		(width 0.127)
		(layer "In2.Cu")
		(net "EXP_XM_ADDR_14")
	)
	(segment
		(start 116.473224 -80.586834)
		(end 116.473224 -82.55)
		(width 0.127)
		(layer "In2.Cu")
		(net "EXP_XM_ADDR_14")
	)
	(segment
		(start 117.500146 -82.500216)
		(end 117.500146 -83.109816)
		(width 0.127)
		(layer "F.Cu")
		(net "EXP_XM_ADDR_13")
	)
	(via
		(at 117.500146 -83.109816)
		(size 0.4572)
		(drill 0.2032)
		(layers "F.Cu" "B.Cu")
		(net "EXP_XM_ADDR_13")
	)
	(via
		(at 74.3712 -92.4052)
		(size 0.508)
		(drill 0.254)
		(layers "F.Cu" "B.Cu")
		(net "EXP_XM_ADDR_13")
	)
	(segment
		(start 74.693526 -92.4052)
		(end 76.26858 -93.980254)
		(width 0.127)
		(layer "B.Cu")
		(net "EXP_XM_ADDR_13")
	)
	(segment
		(start 74.3712 -92.4052)
		(end 74.693526 -92.4052)
		(width 0.127)
		(layer "B.Cu")
		(net "EXP_XM_ADDR_13")
	)
	(segment
		(start 76.26858 -93.980254)
		(end 76.26858 -94.8309)
		(width 0.127)
		(layer "B.Cu")
		(net "EXP_XM_ADDR_13")
	)
	(segment
		(start 117.9957 -87.573104)
		(end 117.9957 -86.543388)
		(width 0.127)
		(layer "In2.Cu")
		(net "EXP_XM_ADDR_13")
	)
	(segment
		(start 69.6214 -93.004386)
		(end 69.4944 -93.131386)
		(width 0.127)
		(layer "In2.Cu")
		(net "EXP_XM_ADDR_13")
	)
	(segment
		(start 117.9957 -86.543388)
		(end 118.4529 -86.086188)
		(width 0.127)
		(layer "In2.Cu")
		(net "EXP_XM_ADDR_13")
	)
	(segment
		(start 116.92636 -91.74353)
		(end 117.559328 -91.74353)
		(width 0.127)
		(layer "In2.Cu")
		(net "EXP_XM_ADDR_13")
	)
	(segment
		(start 118.104666 -84.889086)
		(end 117.598698 -85.395054)
		(width 0.127)
		(layer "In2.Cu")
		(net "EXP_XM_ADDR_13")
	)
	(segment
		(start 71.599806 -93.935296)
		(end 71.599806 -95.4532)
		(width 0.127)
		(layer "In2.Cu")
		(net "EXP_XM_ADDR_13")
	)
	(segment
		(start 118.002304 -88.887554)
		(end 118.4529 -88.436958)
		(width 0.127)
		(layer "In2.Cu")
		(net "EXP_XM_ADDR_13")
	)
	(segment
		(start 118.4529 -88.030304)
		(end 117.9957 -87.573104)
		(width 0.127)
		(layer "In2.Cu")
		(net "EXP_XM_ADDR_13")
	)
	(segment
		(start 117.745256 -84.529676)
		(end 117.745256 -84.349844)
		(width 0.127)
		(layer "In2.Cu")
		(net "EXP_XM_ADDR_13")
	)
	(segment
		(start 117.559328 -91.74353)
		(end 118.002304 -91.300554)
		(width 0.127)
		(layer "In2.Cu")
		(net "EXP_XM_ADDR_13")
	)
	(segment
		(start 71.091806 -93.935296)
		(end 71.218806 -93.808296)
		(width 0.127)
		(layer "In2.Cu")
		(net "EXP_XM_ADDR_13")
	)
	(segment
		(start 72.107806 -93.935296)
		(end 72.234806 -93.808296)
		(width 0.127)
		(layer "In2.Cu")
		(net "EXP_XM_ADDR_13")
	)
	(segment
		(start 71.726806 -95.5802)
		(end 71.980806 -95.5802)
		(width 0.127)
		(layer "In2.Cu")
		(net "EXP_XM_ADDR_13")
	)
	(segment
		(start 118.4529 -85.057488)
		(end 118.284498 -84.889086)
		(width 0.127)
		(layer "In2.Cu")
		(net "EXP_XM_ADDR_13")
	)
	(segment
		(start 118.4529 -86.086188)
		(end 118.4529 -85.057488)
		(width 0.127)
		(layer "In2.Cu")
		(net "EXP_XM_ADDR_13")
	)
	(segment
		(start 69.6214 -93.808296)
		(end 70.456806 -93.808296)
		(width 0.127)
		(layer "In2.Cu")
		(net "EXP_XM_ADDR_13")
	)
	(segment
		(start 70.456806 -93.808296)
		(end 70.583806 -93.935296)
		(width 0.127)
		(layer "In2.Cu")
		(net "EXP_XM_ADDR_13")
	)
	(segment
		(start 72.234806 -93.808296)
		(end 72.488806 -93.808296)
		(width 0.127)
		(layer "In2.Cu")
		(net "EXP_XM_ADDR_13")
	)
	(segment
		(start 83.342734 -94.8817)
		(end 88.048592 -94.8817)
		(width 0.127)
		(layer "In2.Cu")
		(net "EXP_XM_ADDR_13")
	)
	(segment
		(start 70.583806 -94.8436)
		(end 70.710806 -94.9706)
		(width 0.127)
		(layer "In2.Cu")
		(net "EXP_XM_ADDR_13")
	)
	(segment
		(start 117.745256 -84.349844)
		(end 117.500146 -84.104734)
		(width 0.127)
		(layer "In2.Cu")
		(net "EXP_XM_ADDR_13")
	)
	(segment
		(start 70.710806 -94.9706)
		(end 70.964806 -94.9706)
		(width 0.127)
		(layer "In2.Cu")
		(net "EXP_XM_ADDR_13")
	)
	(segment
		(start 71.599806 -95.4532)
		(end 71.726806 -95.5802)
		(width 0.127)
		(layer "In2.Cu")
		(net "EXP_XM_ADDR_13")
	)
	(segment
		(start 73.123806 -95.4278)
		(end 73.123806 -93.935296)
		(width 0.127)
		(layer "In2.Cu")
		(net "EXP_XM_ADDR_13")
	)
	(segment
		(start 82.26933 -93.808296)
		(end 83.342734 -94.8817)
		(width 0.127)
		(layer "In2.Cu")
		(net "EXP_XM_ADDR_13")
	)
	(segment
		(start 118.4529 -88.436958)
		(end 118.4529 -88.030304)
		(width 0.127)
		(layer "In2.Cu")
		(net "EXP_XM_ADDR_13")
	)
	(segment
		(start 73.250806 -93.808296)
		(end 82.26933 -93.808296)
		(width 0.127)
		(layer "In2.Cu")
		(net "EXP_XM_ADDR_13")
	)
	(segment
		(start 72.996806 -95.5548)
		(end 73.123806 -95.4278)
		(width 0.127)
		(layer "In2.Cu")
		(net "EXP_XM_ADDR_13")
	)
	(segment
		(start 117.500146 -84.104734)
		(end 117.500146 -83.109816)
		(width 0.127)
		(layer "In2.Cu")
		(net "EXP_XM_ADDR_13")
	)
	(segment
		(start 71.091806 -94.8436)
		(end 71.091806 -93.935296)
		(width 0.127)
		(layer "In2.Cu")
		(net "EXP_XM_ADDR_13")
	)
	(segment
		(start 73.123806 -93.935296)
		(end 73.250806 -93.808296)
		(width 0.127)
		(layer "In2.Cu")
		(net "EXP_XM_ADDR_13")
	)
	(segment
		(start 117.239288 -85.035644)
		(end 117.745256 -84.529676)
		(width 0.127)
		(layer "In2.Cu")
		(net "EXP_XM_ADDR_13")
	)
	(segment
		(start 72.488806 -93.808296)
		(end 72.615806 -93.935296)
		(width 0.127)
		(layer "In2.Cu")
		(net "EXP_XM_ADDR_13")
	)
	(segment
		(start 69.4944 -93.681296)
		(end 69.6214 -93.808296)
		(width 0.127)
		(layer "In2.Cu")
		(net "EXP_XM_ADDR_13")
	)
	(segment
		(start 72.107806 -95.4532)
		(end 72.107806 -93.935296)
		(width 0.127)
		(layer "In2.Cu")
		(net "EXP_XM_ADDR_13")
	)
	(segment
		(start 117.418866 -85.395054)
		(end 117.239288 -85.215476)
		(width 0.127)
		(layer "In2.Cu")
		(net "EXP_XM_ADDR_13")
	)
	(segment
		(start 88.048592 -94.8817)
		(end 88.447118 -94.483174)
		(width 0.127)
		(layer "In2.Cu")
		(net "EXP_XM_ADDR_13")
	)
	(segment
		(start 118.002304 -91.300554)
		(end 118.002304 -88.887554)
		(width 0.127)
		(layer "In2.Cu")
		(net "EXP_XM_ADDR_13")
	)
	(segment
		(start 72.742806 -95.5548)
		(end 72.996806 -95.5548)
		(width 0.127)
		(layer "In2.Cu")
		(net "EXP_XM_ADDR_13")
	)
	(segment
		(start 117.598698 -85.395054)
		(end 117.418866 -85.395054)
		(width 0.127)
		(layer "In2.Cu")
		(net "EXP_XM_ADDR_13")
	)
	(segment
		(start 71.472806 -93.808296)
		(end 71.599806 -93.935296)
		(width 0.127)
		(layer "In2.Cu")
		(net "EXP_XM_ADDR_13")
	)
	(segment
		(start 71.218806 -93.808296)
		(end 71.472806 -93.808296)
		(width 0.127)
		(layer "In2.Cu")
		(net "EXP_XM_ADDR_13")
	)
	(segment
		(start 72.615806 -93.935296)
		(end 72.615806 -95.4278)
		(width 0.127)
		(layer "In2.Cu")
		(net "EXP_XM_ADDR_13")
	)
	(segment
		(start 73.772014 -93.004386)
		(end 69.6214 -93.004386)
		(width 0.127)
		(layer "In2.Cu")
		(net "EXP_XM_ADDR_13")
	)
	(segment
		(start 118.284498 -84.889086)
		(end 118.104666 -84.889086)
		(width 0.127)
		(layer "In2.Cu")
		(net "EXP_XM_ADDR_13")
	)
	(segment
		(start 69.4944 -93.131386)
		(end 69.4944 -93.681296)
		(width 0.127)
		(layer "In2.Cu")
		(net "EXP_XM_ADDR_13")
	)
	(segment
		(start 70.964806 -94.9706)
		(end 71.091806 -94.8436)
		(width 0.127)
		(layer "In2.Cu")
		(net "EXP_XM_ADDR_13")
	)
	(segment
		(start 74.3712 -92.4052)
		(end 73.772014 -93.004386)
		(width 0.127)
		(layer "In2.Cu")
		(net "EXP_XM_ADDR_13")
	)
	(segment
		(start 88.447118 -94.483174)
		(end 114.186716 -94.483174)
		(width 0.127)
		(layer "In2.Cu")
		(net "EXP_XM_ADDR_13")
	)
	(segment
		(start 72.615806 -95.4278)
		(end 72.742806 -95.5548)
		(width 0.127)
		(layer "In2.Cu")
		(net "EXP_XM_ADDR_13")
	)
	(segment
		(start 114.186716 -94.483174)
		(end 116.92636 -91.74353)
		(width 0.127)
		(layer "In2.Cu")
		(net "EXP_XM_ADDR_13")
	)
	(segment
		(start 71.980806 -95.5802)
		(end 72.107806 -95.4532)
		(width 0.127)
		(layer "In2.Cu")
		(net "EXP_XM_ADDR_13")
	)
	(segment
		(start 117.239288 -85.215476)
		(end 117.239288 -85.035644)
		(width 0.127)
		(layer "In2.Cu")
		(net "EXP_XM_ADDR_13")
	)
	(segment
		(start 70.583806 -93.935296)
		(end 70.583806 -94.8436)
		(width 0.127)
		(layer "In2.Cu")
		(net "EXP_XM_ADDR_13")
	)
	(segment
		(start 116.500148 -78.500224)
		(end 117.00002 -79.000096)
		(width 0.127)
		(layer "F.Cu")
		(net "EXP_XM_ADDR_12")
	)
	(via
		(at 77.317092 -98.165666)
		(size 0.508)
		(drill 0.254)
		(layers "F.Cu" "B.Cu")
		(net "EXP_XM_ADDR_12")
	)
	(via
		(at 117.00002 -79.000096)
		(size 0.4572)
		(drill 0.2032)
		(layers "F.Cu" "B.Cu")
		(net "EXP_XM_ADDR_12")
	)
	(segment
		(start 74.661268 -97.784666)
		(end 74.788268 -97.657666)
		(width 0.127)
		(layer "B.Cu")
		(net "EXP_XM_ADDR_12")
	)
	(segment
		(start 76.76007 -95.78213)
		(end 76.76769 -95.77451)
		(width 0.127)
		(layer "B.Cu")
		(net "EXP_XM_ADDR_12")
	)
	(segment
		(start 74.788268 -98.165666)
		(end 74.661268 -98.038666)
		(width 0.127)
		(layer "B.Cu")
		(net "EXP_XM_ADDR_12")
	)
	(segment
		(start 76.76007 -97.530666)
		(end 76.76007 -95.78213)
		(width 0.127)
		(layer "B.Cu")
		(net "EXP_XM_ADDR_12")
	)
	(segment
		(start 74.661268 -98.038666)
		(end 74.661268 -97.784666)
		(width 0.127)
		(layer "B.Cu")
		(net "EXP_XM_ADDR_12")
	)
	(segment
		(start 76.76769 -95.77451)
		(end 76.76769 -94.8309)
		(width 0.127)
		(layer "B.Cu")
		(net "EXP_XM_ADDR_12")
	)
	(segment
		(start 77.317092 -98.165666)
		(end 74.788268 -98.165666)
		(width 0.127)
		(layer "B.Cu")
		(net "EXP_XM_ADDR_12")
	)
	(segment
		(start 74.788268 -97.657666)
		(end 76.63307 -97.657666)
		(width 0.127)
		(layer "B.Cu")
		(net "EXP_XM_ADDR_12")
	)
	(segment
		(start 76.63307 -97.657666)
		(end 76.76007 -97.530666)
		(width 0.127)
		(layer "B.Cu")
		(net "EXP_XM_ADDR_12")
	)
	(segment
		(start 120.703848 -90.941906)
		(end 120.9929 -90.652346)
		(width 0.127)
		(layer "In2.Cu")
		(net "EXP_XM_ADDR_12")
	)
	(segment
		(start 122.191018 -87.152226)
		(end 122.191018 -86.898226)
		(width 0.127)
		(layer "In2.Cu")
		(net "EXP_XM_ADDR_12")
	)
	(segment
		(start 121.006362 -87.660226)
		(end 121.006362 -87.406226)
		(width 0.127)
		(layer "In2.Cu")
		(net "EXP_XM_ADDR_12")
	)
	(segment
		(start 122.064018 -86.771226)
		(end 120.883172 -86.771226)
		(width 0.127)
		(layer "In2.Cu")
		(net "EXP_XM_ADDR_12")
	)
	(segment
		(start 117.58676 -96.515174)
		(end 119.3927 -94.709234)
		(width 0.127)
		(layer "In2.Cu")
		(net "EXP_XM_ADDR_12")
	)
	(segment
		(start 78.039976 -97.442782)
		(end 83.212432 -97.442782)
		(width 0.127)
		(layer "In2.Cu")
		(net "EXP_XM_ADDR_12")
	)
	(segment
		(start 120.9929 -90.652346)
		(end 121.045224 -90.600022)
		(width 0.127)
		(layer "In2.Cu")
		(net "EXP_XM_ADDR_12")
	)
	(segment
		(start 118.6434 -82.00009)
		(end 119.38127 -82.00009)
		(width 0.127)
		(layer "In2.Cu")
		(net "EXP_XM_ADDR_12")
	)
	(segment
		(start 121.122694 -88.829388)
		(end 121.654316 -88.829388)
		(width 0.127)
		(layer "In2.Cu")
		(net "EXP_XM_ADDR_12")
	)
	(segment
		(start 120.703848 -92.369386)
		(end 120.703848 -90.941906)
		(width 0.127)
		(layer "In2.Cu")
		(net "EXP_XM_ADDR_12")
	)
	(segment
		(start 121.794016 -86.263226)
		(end 121.921016 -86.136226)
		(width 0.127)
		(layer "In2.Cu")
		(net "EXP_XM_ADDR_12")
	)
	(segment
		(start 121.781316 -88.702388)
		(end 121.781316 -87.914226)
		(width 0.127)
		(layer "In2.Cu")
		(net "EXP_XM_ADDR_12")
	)
	(segment
		(start 119.3927 -93.680534)
		(end 120.703848 -92.369386)
		(width 0.127)
		(layer "In2.Cu")
		(net "EXP_XM_ADDR_12")
	)
	(segment
		(start 121.794016 -85.755226)
		(end 121.010426 -85.755226)
		(width 0.127)
		(layer "In2.Cu")
		(net "EXP_XM_ADDR_12")
	)
	(segment
		(start 120.445784 -84.097622)
		(end 120.445784 -82.78749)
		(width 0.127)
		(layer "In2.Cu")
		(net "EXP_XM_ADDR_12")
	)
	(segment
		(start 121.654316 -87.787226)
		(end 121.133362 -87.787226)
		(width 0.127)
		(layer "In2.Cu")
		(net "EXP_XM_ADDR_12")
	)
	(segment
		(start 120.883172 -86.263226)
		(end 121.794016 -86.263226)
		(width 0.127)
		(layer "In2.Cu")
		(net "EXP_XM_ADDR_12")
	)
	(segment
		(start 119.745252 -84.351622)
		(end 119.872252 -84.224622)
		(width 0.127)
		(layer "In2.Cu")
		(net "EXP_XM_ADDR_12")
	)
	(segment
		(start 121.742708 -89.464388)
		(end 121.615708 -89.337388)
		(width 0.127)
		(layer "In2.Cu")
		(net "EXP_XM_ADDR_12")
	)
	(segment
		(start 121.654316 -88.829388)
		(end 121.781316 -88.702388)
		(width 0.127)
		(layer "In2.Cu")
		(net "EXP_XM_ADDR_12")
	)
	(segment
		(start 120.995694 -88.956388)
		(end 121.122694 -88.829388)
		(width 0.127)
		(layer "In2.Cu")
		(net "EXP_XM_ADDR_12")
	)
	(segment
		(start 121.122694 -89.337388)
		(end 120.995694 -89.210388)
		(width 0.127)
		(layer "In2.Cu")
		(net "EXP_XM_ADDR_12")
	)
	(segment
		(start 83.212432 -97.442782)
		(end 83.741514 -96.9137)
		(width 0.127)
		(layer "In2.Cu")
		(net "EXP_XM_ADDR_12")
	)
	(segment
		(start 121.045224 -90.600022)
		(end 121.045224 -89.972388)
		(width 0.127)
		(layer "In2.Cu")
		(net "EXP_XM_ADDR_12")
	)
	(segment
		(start 120.445784 -84.859622)
		(end 120.318784 -84.732622)
		(width 0.127)
		(layer "In2.Cu")
		(net "EXP_XM_ADDR_12")
	)
	(segment
		(start 121.615708 -89.845388)
		(end 121.742708 -89.718388)
		(width 0.127)
		(layer "In2.Cu")
		(net "EXP_XM_ADDR_12")
	)
	(segment
		(start 119.745252 -84.605622)
		(end 119.745252 -84.351622)
		(width 0.127)
		(layer "In2.Cu")
		(net "EXP_XM_ADDR_12")
	)
	(segment
		(start 121.742708 -89.718388)
		(end 121.742708 -89.464388)
		(width 0.127)
		(layer "In2.Cu")
		(net "EXP_XM_ADDR_12")
	)
	(segment
		(start 120.166384 -82.50809)
		(end 118.6434 -82.50809)
		(width 0.127)
		(layer "In2.Cu")
		(net "EXP_XM_ADDR_12")
	)
	(segment
		(start 121.921016 -85.882226)
		(end 121.794016 -85.755226)
		(width 0.127)
		(layer "In2.Cu")
		(net "EXP_XM_ADDR_12")
	)
	(segment
		(start 119.872252 -84.224622)
		(end 120.318784 -84.224622)
		(width 0.127)
		(layer "In2.Cu")
		(net "EXP_XM_ADDR_12")
	)
	(segment
		(start 119.50827 -81.61909)
		(end 119.38127 -81.49209)
		(width 0.127)
		(layer "In2.Cu")
		(net "EXP_XM_ADDR_12")
	)
	(segment
		(start 121.006362 -87.406226)
		(end 121.133362 -87.279226)
		(width 0.127)
		(layer "In2.Cu")
		(net "EXP_XM_ADDR_12")
	)
	(segment
		(start 89.289382 -96.515174)
		(end 117.58676 -96.515174)
		(width 0.127)
		(layer "In2.Cu")
		(net "EXP_XM_ADDR_12")
	)
	(segment
		(start 121.133362 -87.279226)
		(end 122.064018 -87.279226)
		(width 0.127)
		(layer "In2.Cu")
		(net "EXP_XM_ADDR_12")
	)
	(segment
		(start 120.756172 -86.644226)
		(end 120.756172 -86.390226)
		(width 0.127)
		(layer "In2.Cu")
		(net "EXP_XM_ADDR_12")
	)
	(segment
		(start 120.445784 -85.190584)
		(end 120.445784 -84.859622)
		(width 0.127)
		(layer "In2.Cu")
		(net "EXP_XM_ADDR_12")
	)
	(segment
		(start 120.318784 -84.224622)
		(end 120.445784 -84.097622)
		(width 0.127)
		(layer "In2.Cu")
		(net "EXP_XM_ADDR_12")
	)
	(segment
		(start 119.872252 -84.732622)
		(end 119.745252 -84.605622)
		(width 0.127)
		(layer "In2.Cu")
		(net "EXP_XM_ADDR_12")
	)
	(segment
		(start 118.6434 -81.49209)
		(end 118.5164 -81.36509)
		(width 0.127)
		(layer "In2.Cu")
		(net "EXP_XM_ADDR_12")
	)
	(segment
		(start 117.00002 -79.225394)
		(end 117.00002 -79.000096)
		(width 0.127)
		(layer "In2.Cu")
		(net "EXP_XM_ADDR_12")
	)
	(segment
		(start 118.6434 -82.50809)
		(end 118.5164 -82.38109)
		(width 0.127)
		(layer "In2.Cu")
		(net "EXP_XM_ADDR_12")
	)
	(segment
		(start 121.045224 -89.972388)
		(end 121.172224 -89.845388)
		(width 0.127)
		(layer "In2.Cu")
		(net "EXP_XM_ADDR_12")
	)
	(segment
		(start 118.5164 -81.36509)
		(end 118.5164 -80.741774)
		(width 0.127)
		(layer "In2.Cu")
		(net "EXP_XM_ADDR_12")
	)
	(segment
		(start 119.3927 -94.709234)
		(end 119.3927 -93.680534)
		(width 0.127)
		(layer "In2.Cu")
		(net "EXP_XM_ADDR_12")
	)
	(segment
		(start 120.883172 -86.771226)
		(end 120.756172 -86.644226)
		(width 0.127)
		(layer "In2.Cu")
		(net "EXP_XM_ADDR_12")
	)
	(segment
		(start 88.890856 -96.9137)
		(end 89.289382 -96.515174)
		(width 0.127)
		(layer "In2.Cu")
		(net "EXP_XM_ADDR_12")
	)
	(segment
		(start 121.010426 -85.755226)
		(end 120.445784 -85.190584)
		(width 0.127)
		(layer "In2.Cu")
		(net "EXP_XM_ADDR_12")
	)
	(segment
		(start 120.318784 -84.732622)
		(end 119.872252 -84.732622)
		(width 0.127)
		(layer "In2.Cu")
		(net "EXP_XM_ADDR_12")
	)
	(segment
		(start 77.317092 -98.165666)
		(end 78.039976 -97.442782)
		(width 0.127)
		(layer "In2.Cu")
		(net "EXP_XM_ADDR_12")
	)
	(segment
		(start 119.38127 -82.00009)
		(end 119.50827 -81.87309)
		(width 0.127)
		(layer "In2.Cu")
		(net "EXP_XM_ADDR_12")
	)
	(segment
		(start 121.615708 -89.337388)
		(end 121.122694 -89.337388)
		(width 0.127)
		(layer "In2.Cu")
		(net "EXP_XM_ADDR_12")
	)
	(segment
		(start 119.38127 -81.49209)
		(end 118.6434 -81.49209)
		(width 0.127)
		(layer "In2.Cu")
		(net "EXP_XM_ADDR_12")
	)
	(segment
		(start 118.5164 -82.12709)
		(end 118.6434 -82.00009)
		(width 0.127)
		(layer "In2.Cu")
		(net "EXP_XM_ADDR_12")
	)
	(segment
		(start 83.741514 -96.9137)
		(end 88.890856 -96.9137)
		(width 0.127)
		(layer "In2.Cu")
		(net "EXP_XM_ADDR_12")
	)
	(segment
		(start 121.133362 -87.787226)
		(end 121.006362 -87.660226)
		(width 0.127)
		(layer "In2.Cu")
		(net "EXP_XM_ADDR_12")
	)
	(segment
		(start 122.064018 -87.279226)
		(end 122.191018 -87.152226)
		(width 0.127)
		(layer "In2.Cu")
		(net "EXP_XM_ADDR_12")
	)
	(segment
		(start 118.5164 -80.741774)
		(end 117.00002 -79.225394)
		(width 0.127)
		(layer "In2.Cu")
		(net "EXP_XM_ADDR_12")
	)
	(segment
		(start 119.50827 -81.87309)
		(end 119.50827 -81.61909)
		(width 0.127)
		(layer "In2.Cu")
		(net "EXP_XM_ADDR_12")
	)
	(segment
		(start 120.445784 -82.78749)
		(end 120.166384 -82.50809)
		(width 0.127)
		(layer "In2.Cu")
		(net "EXP_XM_ADDR_12")
	)
	(segment
		(start 120.995694 -89.210388)
		(end 120.995694 -88.956388)
		(width 0.127)
		(layer "In2.Cu")
		(net "EXP_XM_ADDR_12")
	)
	(segment
		(start 120.756172 -86.390226)
		(end 120.883172 -86.263226)
		(width 0.127)
		(layer "In2.Cu")
		(net "EXP_XM_ADDR_12")
	)
	(segment
		(start 121.921016 -86.136226)
		(end 121.921016 -85.882226)
		(width 0.127)
		(layer "In2.Cu")
		(net "EXP_XM_ADDR_12")
	)
	(segment
		(start 121.781316 -87.914226)
		(end 121.654316 -87.787226)
		(width 0.127)
		(layer "In2.Cu")
		(net "EXP_XM_ADDR_12")
	)
	(segment
		(start 121.172224 -89.845388)
		(end 121.615708 -89.845388)
		(width 0.127)
		(layer "In2.Cu")
		(net "EXP_XM_ADDR_12")
	)
	(segment
		(start 122.191018 -86.898226)
		(end 122.064018 -86.771226)
		(width 0.127)
		(layer "In2.Cu")
		(net "EXP_XM_ADDR_12")
	)
	(segment
		(start 118.5164 -82.38109)
		(end 118.5164 -82.12709)
		(width 0.127)
		(layer "In2.Cu")
		(net "EXP_XM_ADDR_12")
	)
	(segment
		(start 115.50015 -77.500226)
		(end 116.000022 -78.000098)
		(width 0.127)
		(layer "F.Cu")
		(net "EXP_XM_ADDR_11")
	)
	(via
		(at 116.000022 -78.000098)
		(size 0.4572)
		(drill 0.2032)
		(layers "F.Cu" "B.Cu")
		(net "EXP_XM_ADDR_11")
	)
	(via
		(at 77.26807 -97.1423)
		(size 0.508)
		(drill 0.254)
		(layers "F.Cu" "B.Cu")
		(net "EXP_XM_ADDR_11")
	)
	(segment
		(start 77.26807 -94.8309)
		(end 77.26807 -97.1423)
		(width 0.127)
		(layer "B.Cu")
		(net "EXP_XM_ADDR_11")
	)
	(segment
		(start 119.33809 -83.621626)
		(end 119.158258 -83.621626)
		(width 0.127)
		(layer "In2.Cu")
		(net "EXP_XM_ADDR_11")
	)
	(segment
		(start 82.867246 -96.788224)
		(end 82.867246 -96.5327)
		(width 0.127)
		(layer "In2.Cu")
		(net "EXP_XM_ADDR_11")
	)
	(segment
		(start 118.876572 -94.379542)
		(end 118.876572 -94.19971)
		(width 0.127)
		(layer "In2.Cu")
		(net "EXP_XM_ADDR_11")
	)
	(segment
		(start 79.311246 -96.149922)
		(end 79.311246 -96.788224)
		(width 0.127)
		(layer "In2.Cu")
		(net "EXP_XM_ADDR_11")
	)
	(segment
		(start 80.327246 -96.788224)
		(end 80.454246 -96.915224)
		(width 0.127)
		(layer "In2.Cu")
		(net "EXP_XM_ADDR_11")
	)
	(segment
		(start 80.962246 -95.967804)
		(end 81.216246 -95.967804)
		(width 0.127)
		(layer "In2.Cu")
		(net "EXP_XM_ADDR_11")
	)
	(segment
		(start 117.492526 -94.972124)
		(end 117.798342 -95.27794)
		(width 0.127)
		(layer "In2.Cu")
		(net "EXP_XM_ADDR_11")
	)
	(segment
		(start 120.4849 -90.435938)
		(end 120.4849 -87.145114)
		(width 0.127)
		(layer "In2.Cu")
		(net "EXP_XM_ADDR_11")
	)
	(segment
		(start 117.798342 -95.27794)
		(end 117.978174 -95.27794)
		(width 0.127)
		(layer "In2.Cu")
		(net "EXP_XM_ADDR_11")
	)
	(segment
		(start 117.35689 -94.972124)
		(end 117.492526 -94.972124)
		(width 0.127)
		(layer "In2.Cu")
		(net "EXP_XM_ADDR_11")
	)
	(segment
		(start 78.803246 -96.788224)
		(end 78.803246 -96.149922)
		(width 0.127)
		(layer "In2.Cu")
		(net "EXP_XM_ADDR_11")
	)
	(segment
		(start 81.851246 -96.072706)
		(end 81.978246 -95.945706)
		(width 0.127)
		(layer "In2.Cu")
		(net "EXP_XM_ADDR_11")
	)
	(segment
		(start 82.359246 -96.072706)
		(end 82.359246 -96.788224)
		(width 0.127)
		(layer "In2.Cu")
		(net "EXP_XM_ADDR_11")
	)
	(segment
		(start 82.232246 -95.945706)
		(end 82.359246 -96.072706)
		(width 0.127)
		(layer "In2.Cu")
		(net "EXP_XM_ADDR_11")
	)
	(segment
		(start 79.311246 -96.788224)
		(end 79.438246 -96.915224)
		(width 0.127)
		(layer "In2.Cu")
		(net "EXP_XM_ADDR_11")
	)
	(segment
		(start 88.68029 -96.4057)
		(end 89.078816 -96.007174)
		(width 0.127)
		(layer "In2.Cu")
		(net "EXP_XM_ADDR_11")
	)
	(segment
		(start 120.220232 -85.53069)
		(end 119.22887 -84.539328)
		(width 0.127)
		(layer "In2.Cu")
		(net "EXP_XM_ADDR_11")
	)
	(segment
		(start 81.978246 -95.945706)
		(end 82.232246 -95.945706)
		(width 0.127)
		(layer "In2.Cu")
		(net "EXP_XM_ADDR_11")
	)
	(segment
		(start 82.359246 -96.788224)
		(end 82.486246 -96.915224)
		(width 0.127)
		(layer "In2.Cu")
		(net "EXP_XM_ADDR_11")
	)
	(segment
		(start 80.327246 -96.139)
		(end 80.327246 -96.788224)
		(width 0.127)
		(layer "In2.Cu")
		(net "EXP_XM_ADDR_11")
	)
	(segment
		(start 80.454246 -96.915224)
		(end 80.708246 -96.915224)
		(width 0.127)
		(layer "In2.Cu")
		(net "EXP_XM_ADDR_11")
	)
	(segment
		(start 79.819246 -96.788224)
		(end 79.819246 -96.139)
		(width 0.127)
		(layer "In2.Cu")
		(net "EXP_XM_ADDR_11")
	)
	(segment
		(start 116.754148 -82.141568)
		(end 116.754148 -81.646268)
		(width 0.127)
		(layer "In2.Cu")
		(net "EXP_XM_ADDR_11")
	)
	(segment
		(start 78.676246 -96.915224)
		(end 78.803246 -96.788224)
		(width 0.127)
		(layer "In2.Cu")
		(net "EXP_XM_ADDR_11")
	)
	(segment
		(start 118.157752 -94.91853)
		(end 117.851936 -94.612714)
		(width 0.127)
		(layer "In2.Cu")
		(net "EXP_XM_ADDR_11")
	)
	(segment
		(start 116.773706 -95.690944)
		(end 117.079522 -95.99676)
		(width 0.127)
		(layer "In2.Cu")
		(net "EXP_XM_ADDR_11")
	)
	(segment
		(start 117.606318 -81.33715)
		(end 117.606318 -80.767682)
		(width 0.127)
		(layer "In2.Cu")
		(net "EXP_XM_ADDR_11")
	)
	(segment
		(start 80.835246 -96.788224)
		(end 80.835246 -96.094804)
		(width 0.127)
		(layer "In2.Cu")
		(net "EXP_XM_ADDR_11")
	)
	(segment
		(start 81.724246 -96.915224)
		(end 81.851246 -96.788224)
		(width 0.127)
		(layer "In2.Cu")
		(net "EXP_XM_ADDR_11")
	)
	(segment
		(start 118.741952 -84.037932)
		(end 118.56212 -84.037932)
		(width 0.127)
		(layer "In2.Cu")
		(net "EXP_XM_ADDR_11")
	)
	(segment
		(start 78.295246 -96.788224)
		(end 78.422246 -96.915224)
		(width 0.127)
		(layer "In2.Cu")
		(net "EXP_XM_ADDR_11")
	)
	(segment
		(start 119.158258 -83.621626)
		(end 118.741952 -84.037932)
		(width 0.127)
		(layer "In2.Cu")
		(net "EXP_XM_ADDR_11")
	)
	(segment
		(start 79.819246 -96.139)
		(end 79.946246 -96.012)
		(width 0.127)
		(layer "In2.Cu")
		(net "EXP_XM_ADDR_11")
	)
	(segment
		(start 119.517668 -83.801204)
		(end 119.33809 -83.621626)
		(width 0.127)
		(layer "In2.Cu")
		(net "EXP_XM_ADDR_11")
	)
	(segment
		(start 117.438932 -95.817182)
		(end 117.438932 -95.63735)
		(width 0.127)
		(layer "In2.Cu")
		(net "EXP_XM_ADDR_11")
	)
	(segment
		(start 116.881148 -81.519268)
		(end 117.4242 -81.519268)
		(width 0.127)
		(layer "In2.Cu")
		(net "EXP_XM_ADDR_11")
	)
	(segment
		(start 79.946246 -96.012)
		(end 80.200246 -96.012)
		(width 0.127)
		(layer "In2.Cu")
		(net "EXP_XM_ADDR_11")
	)
	(segment
		(start 116.5352 -80.092296)
		(end 116.5352 -78.535276)
		(width 0.127)
		(layer "In2.Cu")
		(net "EXP_XM_ADDR_11")
	)
	(segment
		(start 117.388132 -80.549496)
		(end 116.9924 -80.549496)
		(width 0.127)
		(layer "In2.Cu")
		(net "EXP_XM_ADDR_11")
	)
	(segment
		(start 118.157752 -95.098362)
		(end 118.157752 -94.91853)
		(width 0.127)
		(layer "In2.Cu")
		(net "EXP_XM_ADDR_11")
	)
	(segment
		(start 77.26807 -96.149922)
		(end 77.39507 -96.022922)
		(width 0.127)
		(layer "In2.Cu")
		(net "EXP_XM_ADDR_11")
	)
	(segment
		(start 82.867246 -96.5327)
		(end 82.994246 -96.4057)
		(width 0.127)
		(layer "In2.Cu")
		(net "EXP_XM_ADDR_11")
	)
	(segment
		(start 116.754148 -81.646268)
		(end 116.881148 -81.519268)
		(width 0.127)
		(layer "In2.Cu")
		(net "EXP_XM_ADDR_11")
	)
	(segment
		(start 82.486246 -96.915224)
		(end 82.740246 -96.915224)
		(width 0.127)
		(layer "In2.Cu")
		(net "EXP_XM_ADDR_11")
	)
	(segment
		(start 77.39507 -96.022922)
		(end 78.168246 -96.022922)
		(width 0.127)
		(layer "In2.Cu")
		(net "EXP_XM_ADDR_11")
	)
	(segment
		(start 117.133116 -95.331534)
		(end 117.133116 -95.195898)
		(width 0.127)
		(layer "In2.Cu")
		(net "EXP_XM_ADDR_11")
	)
	(segment
		(start 78.295246 -96.149922)
		(end 78.295246 -96.788224)
		(width 0.127)
		(layer "In2.Cu")
		(net "EXP_XM_ADDR_11")
	)
	(segment
		(start 81.851246 -96.788224)
		(end 81.851246 -96.072706)
		(width 0.127)
		(layer "In2.Cu")
		(net "EXP_XM_ADDR_11")
	)
	(segment
		(start 119.22887 -84.539328)
		(end 119.22887 -84.269834)
		(width 0.127)
		(layer "In2.Cu")
		(net "EXP_XM_ADDR_11")
	)
	(segment
		(start 118.382542 -83.858354)
		(end 118.382542 -83.678522)
		(width 0.127)
		(layer "In2.Cu")
		(net "EXP_XM_ADDR_11")
	)
	(segment
		(start 82.740246 -96.915224)
		(end 82.867246 -96.788224)
		(width 0.127)
		(layer "In2.Cu")
		(net "EXP_XM_ADDR_11")
	)
	(segment
		(start 116.32184 -96.007174)
		(end 116.63807 -95.690944)
		(width 0.127)
		(layer "In2.Cu")
		(net "EXP_XM_ADDR_11")
	)
	(segment
		(start 118.876572 -94.19971)
		(end 118.570756 -93.893894)
		(width 0.127)
		(layer "In2.Cu")
		(net "EXP_XM_ADDR_11")
	)
	(segment
		(start 78.168246 -96.022922)
		(end 78.295246 -96.149922)
		(width 0.127)
		(layer "In2.Cu")
		(net "EXP_XM_ADDR_11")
	)
	(segment
		(start 78.930246 -96.022922)
		(end 79.184246 -96.022922)
		(width 0.127)
		(layer "In2.Cu")
		(net "EXP_XM_ADDR_11")
	)
	(segment
		(start 118.517162 -94.55912)
		(end 118.696994 -94.55912)
		(width 0.127)
		(layer "In2.Cu")
		(net "EXP_XM_ADDR_11")
	)
	(segment
		(start 117.606318 -80.767682)
		(end 117.388132 -80.549496)
		(width 0.127)
		(layer "In2.Cu")
		(net "EXP_XM_ADDR_11")
	)
	(segment
		(start 80.835246 -96.094804)
		(end 80.962246 -95.967804)
		(width 0.127)
		(layer "In2.Cu")
		(net "EXP_XM_ADDR_11")
	)
	(segment
		(start 117.851936 -94.612714)
		(end 117.851936 -94.477078)
		(width 0.127)
		(layer "In2.Cu")
		(net "EXP_XM_ADDR_11")
	)
	(segment
		(start 117.438932 -95.63735)
		(end 117.133116 -95.331534)
		(width 0.127)
		(layer "In2.Cu")
		(net "EXP_XM_ADDR_11")
	)
	(segment
		(start 118.56212 -84.037932)
		(end 118.382542 -83.858354)
		(width 0.127)
		(layer "In2.Cu")
		(net "EXP_XM_ADDR_11")
	)
	(segment
		(start 80.708246 -96.915224)
		(end 80.835246 -96.788224)
		(width 0.127)
		(layer "In2.Cu")
		(net "EXP_XM_ADDR_11")
	)
	(segment
		(start 78.803246 -96.149922)
		(end 78.930246 -96.022922)
		(width 0.127)
		(layer "In2.Cu")
		(net "EXP_XM_ADDR_11")
	)
	(segment
		(start 120.195848 -92.133166)
		(end 120.195848 -90.725244)
		(width 0.127)
		(layer "In2.Cu")
		(net "EXP_XM_ADDR_11")
	)
	(segment
		(start 82.994246 -96.4057)
		(end 88.68029 -96.4057)
		(width 0.127)
		(layer "In2.Cu")
		(net "EXP_XM_ADDR_11")
	)
	(segment
		(start 118.696994 -94.55912)
		(end 118.876572 -94.379542)
		(width 0.127)
		(layer "In2.Cu")
		(net "EXP_XM_ADDR_11")
	)
	(segment
		(start 81.343246 -96.094804)
		(end 81.343246 -96.788224)
		(width 0.127)
		(layer "In2.Cu")
		(net "EXP_XM_ADDR_11")
	)
	(segment
		(start 80.200246 -96.012)
		(end 80.327246 -96.139)
		(width 0.127)
		(layer "In2.Cu")
		(net "EXP_XM_ADDR_11")
	)
	(segment
		(start 119.22887 -84.269834)
		(end 119.517668 -83.981036)
		(width 0.127)
		(layer "In2.Cu")
		(net "EXP_XM_ADDR_11")
	)
	(segment
		(start 81.343246 -96.788224)
		(end 81.470246 -96.915224)
		(width 0.127)
		(layer "In2.Cu")
		(net "EXP_XM_ADDR_11")
	)
	(segment
		(start 118.211346 -94.253304)
		(end 118.517162 -94.55912)
		(width 0.127)
		(layer "In2.Cu")
		(net "EXP_XM_ADDR_11")
	)
	(segment
		(start 118.07571 -94.253304)
		(end 118.211346 -94.253304)
		(width 0.127)
		(layer "In2.Cu")
		(net "EXP_XM_ADDR_11")
	)
	(segment
		(start 81.216246 -95.967804)
		(end 81.343246 -96.094804)
		(width 0.127)
		(layer "In2.Cu")
		(net "EXP_XM_ADDR_11")
	)
	(segment
		(start 116.63807 -95.690944)
		(end 116.773706 -95.690944)
		(width 0.127)
		(layer "In2.Cu")
		(net "EXP_XM_ADDR_11")
	)
	(segment
		(start 81.470246 -96.915224)
		(end 81.724246 -96.915224)
		(width 0.127)
		(layer "In2.Cu")
		(net "EXP_XM_ADDR_11")
	)
	(segment
		(start 78.422246 -96.915224)
		(end 78.676246 -96.915224)
		(width 0.127)
		(layer "In2.Cu")
		(net "EXP_XM_ADDR_11")
	)
	(segment
		(start 116.881148 -82.268568)
		(end 116.754148 -82.141568)
		(width 0.127)
		(layer "In2.Cu")
		(net "EXP_XM_ADDR_11")
	)
	(segment
		(start 120.220232 -86.880446)
		(end 120.220232 -85.53069)
		(width 0.127)
		(layer "In2.Cu")
		(net "EXP_XM_ADDR_11")
	)
	(segment
		(start 117.079522 -95.99676)
		(end 117.259354 -95.99676)
		(width 0.127)
		(layer "In2.Cu")
		(net "EXP_XM_ADDR_11")
	)
	(segment
		(start 117.851936 -94.477078)
		(end 118.07571 -94.253304)
		(width 0.127)
		(layer "In2.Cu")
		(net "EXP_XM_ADDR_11")
	)
	(segment
		(start 117.902736 -82.268568)
		(end 116.881148 -82.268568)
		(width 0.127)
		(layer "In2.Cu")
		(net "EXP_XM_ADDR_11")
	)
	(segment
		(start 79.184246 -96.022922)
		(end 79.311246 -96.149922)
		(width 0.127)
		(layer "In2.Cu")
		(net "EXP_XM_ADDR_11")
	)
	(segment
		(start 120.4849 -87.145114)
		(end 120.220232 -86.880446)
		(width 0.127)
		(layer "In2.Cu")
		(net "EXP_XM_ADDR_11")
	)
	(segment
		(start 118.798848 -83.262216)
		(end 118.798848 -83.16468)
		(width 0.127)
		(layer "In2.Cu")
		(net "EXP_XM_ADDR_11")
	)
	(segment
		(start 116.9924 -80.549496)
		(end 116.5352 -80.092296)
		(width 0.127)
		(layer "In2.Cu")
		(net "EXP_XM_ADDR_11")
	)
	(segment
		(start 118.570756 -93.893894)
		(end 118.570756 -93.758258)
		(width 0.127)
		(layer "In2.Cu")
		(net "EXP_XM_ADDR_11")
	)
	(segment
		(start 118.570756 -93.758258)
		(end 120.195848 -92.133166)
		(width 0.127)
		(layer "In2.Cu")
		(net "EXP_XM_ADDR_11")
	)
	(segment
		(start 119.517668 -83.981036)
		(end 119.517668 -83.801204)
		(width 0.127)
		(layer "In2.Cu")
		(net "EXP_XM_ADDR_11")
	)
	(segment
		(start 118.798848 -83.16468)
		(end 117.902736 -82.268568)
		(width 0.127)
		(layer "In2.Cu")
		(net "EXP_XM_ADDR_11")
	)
	(segment
		(start 116.5352 -78.535276)
		(end 116.000022 -78.000098)
		(width 0.127)
		(layer "In2.Cu")
		(net "EXP_XM_ADDR_11")
	)
	(segment
		(start 117.4242 -81.519268)
		(end 117.606318 -81.33715)
		(width 0.127)
		(layer "In2.Cu")
		(net "EXP_XM_ADDR_11")
	)
	(segment
		(start 117.259354 -95.99676)
		(end 117.438932 -95.817182)
		(width 0.127)
		(layer "In2.Cu")
		(net "EXP_XM_ADDR_11")
	)
	(segment
		(start 79.438246 -96.915224)
		(end 79.692246 -96.915224)
		(width 0.127)
		(layer "In2.Cu")
		(net "EXP_XM_ADDR_11")
	)
	(segment
		(start 117.978174 -95.27794)
		(end 118.157752 -95.098362)
		(width 0.127)
		(layer "In2.Cu")
		(net "EXP_XM_ADDR_11")
	)
	(segment
		(start 77.26807 -97.1423)
		(end 77.26807 -96.149922)
		(width 0.127)
		(layer "In2.Cu")
		(net "EXP_XM_ADDR_11")
	)
	(segment
		(start 117.133116 -95.195898)
		(end 117.35689 -94.972124)
		(width 0.127)
		(layer "In2.Cu")
		(net "EXP_XM_ADDR_11")
	)
	(segment
		(start 118.382542 -83.678522)
		(end 118.798848 -83.262216)
		(width 0.127)
		(layer "In2.Cu")
		(net "EXP_XM_ADDR_11")
	)
	(segment
		(start 89.078816 -96.007174)
		(end 116.32184 -96.007174)
		(width 0.127)
		(layer "In2.Cu")
		(net "EXP_XM_ADDR_11")
	)
	(segment
		(start 120.195848 -90.725244)
		(end 120.4849 -90.435938)
		(width 0.127)
		(layer "In2.Cu")
		(net "EXP_XM_ADDR_11")
	)
	(segment
		(start 79.692246 -96.915224)
		(end 79.819246 -96.788224)
		(width 0.127)
		(layer "In2.Cu")
		(net "EXP_XM_ADDR_11")
	)
	(segment
		(start 114.499898 -72.500236)
		(end 114.99977 -73.000108)
		(width 0.127)
		(layer "F.Cu")
		(net "EXP_XM_ADDR_10")
	)
	(via
		(at 78.333092 -98.165666)
		(size 0.508)
		(drill 0.254)
		(layers "F.Cu" "B.Cu")
		(net "EXP_XM_ADDR_10")
	)
	(via
		(at 114.99977 -73.000108)
		(size 0.4572)
		(drill 0.2032)
		(layers "F.Cu" "B.Cu")
		(net "EXP_XM_ADDR_10")
	)
	(segment
		(start 77.76845 -95.715836)
		(end 77.76845 -94.8309)
		(width 0.127)
		(layer "B.Cu")
		(net "EXP_XM_ADDR_10")
	)
	(segment
		(start 78.333092 -98.165666)
		(end 78.333092 -96.280478)
		(width 0.127)
		(layer "B.Cu")
		(net "EXP_XM_ADDR_10")
	)
	(segment
		(start 78.333092 -96.280478)
		(end 77.76845 -95.715836)
		(width 0.127)
		(layer "B.Cu")
		(net "EXP_XM_ADDR_10")
	)
	(segment
		(start 122.5296 -81.2292)
		(end 122.5296 -79.832454)
		(width 0.127)
		(layer "In2.Cu")
		(net "EXP_XM_ADDR_10")
	)
	(segment
		(start 124.2949 -91.87561)
		(end 124.2949 -90.258646)
		(width 0.127)
		(layer "In2.Cu")
		(net "EXP_XM_ADDR_10")
	)
	(segment
		(start 122.9106 -83.158076)
		(end 122.9106 -81.6102)
		(width 0.127)
		(layer "In2.Cu")
		(net "EXP_XM_ADDR_10")
	)
	(segment
		(start 118.208806 -74.520806)
		(end 116.7638 -74.520806)
		(width 0.127)
		(layer "In2.Cu")
		(net "EXP_XM_ADDR_10")
	)
	(segment
		(start 120.992138 -77.6732)
		(end 120.598946 -77.280008)
		(width 0.127)
		(layer "In2.Cu")
		(net "EXP_XM_ADDR_10")
	)
	(segment
		(start 120.735344 -98.547174)
		(end 123.7996 -95.482918)
		(width 0.127)
		(layer "In2.Cu")
		(net "EXP_XM_ADDR_10")
	)
	(segment
		(start 123.7996 -95.482918)
		(end 123.7996 -92.37091)
		(width 0.127)
		(layer "In2.Cu")
		(net "EXP_XM_ADDR_10")
	)
	(segment
		(start 120.2182 -76.5048)
		(end 119.6848 -76.5048)
		(width 0.127)
		(layer "In2.Cu")
		(net "EXP_XM_ADDR_10")
	)
	(segment
		(start 123.7996 -92.37091)
		(end 124.2949 -91.87561)
		(width 0.127)
		(layer "In2.Cu")
		(net "EXP_XM_ADDR_10")
	)
	(segment
		(start 116.251228 -73.426828)
		(end 115.42649 -73.426828)
		(width 0.127)
		(layer "In2.Cu")
		(net "EXP_XM_ADDR_10")
	)
	(segment
		(start 119.4562 -75.7682)
		(end 118.208806 -74.520806)
		(width 0.127)
		(layer "In2.Cu")
		(net "EXP_XM_ADDR_10")
	)
	(segment
		(start 125.444758 -89.108788)
		(end 125.444758 -85.692234)
		(width 0.127)
		(layer "In2.Cu")
		(net "EXP_XM_ADDR_10")
	)
	(segment
		(start 122.5296 -79.832454)
		(end 120.992138 -78.294992)
		(width 0.127)
		(layer "In2.Cu")
		(net "EXP_XM_ADDR_10")
	)
	(segment
		(start 119.4562 -76.2762)
		(end 119.4562 -75.7682)
		(width 0.127)
		(layer "In2.Cu")
		(net "EXP_XM_ADDR_10")
	)
	(segment
		(start 115.42649 -73.426828)
		(end 114.99977 -73.000108)
		(width 0.127)
		(layer "In2.Cu")
		(net "EXP_XM_ADDR_10")
	)
	(segment
		(start 89.662 -99.187)
		(end 90.301826 -98.547174)
		(width 0.127)
		(layer "In2.Cu")
		(net "EXP_XM_ADDR_10")
	)
	(segment
		(start 78.333092 -98.165666)
		(end 79.354426 -99.187)
		(width 0.127)
		(layer "In2.Cu")
		(net "EXP_XM_ADDR_10")
	)
	(segment
		(start 120.598946 -77.280008)
		(end 120.598946 -76.885546)
		(width 0.127)
		(layer "In2.Cu")
		(net "EXP_XM_ADDR_10")
	)
	(segment
		(start 120.992138 -78.294992)
		(end 120.992138 -77.6732)
		(width 0.127)
		(layer "In2.Cu")
		(net "EXP_XM_ADDR_10")
	)
	(segment
		(start 116.5352 -73.7108)
		(end 116.251228 -73.426828)
		(width 0.127)
		(layer "In2.Cu")
		(net "EXP_XM_ADDR_10")
	)
	(segment
		(start 90.301826 -98.547174)
		(end 120.735344 -98.547174)
		(width 0.127)
		(layer "In2.Cu")
		(net "EXP_XM_ADDR_10")
	)
	(segment
		(start 79.354426 -99.187)
		(end 89.662 -99.187)
		(width 0.127)
		(layer "In2.Cu")
		(net "EXP_XM_ADDR_10")
	)
	(segment
		(start 120.598946 -76.885546)
		(end 120.2182 -76.5048)
		(width 0.127)
		(layer "In2.Cu")
		(net "EXP_XM_ADDR_10")
	)
	(segment
		(start 116.5352 -74.292206)
		(end 116.5352 -73.7108)
		(width 0.127)
		(layer "In2.Cu")
		(net "EXP_XM_ADDR_10")
	)
	(segment
		(start 124.2949 -90.258646)
		(end 125.444758 -89.108788)
		(width 0.127)
		(layer "In2.Cu")
		(net "EXP_XM_ADDR_10")
	)
	(segment
		(start 116.7638 -74.520806)
		(end 116.5352 -74.292206)
		(width 0.127)
		(layer "In2.Cu")
		(net "EXP_XM_ADDR_10")
	)
	(segment
		(start 119.6848 -76.5048)
		(end 119.4562 -76.2762)
		(width 0.127)
		(layer "In2.Cu")
		(net "EXP_XM_ADDR_10")
	)
	(segment
		(start 122.9106 -81.6102)
		(end 122.5296 -81.2292)
		(width 0.127)
		(layer "In2.Cu")
		(net "EXP_XM_ADDR_10")
	)
	(segment
		(start 125.444758 -85.692234)
		(end 122.9106 -83.158076)
		(width 0.127)
		(layer "In2.Cu")
		(net "EXP_XM_ADDR_10")
	)
	(segment
		(start 116.500148 -77.500226)
		(end 117.00002 -78.000098)
		(width 0.127)
		(layer "F.Cu")
		(net "EXP_XM_ADDR_1")
	)
	(via
		(at 85.1916 -85.6996)
		(size 0.508)
		(drill 0.254)
		(layers "F.Cu" "B.Cu")
		(net "EXP_XM_ADDR_1")
	)
	(via
		(at 117.00002 -78.000098)
		(size 0.4572)
		(drill 0.2032)
		(layers "F.Cu" "B.Cu")
		(net "EXP_XM_ADDR_1")
	)
	(segment
		(start 85.5218 -80.434942)
		(end 85.6488 -80.307942)
		(width 0.127)
		(layer "B.Cu")
		(net "EXP_XM_ADDR_1")
	)
	(segment
		(start 85.5472 -81.323942)
		(end 86.995 -81.323942)
		(width 0.127)
		(layer "B.Cu")
		(net "EXP_XM_ADDR_1")
	)
	(segment
		(start 85.5472 -83.863942)
		(end 85.4202 -83.736942)
		(width 0.127)
		(layer "B.Cu")
		(net "EXP_XM_ADDR_1")
	)
	(segment
		(start 87.0458 -83.355942)
		(end 87.1728 -83.228942)
		(width 0.127)
		(layer "B.Cu")
		(net "EXP_XM_ADDR_1")
	)
	(segment
		(start 87.9348 -78.148942)
		(end 87.9348 -77.894942)
		(width 0.127)
		(layer "B.Cu")
		(net "EXP_XM_ADDR_1")
	)
	(segment
		(start 86.505542 -77.767942)
		(end 86.26856 -77.53096)
		(width 0.127)
		(layer "B.Cu")
		(net "EXP_XM_ADDR_1")
	)
	(segment
		(start 87.122 -84.244942)
		(end 87.122 -83.990942)
		(width 0.127)
		(layer "B.Cu")
		(net "EXP_XM_ADDR_1")
	)
	(segment
		(start 85.3948 -82.466942)
		(end 85.5218 -82.339942)
		(width 0.127)
		(layer "B.Cu")
		(net "EXP_XM_ADDR_1")
	)
	(segment
		(start 85.4202 -81.704942)
		(end 85.4202 -81.450942)
		(width 0.127)
		(layer "B.Cu")
		(net "EXP_XM_ADDR_1")
	)
	(segment
		(start 88.011 -78.910942)
		(end 87.884 -78.783942)
		(width 0.127)
		(layer "B.Cu")
		(net "EXP_XM_ADDR_1")
	)
	(segment
		(start 87.0712 -85.006942)
		(end 86.9442 -84.879942)
		(width 0.127)
		(layer "B.Cu")
		(net "EXP_XM_ADDR_1")
	)
	(segment
		(start 85.6234 -79.418942)
		(end 85.7504 -79.291942)
		(width 0.127)
		(layer "B.Cu")
		(net "EXP_XM_ADDR_1")
	)
	(segment
		(start 85.3186 -84.371942)
		(end 86.995 -84.371942)
		(width 0.127)
		(layer "B.Cu")
		(net "EXP_XM_ADDR_1")
	)
	(segment
		(start 85.5218 -82.339942)
		(end 86.995 -82.339942)
		(width 0.127)
		(layer "B.Cu")
		(net "EXP_XM_ADDR_1")
	)
	(segment
		(start 88.011 -79.164942)
		(end 88.011 -78.910942)
		(width 0.127)
		(layer "B.Cu")
		(net "EXP_XM_ADDR_1")
	)
	(segment
		(start 87.122 -82.212942)
		(end 87.122 -81.958942)
		(width 0.127)
		(layer "B.Cu")
		(net "EXP_XM_ADDR_1")
	)
	(segment
		(start 87.1728 -82.974942)
		(end 87.0458 -82.847942)
		(width 0.127)
		(layer "B.Cu")
		(net "EXP_XM_ADDR_1")
	)
	(segment
		(start 85.1916 -84.498942)
		(end 85.3186 -84.371942)
		(width 0.127)
		(layer "B.Cu")
		(net "EXP_XM_ADDR_1")
	)
	(segment
		(start 85.5218 -82.847942)
		(end 85.3948 -82.720942)
		(width 0.127)
		(layer "B.Cu")
		(net "EXP_XM_ADDR_1")
	)
	(segment
		(start 86.6648 -79.926942)
		(end 86.5378 -79.799942)
		(width 0.127)
		(layer "B.Cu")
		(net "EXP_XM_ADDR_1")
	)
	(segment
		(start 85.5472 -81.831942)
		(end 85.4202 -81.704942)
		(width 0.127)
		(layer "B.Cu")
		(net "EXP_XM_ADDR_1")
	)
	(segment
		(start 85.9028 -78.656942)
		(end 85.9028 -78.402942)
		(width 0.127)
		(layer "B.Cu")
		(net "EXP_XM_ADDR_1")
	)
	(segment
		(start 85.4202 -83.482942)
		(end 85.5472 -83.355942)
		(width 0.127)
		(layer "B.Cu")
		(net "EXP_XM_ADDR_1")
	)
	(segment
		(start 87.122 -80.942942)
		(end 86.995 -80.815942)
		(width 0.127)
		(layer "B.Cu")
		(net "EXP_XM_ADDR_1")
	)
	(segment
		(start 86.995 -82.339942)
		(end 87.122 -82.212942)
		(width 0.127)
		(layer "B.Cu")
		(net "EXP_XM_ADDR_1")
	)
	(segment
		(start 87.8078 -77.767942)
		(end 86.505542 -77.767942)
		(width 0.127)
		(layer "B.Cu")
		(net "EXP_XM_ADDR_1")
	)
	(segment
		(start 86.5378 -80.307942)
		(end 86.6648 -80.180942)
		(width 0.127)
		(layer "B.Cu")
		(net "EXP_XM_ADDR_1")
	)
	(segment
		(start 85.3948 -82.720942)
		(end 85.3948 -82.466942)
		(width 0.127)
		(layer "B.Cu")
		(net "EXP_XM_ADDR_1")
	)
	(segment
		(start 86.995 -80.815942)
		(end 85.6488 -80.815942)
		(width 0.127)
		(layer "B.Cu")
		(net "EXP_XM_ADDR_1")
	)
	(segment
		(start 86.6648 -80.180942)
		(end 86.6648 -79.926942)
		(width 0.127)
		(layer "B.Cu")
		(net "EXP_XM_ADDR_1")
	)
	(segment
		(start 86.9442 -84.879942)
		(end 85.3186 -84.879942)
		(width 0.127)
		(layer "B.Cu")
		(net "EXP_XM_ADDR_1")
	)
	(segment
		(start 87.1728 -83.228942)
		(end 87.1728 -82.974942)
		(width 0.127)
		(layer "B.Cu")
		(net "EXP_XM_ADDR_1")
	)
	(segment
		(start 85.1916 -85.6996)
		(end 85.503258 -85.387942)
		(width 0.127)
		(layer "B.Cu")
		(net "EXP_XM_ADDR_1")
	)
	(segment
		(start 86.0298 -78.275942)
		(end 87.8078 -78.275942)
		(width 0.127)
		(layer "B.Cu")
		(net "EXP_XM_ADDR_1")
	)
	(segment
		(start 85.4202 -81.450942)
		(end 85.5472 -81.323942)
		(width 0.127)
		(layer "B.Cu")
		(net "EXP_XM_ADDR_1")
	)
	(segment
		(start 85.9028 -78.402942)
		(end 86.0298 -78.275942)
		(width 0.127)
		(layer "B.Cu")
		(net "EXP_XM_ADDR_1")
	)
	(segment
		(start 87.884 -79.291942)
		(end 88.011 -79.164942)
		(width 0.127)
		(layer "B.Cu")
		(net "EXP_XM_ADDR_1")
	)
	(segment
		(start 85.6234 -79.672942)
		(end 85.6234 -79.418942)
		(width 0.127)
		(layer "B.Cu")
		(net "EXP_XM_ADDR_1")
	)
	(segment
		(start 85.5218 -80.688942)
		(end 85.5218 -80.434942)
		(width 0.127)
		(layer "B.Cu")
		(net "EXP_XM_ADDR_1")
	)
	(segment
		(start 87.122 -81.958942)
		(end 86.995 -81.831942)
		(width 0.127)
		(layer "B.Cu")
		(net "EXP_XM_ADDR_1")
	)
	(segment
		(start 87.0458 -82.847942)
		(end 85.5218 -82.847942)
		(width 0.127)
		(layer "B.Cu")
		(net "EXP_XM_ADDR_1")
	)
	(segment
		(start 85.6488 -80.815942)
		(end 85.5218 -80.688942)
		(width 0.127)
		(layer "B.Cu")
		(net "EXP_XM_ADDR_1")
	)
	(segment
		(start 87.122 -83.990942)
		(end 86.995 -83.863942)
		(width 0.127)
		(layer "B.Cu")
		(net "EXP_XM_ADDR_1")
	)
	(segment
		(start 85.4202 -83.736942)
		(end 85.4202 -83.482942)
		(width 0.127)
		(layer "B.Cu")
		(net "EXP_XM_ADDR_1")
	)
	(segment
		(start 86.995 -83.863942)
		(end 85.5472 -83.863942)
		(width 0.127)
		(layer "B.Cu")
		(net "EXP_XM_ADDR_1")
	)
	(segment
		(start 87.884 -78.783942)
		(end 86.0298 -78.783942)
		(width 0.127)
		(layer "B.Cu")
		(net "EXP_XM_ADDR_1")
	)
	(segment
		(start 87.9348 -77.894942)
		(end 87.8078 -77.767942)
		(width 0.127)
		(layer "B.Cu")
		(net "EXP_XM_ADDR_1")
	)
	(segment
		(start 85.5472 -83.355942)
		(end 87.0458 -83.355942)
		(width 0.127)
		(layer "B.Cu")
		(net "EXP_XM_ADDR_1")
	)
	(segment
		(start 85.503258 -85.387942)
		(end 86.9442 -85.387942)
		(width 0.127)
		(layer "B.Cu")
		(net "EXP_XM_ADDR_1")
	)
	(segment
		(start 86.26856 -77.53096)
		(end 86.26856 -75.6031)
		(width 0.127)
		(layer "B.Cu")
		(net "EXP_XM_ADDR_1")
	)
	(segment
		(start 87.8078 -78.275942)
		(end 87.9348 -78.148942)
		(width 0.127)
		(layer "B.Cu")
		(net "EXP_XM_ADDR_1")
	)
	(segment
		(start 85.1916 -84.752942)
		(end 85.1916 -84.498942)
		(width 0.127)
		(layer "B.Cu")
		(net "EXP_XM_ADDR_1")
	)
	(segment
		(start 87.0712 -85.260942)
		(end 87.0712 -85.006942)
		(width 0.127)
		(layer "B.Cu")
		(net "EXP_XM_ADDR_1")
	)
	(segment
		(start 86.995 -81.831942)
		(end 85.5472 -81.831942)
		(width 0.127)
		(layer "B.Cu")
		(net "EXP_XM_ADDR_1")
	)
	(segment
		(start 86.995 -81.323942)
		(end 87.122 -81.196942)
		(width 0.127)
		(layer "B.Cu")
		(net "EXP_XM_ADDR_1")
	)
	(segment
		(start 86.5378 -79.799942)
		(end 85.7504 -79.799942)
		(width 0.127)
		(layer "B.Cu")
		(net "EXP_XM_ADDR_1")
	)
	(segment
		(start 86.0298 -78.783942)
		(end 85.9028 -78.656942)
		(width 0.127)
		(layer "B.Cu")
		(net "EXP_XM_ADDR_1")
	)
	(segment
		(start 86.9442 -85.387942)
		(end 87.0712 -85.260942)
		(width 0.127)
		(layer "B.Cu")
		(net "EXP_XM_ADDR_1")
	)
	(segment
		(start 87.122 -81.196942)
		(end 87.122 -80.942942)
		(width 0.127)
		(layer "B.Cu")
		(net "EXP_XM_ADDR_1")
	)
	(segment
		(start 85.7504 -79.291942)
		(end 87.884 -79.291942)
		(width 0.127)
		(layer "B.Cu")
		(net "EXP_XM_ADDR_1")
	)
	(segment
		(start 86.995 -84.371942)
		(end 87.122 -84.244942)
		(width 0.127)
		(layer "B.Cu")
		(net "EXP_XM_ADDR_1")
	)
	(segment
		(start 85.7504 -79.799942)
		(end 85.6234 -79.672942)
		(width 0.127)
		(layer "B.Cu")
		(net "EXP_XM_ADDR_1")
	)
	(segment
		(start 85.3186 -84.879942)
		(end 85.1916 -84.752942)
		(width 0.127)
		(layer "B.Cu")
		(net "EXP_XM_ADDR_1")
	)
	(segment
		(start 85.6488 -80.307942)
		(end 86.5378 -80.307942)
		(width 0.127)
		(layer "B.Cu")
		(net "EXP_XM_ADDR_1")
	)
	(segment
		(start 114.2873 -81.855564)
		(end 114.2873 -83.482942)
		(width 0.127)
		(layer "In2.Cu")
		(net "EXP_XM_ADDR_1")
	)
	(segment
		(start 112.5474 -76.895706)
		(end 112.5474 -80.1624)
		(width 0.127)
		(layer "In2.Cu")
		(net "EXP_XM_ADDR_1")
	)
	(segment
		(start 115.557046 -76.890626)
		(end 115.22202 -76.5556)
		(width 0.127)
		(layer "In2.Cu")
		(net "EXP_XM_ADDR_1")
	)
	(segment
		(start 115.557046 -77.136244)
		(end 115.557046 -76.890626)
		(width 0.127)
		(layer "In2.Cu")
		(net "EXP_XM_ADDR_1")
	)
	(segment
		(start 116.699538 -78.000098)
		(end 116.190522 -77.491082)
		(width 0.127)
		(layer "In2.Cu")
		(net "EXP_XM_ADDR_1")
	)
	(segment
		(start 114.2873 -83.482942)
		(end 112.972342 -84.7979)
		(width 0.127)
		(layer "In2.Cu")
		(net "EXP_XM_ADDR_1")
	)
	(segment
		(start 115.22202 -76.5556)
		(end 112.887506 -76.5556)
		(width 0.127)
		(layer "In2.Cu")
		(net "EXP_XM_ADDR_1")
	)
	(segment
		(start 88.331294 -84.474812)
		(end 87.011764 -85.794342)
		(width 0.127)
		(layer "In2.Cu")
		(net "EXP_XM_ADDR_1")
	)
	(segment
		(start 113.106454 -80.4926)
		(end 113.5888 -80.974946)
		(width 0.127)
		(layer "In2.Cu")
		(net "EXP_XM_ADDR_1")
	)
	(segment
		(start 87.011764 -85.794342)
		(end 85.286342 -85.794342)
		(width 0.127)
		(layer "In2.Cu")
		(net "EXP_XM_ADDR_1")
	)
	(segment
		(start 112.5474 -80.1624)
		(end 112.8776 -80.4926)
		(width 0.127)
		(layer "In2.Cu")
		(net "EXP_XM_ADDR_1")
	)
	(segment
		(start 115.911884 -77.491082)
		(end 115.557046 -77.136244)
		(width 0.127)
		(layer "In2.Cu")
		(net "EXP_XM_ADDR_1")
	)
	(segment
		(start 116.190522 -77.491082)
		(end 115.911884 -77.491082)
		(width 0.127)
		(layer "In2.Cu")
		(net "EXP_XM_ADDR_1")
	)
	(segment
		(start 112.887506 -76.5556)
		(end 112.5474 -76.895706)
		(width 0.127)
		(layer "In2.Cu")
		(net "EXP_XM_ADDR_1")
	)
	(segment
		(start 85.286342 -85.794342)
		(end 85.1916 -85.6996)
		(width 0.127)
		(layer "In2.Cu")
		(net "EXP_XM_ADDR_1")
	)
	(segment
		(start 113.5888 -81.157064)
		(end 114.2873 -81.855564)
		(width 0.127)
		(layer "In2.Cu")
		(net "EXP_XM_ADDR_1")
	)
	(segment
		(start 113.5888 -80.974946)
		(end 113.5888 -81.157064)
		(width 0.127)
		(layer "In2.Cu")
		(net "EXP_XM_ADDR_1")
	)
	(segment
		(start 108.981494 -83.696302)
		(end 108.202984 -84.474812)
		(width 0.127)
		(layer "In2.Cu")
		(net "EXP_XM_ADDR_1")
	)
	(segment
		(start 112.8776 -80.4926)
		(end 113.106454 -80.4926)
		(width 0.127)
		(layer "In2.Cu")
		(net "EXP_XM_ADDR_1")
	)
	(segment
		(start 110.836456 -84.7979)
		(end 109.734858 -83.696302)
		(width 0.127)
		(layer "In2.Cu")
		(net "EXP_XM_ADDR_1")
	)
	(segment
		(start 108.202984 -84.474812)
		(end 88.331294 -84.474812)
		(width 0.127)
		(layer "In2.Cu")
		(net "EXP_XM_ADDR_1")
	)
	(segment
		(start 117.00002 -78.000098)
		(end 116.699538 -78.000098)
		(width 0.127)
		(layer "In2.Cu")
		(net "EXP_XM_ADDR_1")
	)
	(segment
		(start 109.734858 -83.696302)
		(end 108.981494 -83.696302)
		(width 0.127)
		(layer "In2.Cu")
		(net "EXP_XM_ADDR_1")
	)
	(segment
		(start 112.972342 -84.7979)
		(end 110.836456 -84.7979)
		(width 0.127)
		(layer "In2.Cu")
		(net "EXP_XM_ADDR_1")
	)
	(segment
		(start 118.48338 -86.908386)
		(end 119.456454 -85.935312)
		(width 0.127)
		(layer "F.Cu")
		(net "EXP_XM_ADDR_0")
	)
	(segment
		(start 117.992144 -82.435192)
		(end 117.500146 -81.943194)
		(width 0.127)
		(layer "F.Cu")
		(net "EXP_XM_ADDR_0")
	)
	(segment
		(start 117.500146 -81.943194)
		(end 117.500146 -81.500218)
		(width 0.127)
		(layer "F.Cu")
		(net "EXP_XM_ADDR_0")
	)
	(segment
		(start 119.31777 -85.376004)
		(end 119.31777 -84.440522)
		(width 0.127)
		(layer "F.Cu")
		(net "EXP_XM_ADDR_0")
	)
	(segment
		(start 119.456454 -85.514688)
		(end 119.31777 -85.376004)
		(width 0.127)
		(layer "F.Cu")
		(net "EXP_XM_ADDR_0")
	)
	(segment
		(start 119.456454 -85.935312)
		(end 119.456454 -85.514688)
		(width 0.127)
		(layer "F.Cu")
		(net "EXP_XM_ADDR_0")
	)
	(segment
		(start 118.1862 -89.276174)
		(end 118.48338 -88.978994)
		(width 0.127)
		(layer "F.Cu")
		(net "EXP_XM_ADDR_0")
	)
	(segment
		(start 119.31777 -84.440522)
		(end 117.992144 -83.114896)
		(width 0.127)
		(layer "F.Cu")
		(net "EXP_XM_ADDR_0")
	)
	(segment
		(start 117.992144 -83.114896)
		(end 117.992144 -82.435192)
		(width 0.127)
		(layer "F.Cu")
		(net "EXP_XM_ADDR_0")
	)
	(segment
		(start 118.48338 -88.978994)
		(end 118.48338 -86.908386)
		(width 0.127)
		(layer "F.Cu")
		(net "EXP_XM_ADDR_0")
	)
	(via
		(at 81.652618 -97.351342)
		(size 0.6096)
		(drill 0.3048)
		(layers "F.Cu" "B.Cu")
		(net "EXP_WP_N")
	)
	(segment
		(start 81.652618 -96.631252)
		(end 81.652618 -97.351342)
		(width 0.127)
		(layer "B.Cu")
		(net "EXP_WP_N")
	)
	(segment
		(start 81.345024 -98.168968)
		(end 81.652618 -97.861374)
		(width 0.127)
		(layer "B.Cu")
		(net "EXP_WP_N")
	)
	(segment
		(start 80.463644 -98.168968)
		(end 81.345024 -98.168968)
		(width 0.127)
		(layer "B.Cu")
		(net "EXP_WP_N")
	)
	(segment
		(start 81.652618 -97.861374)
		(end 81.652618 -97.351342)
		(width 0.127)
		(layer "B.Cu")
		(net "EXP_WP_N")
	)
	(segment
		(start 81.26857 -94.8309)
		(end 81.26857 -96.247204)
		(width 0.127)
		(layer "B.Cu")
		(net "EXP_WP_N")
	)
	(segment
		(start 81.26857 -96.247204)
		(end 81.652618 -96.631252)
		(width 0.127)
		(layer "B.Cu")
		(net "EXP_WP_N")
	)
	(via
		(at 94.27464 -79.883)
		(size 0.6096)
		(drill 0.3048)
		(layers "F.Cu" "B.Cu")
		(net "EXP_SYS_RST_N")
	)
	(segment
		(start 94.27464 -79.439516)
		(end 94.27464 -79.883)
		(width 0.127)
		(layer "B.Cu")
		(net "EXP_SYS_RST_N")
	)
	(segment
		(start 95.690436 -78.955138)
		(end 94.759018 -78.955138)
		(width 0.127)
		(layer "B.Cu")
		(net "EXP_SYS_RST_N")
	)
	(segment
		(start 94.27464 -81.52511)
		(end 94.27464 -79.883)
		(width 0.127)
		(layer "B.Cu")
		(net "EXP_SYS_RST_N")
	)
	(segment
		(start 94.759018 -78.955138)
		(end 94.27464 -79.439516)
		(width 0.127)
		(layer "B.Cu")
		(net "EXP_SYS_RST_N")
	)
	(segment
		(start 156.01188 -93.96095)
		(end 155.5242 -94.44863)
		(width 0.127)
		(layer "F.Cu")
		(net "EXP_SMART_TX_R")
	)
	(segment
		(start 156.722318 -95.223076)
		(end 155.878276 -95.223076)
		(width 0.127)
		(layer "F.Cu")
		(net "EXP_SMART_TX_R")
	)
	(segment
		(start 156.01188 -93.40215)
		(end 156.01188 -93.96095)
		(width 0.127)
		(layer "F.Cu")
		(net "EXP_SMART_TX_R")
	)
	(segment
		(start 155.878276 -95.223076)
		(end 155.5242 -94.869)
		(width 0.127)
		(layer "F.Cu")
		(net "EXP_SMART_TX_R")
	)
	(segment
		(start 155.5242 -94.44863)
		(end 155.5242 -94.869)
		(width 0.127)
		(layer "F.Cu")
		(net "EXP_SMART_TX_R")
	)
	(via
		(at 155.5242 -94.869)
		(size 0.6604)
		(drill 0.3302)
		(layers "F.Cu" "B.Cu")
		(net "EXP_SMART_TX_R")
	)
	(segment
		(start 154.469338 -93.40215)
		(end 154.8384 -93.771212)
		(width 0.127)
		(layer "F.Cu")
		(net "EXP_SMART_RX_R")
	)
	(segment
		(start 154.8384 -93.771212)
		(end 154.8384 -95.4532)
		(width 0.127)
		(layer "F.Cu")
		(net "EXP_SMART_RX_R")
	)
	(segment
		(start 156.722318 -96.239076)
		(end 155.624276 -96.239076)
		(width 0.127)
		(layer "F.Cu")
		(net "EXP_SMART_RX_R")
	)
	(segment
		(start 155.624276 -96.239076)
		(end 155.5242 -96.139)
		(width 0.127)
		(layer "F.Cu")
		(net "EXP_SMART_RX_R")
	)
	(segment
		(start 153.67508 -93.40215)
		(end 154.469338 -93.40215)
		(width 0.127)
		(layer "F.Cu")
		(net "EXP_SMART_RX_R")
	)
	(segment
		(start 154.8384 -95.4532)
		(end 155.5242 -96.139)
		(width 0.127)
		(layer "F.Cu")
		(net "EXP_SMART_RX_R")
	)
	(via
		(at 155.5242 -96.139)
		(size 0.6604)
		(drill 0.3302)
		(layers "F.Cu" "B.Cu")
		(net "EXP_SMART_RX_R")
	)
	(segment
		(start 120.50014 -73.500234)
		(end 121.000012 -74.000106)
		(width 0.127)
		(layer "F.Cu")
		(net "EXP_SIO_LOAD_OUT")
	)
	(via
		(at 121.8184 -78.8162)
		(size 0.6096)
		(drill 0.3048)
		(layers "F.Cu" "B.Cu")
		(net "EXP_SIO_LOAD_OUT")
	)
	(via
		(at 121.000012 -74.000106)
		(size 0.4572)
		(drill 0.2032)
		(layers "F.Cu" "B.Cu")
		(net "EXP_SIO_LOAD_OUT")
	)
	(segment
		(start 122.6947 -83.560666)
		(end 125.52553 -86.391496)
		(width 0.127)
		(layer "B.Cu")
		(net "EXP_SIO_LOAD_OUT")
	)
	(segment
		(start 121.8184 -81.4959)
		(end 121.4882 -81.8261)
		(width 0.127)
		(layer "B.Cu")
		(net "EXP_SIO_LOAD_OUT")
	)
	(segment
		(start 125.52553 -86.391496)
		(end 125.52553 -88.88603)
		(width 0.127)
		(layer "B.Cu")
		(net "EXP_SIO_LOAD_OUT")
	)
	(segment
		(start 125.52553 -88.88603)
		(end 126.0094 -89.3699)
		(width 0.127)
		(layer "B.Cu")
		(net "EXP_SIO_LOAD_OUT")
	)
	(segment
		(start 121.4882 -81.8261)
		(end 121.4882 -82.2452)
		(width 0.127)
		(layer "B.Cu")
		(net "EXP_SIO_LOAD_OUT")
	)
	(segment
		(start 121.4882 -82.2452)
		(end 121.793 -82.55)
		(width 0.127)
		(layer "B.Cu")
		(net "EXP_SIO_LOAD_OUT")
	)
	(segment
		(start 121.000012 -74.000106)
		(end 120.87987 -74.120248)
		(width 0.127)
		(layer "B.Cu")
		(net "EXP_SIO_LOAD_OUT")
	)
	(segment
		(start 120.87987 -74.120248)
		(end 120.87987 -77.57287)
		(width 0.127)
		(layer "B.Cu")
		(net "EXP_SIO_LOAD_OUT")
	)
	(segment
		(start 121.8184 -78.8162)
		(end 121.8184 -81.4959)
		(width 0.127)
		(layer "B.Cu")
		(net "EXP_SIO_LOAD_OUT")
	)
	(segment
		(start 122.6947 -83.0453)
		(end 122.6947 -83.560666)
		(width 0.127)
		(layer "B.Cu")
		(net "EXP_SIO_LOAD_OUT")
	)
	(segment
		(start 121.793 -82.55)
		(end 122.1994 -82.55)
		(width 0.127)
		(layer "B.Cu")
		(net "EXP_SIO_LOAD_OUT")
	)
	(segment
		(start 120.87987 -77.57287)
		(end 121.8184 -78.5114)
		(width 0.127)
		(layer "B.Cu")
		(net "EXP_SIO_LOAD_OUT")
	)
	(segment
		(start 121.8184 -78.5114)
		(end 121.8184 -78.8162)
		(width 0.127)
		(layer "B.Cu")
		(net "EXP_SIO_LOAD_OUT")
	)
	(segment
		(start 122.1994 -82.55)
		(end 122.6947 -83.0453)
		(width 0.127)
		(layer "B.Cu")
		(net "EXP_SIO_LOAD_OUT")
	)
	(segment
		(start 124.500132 -78.500224)
		(end 125.000004 -79.000096)
		(width 0.127)
		(layer "F.Cu")
		(net "EXP_SIO_LOAD_IN")
	)
	(via
		(at 127.0762 -83.351116)
		(size 0.6096)
		(drill 0.3048)
		(layers "F.Cu" "B.Cu")
		(net "EXP_SIO_LOAD_IN")
	)
	(via
		(at 125.000004 -79.000096)
		(size 0.4572)
		(drill 0.2032)
		(layers "F.Cu" "B.Cu")
		(net "EXP_SIO_LOAD_IN")
	)
	(segment
		(start 125.6792 -82.986118)
		(end 125.6792 -81.4324)
		(width 0.127)
		(layer "B.Cu")
		(net "EXP_SIO_LOAD_IN")
	)
	(segment
		(start 127.278384 -83.5533)
		(end 128.6129 -83.5533)
		(width 0.127)
		(layer "B.Cu")
		(net "EXP_SIO_LOAD_IN")
	)
	(segment
		(start 127.0762 -83.351116)
		(end 127.278384 -83.5533)
		(width 0.127)
		(layer "B.Cu")
		(net "EXP_SIO_LOAD_IN")
	)
	(segment
		(start 124.846588 -80.4037)
		(end 124.606304 -80.163416)
		(width 0.127)
		(layer "B.Cu")
		(net "EXP_SIO_LOAD_IN")
	)
	(segment
		(start 126.044198 -83.351116)
		(end 125.6792 -82.986118)
		(width 0.127)
		(layer "B.Cu")
		(net "EXP_SIO_LOAD_IN")
	)
	(segment
		(start 125.49505 -81.24825)
		(end 125.49505 -80.938116)
		(width 0.127)
		(layer "B.Cu")
		(net "EXP_SIO_LOAD_IN")
	)
	(segment
		(start 131.449318 -86.389718)
		(end 131.449318 -86.816184)
		(width 0.127)
		(layer "B.Cu")
		(net "EXP_SIO_LOAD_IN")
	)
	(segment
		(start 128.6129 -83.5533)
		(end 131.449318 -86.389718)
		(width 0.127)
		(layer "B.Cu")
		(net "EXP_SIO_LOAD_IN")
	)
	(segment
		(start 125.6792 -81.4324)
		(end 125.49505 -81.24825)
		(width 0.127)
		(layer "B.Cu")
		(net "EXP_SIO_LOAD_IN")
	)
	(segment
		(start 125.000004 -79.443072)
		(end 125.000004 -79.000096)
		(width 0.127)
		(layer "B.Cu")
		(net "EXP_SIO_LOAD_IN")
	)
	(segment
		(start 124.960634 -80.4037)
		(end 124.846588 -80.4037)
		(width 0.127)
		(layer "B.Cu")
		(net "EXP_SIO_LOAD_IN")
	)
	(segment
		(start 124.606304 -80.163416)
		(end 124.606304 -79.836772)
		(width 0.127)
		(layer "B.Cu")
		(net "EXP_SIO_LOAD_IN")
	)
	(segment
		(start 124.606304 -79.836772)
		(end 125.000004 -79.443072)
		(width 0.127)
		(layer "B.Cu")
		(net "EXP_SIO_LOAD_IN")
	)
	(segment
		(start 125.49505 -80.938116)
		(end 124.960634 -80.4037)
		(width 0.127)
		(layer "B.Cu")
		(net "EXP_SIO_LOAD_IN")
	)
	(segment
		(start 127.0762 -83.351116)
		(end 126.044198 -83.351116)
		(width 0.127)
		(layer "B.Cu")
		(net "EXP_SIO_LOAD_IN")
	)
	(segment
		(start 123.500134 -77.500226)
		(end 124.000006 -78.000098)
		(width 0.127)
		(layer "F.Cu")
		(net "EXP_SIO_D_OUT")
	)
	(via
		(at 124.500132 -78.49997)
		(size 0.6096)
		(drill 0.3048)
		(layers "F.Cu" "B.Cu")
		(net "EXP_SIO_D_OUT")
	)
	(via
		(at 124.000006 -78.000098)
		(size 0.4572)
		(drill 0.2032)
		(layers "F.Cu" "B.Cu")
		(net "EXP_SIO_D_OUT")
	)
	(segment
		(start 125.2093 -81.407)
		(end 125.393704 -81.591404)
		(width 0.127)
		(layer "B.Cu")
		(net "EXP_SIO_D_OUT")
	)
	(segment
		(start 126.061216 -83.871816)
		(end 128.194816 -83.871816)
		(width 0.127)
		(layer "B.Cu")
		(net "EXP_SIO_D_OUT")
	)
	(segment
		(start 124.500132 -79.481172)
		(end 124.352304 -79.629)
		(width 0.127)
		(layer "B.Cu")
		(net "EXP_SIO_D_OUT")
	)
	(segment
		(start 128.194816 -83.871816)
		(end 130.433318 -86.110318)
		(width 0.127)
		(layer "B.Cu")
		(net "EXP_SIO_D_OUT")
	)
	(segment
		(start 124.669804 -81.407)
		(end 125.2093 -81.407)
		(width 0.127)
		(layer "B.Cu")
		(net "EXP_SIO_D_OUT")
	)
	(segment
		(start 130.433318 -86.110318)
		(end 130.433318 -86.816184)
		(width 0.127)
		(layer "B.Cu")
		(net "EXP_SIO_D_OUT")
	)
	(segment
		(start 124.352304 -81.0895)
		(end 124.669804 -81.407)
		(width 0.127)
		(layer "B.Cu")
		(net "EXP_SIO_D_OUT")
	)
	(segment
		(start 125.393704 -81.591404)
		(end 125.393704 -83.204304)
		(width 0.127)
		(layer "B.Cu")
		(net "EXP_SIO_D_OUT")
	)
	(segment
		(start 124.000006 -78.000098)
		(end 124.499878 -78.49997)
		(width 0.127)
		(layer "B.Cu")
		(net "EXP_SIO_D_OUT")
	)
	(segment
		(start 125.393704 -83.204304)
		(end 126.061216 -83.871816)
		(width 0.127)
		(layer "B.Cu")
		(net "EXP_SIO_D_OUT")
	)
	(segment
		(start 124.499878 -78.49997)
		(end 124.500132 -78.49997)
		(width 0.127)
		(layer "B.Cu")
		(net "EXP_SIO_D_OUT")
	)
	(segment
		(start 124.500132 -78.49997)
		(end 124.500132 -79.481172)
		(width 0.127)
		(layer "B.Cu")
		(net "EXP_SIO_D_OUT")
	)
	(segment
		(start 124.352304 -79.629)
		(end 124.352304 -81.0895)
		(width 0.127)
		(layer "B.Cu")
		(net "EXP_SIO_D_OUT")
	)
	(segment
		(start 132.208524 -88.876124)
		(end 132.588 -89.2556)
		(width 0.127)
		(layer "F.Cu")
		(net "EXP_SIO_D_IN")
	)
	(segment
		(start 131.342638 -85.93201)
		(end 128.329944 -82.919316)
		(width 0.127)
		(layer "F.Cu")
		(net "EXP_SIO_D_IN")
	)
	(segment
		(start 128.081024 -82.391504)
		(end 127.500126 -81.810606)
		(width 0.127)
		(layer "F.Cu")
		(net "EXP_SIO_D_IN")
	)
	(segment
		(start 128.329944 -82.919316)
		(end 128.326388 -82.919316)
		(width 0.127)
		(layer "F.Cu")
		(net "EXP_SIO_D_IN")
	)
	(segment
		(start 128.081024 -82.673952)
		(end 128.081024 -82.391504)
		(width 0.127)
		(layer "F.Cu")
		(net "EXP_SIO_D_IN")
	)
	(segment
		(start 132.208524 -86.797896)
		(end 132.208524 -88.876124)
		(width 0.127)
		(layer "F.Cu")
		(net "EXP_SIO_D_IN")
	)
	(segment
		(start 128.326388 -82.919316)
		(end 128.081024 -82.673952)
		(width 0.127)
		(layer "F.Cu")
		(net "EXP_SIO_D_IN")
	)
	(segment
		(start 131.342638 -85.93201)
		(end 132.208524 -86.797896)
		(width 0.127)
		(layer "F.Cu")
		(net "EXP_SIO_D_IN")
	)
	(segment
		(start 127.500126 -81.810606)
		(end 127.500126 -81.500218)
		(width 0.127)
		(layer "F.Cu")
		(net "EXP_SIO_D_IN")
	)
	(via
		(at 131.342638 -85.93201)
		(size 0.6604)
		(drill 0.3302)
		(layers "F.Cu" "B.Cu")
		(net "EXP_SIO_D_IN")
	)
	(segment
		(start 122.500136 -75.50023)
		(end 123.000008 -75.000358)
		(width 0.127)
		(layer "F.Cu")
		(net "EXP_SIO_CLK_OUT")
	)
	(via
		(at 123.000008 -75.000358)
		(size 0.4572)
		(drill 0.2032)
		(layers "F.Cu" "B.Cu")
		(net "EXP_SIO_CLK_OUT")
	)
	(via
		(at 123.035568 -75.864974)
		(size 0.6096)
		(drill 0.3048)
		(layers "F.Cu" "B.Cu")
		(net "EXP_SIO_CLK_OUT")
	)
	(segment
		(start 125.44298 -80.000094)
		(end 125.44298 -77.817472)
		(width 0.127)
		(layer "B.Cu")
		(net "EXP_SIO_CLK_OUT")
	)
	(segment
		(start 123.47829 -76.72324)
		(end 123.035568 -76.280518)
		(width 0.127)
		(layer "B.Cu")
		(net "EXP_SIO_CLK_OUT")
	)
	(segment
		(start 123.78055 -77.53858)
		(end 123.47829 -77.23632)
		(width 0.127)
		(layer "B.Cu")
		(net "EXP_SIO_CLK_OUT")
	)
	(segment
		(start 125.44298 -77.817472)
		(end 125.164088 -77.53858)
		(width 0.127)
		(layer "B.Cu")
		(net "EXP_SIO_CLK_OUT")
	)
	(segment
		(start 123.47829 -77.23632)
		(end 123.47829 -76.72324)
		(width 0.127)
		(layer "B.Cu")
		(net "EXP_SIO_CLK_OUT")
	)
	(segment
		(start 132.466588 -86.670388)
		(end 128.918716 -83.122516)
		(width 0.127)
		(layer "B.Cu")
		(net "EXP_SIO_CLK_OUT")
	)
	(segment
		(start 126.393702 -81.016602)
		(end 126.393702 -80.83677)
		(width 0.127)
		(layer "B.Cu")
		(net "EXP_SIO_CLK_OUT")
	)
	(segment
		(start 123.035568 -76.280518)
		(end 123.035568 -75.864974)
		(width 0.127)
		(layer "B.Cu")
		(net "EXP_SIO_CLK_OUT")
	)
	(segment
		(start 126.163324 -80.606392)
		(end 126.049278 -80.606392)
		(width 0.127)
		(layer "B.Cu")
		(net "EXP_SIO_CLK_OUT")
	)
	(segment
		(start 126.393702 -80.83677)
		(end 126.163324 -80.606392)
		(width 0.127)
		(layer "B.Cu")
		(net "EXP_SIO_CLK_OUT")
	)
	(segment
		(start 132.466588 -86.816184)
		(end 132.466588 -86.670388)
		(width 0.127)
		(layer "B.Cu")
		(net "EXP_SIO_CLK_OUT")
	)
	(segment
		(start 125.164088 -77.53858)
		(end 123.78055 -77.53858)
		(width 0.127)
		(layer "B.Cu")
		(net "EXP_SIO_CLK_OUT")
	)
	(segment
		(start 126.049278 -80.606392)
		(end 125.44298 -80.000094)
		(width 0.127)
		(layer "B.Cu")
		(net "EXP_SIO_CLK_OUT")
	)
	(segment
		(start 127.852424 -83.122516)
		(end 127.1778 -82.447892)
		(width 0.127)
		(layer "B.Cu")
		(net "EXP_SIO_CLK_OUT")
	)
	(segment
		(start 127.1778 -81.8007)
		(end 126.393702 -81.016602)
		(width 0.127)
		(layer "B.Cu")
		(net "EXP_SIO_CLK_OUT")
	)
	(segment
		(start 127.1778 -82.447892)
		(end 127.1778 -81.8007)
		(width 0.127)
		(layer "B.Cu")
		(net "EXP_SIO_CLK_OUT")
	)
	(segment
		(start 128.918716 -83.122516)
		(end 127.852424 -83.122516)
		(width 0.127)
		(layer "B.Cu")
		(net "EXP_SIO_CLK_OUT")
	)
	(segment
		(start 123.035568 -75.035918)
		(end 123.000008 -75.000358)
		(width 0.127)
		(layer "B.Cu")
		(net "EXP_SIO_CLK_OUT")
	)
	(segment
		(start 123.035568 -75.864974)
		(end 123.035568 -75.035918)
		(width 0.127)
		(layer "B.Cu")
		(net "EXP_SIO_CLK_OUT")
	)
	(segment
		(start 121.500138 -74.500232)
		(end 122.00001 -75.000104)
		(width 0.127)
		(layer "F.Cu")
		(net "EXP_SIO_CLK_IN")
	)
	(via
		(at 122.00001 -75.000104)
		(size 0.4572)
		(drill 0.2032)
		(layers "F.Cu" "B.Cu")
		(net "EXP_SIO_CLK_IN")
	)
	(via
		(at 121.40057 -76.455524)
		(size 0.6096)
		(drill 0.3048)
		(layers "F.Cu" "B.Cu")
		(net "EXP_SIO_CLK_IN")
	)
	(segment
		(start 121.912888 -77.47)
		(end 122.026934 -77.47)
		(width 0.127)
		(layer "B.Cu")
		(net "EXP_SIO_CLK_IN")
	)
	(segment
		(start 121.40057 -75.22464)
		(end 121.40057 -76.455524)
		(width 0.127)
		(layer "B.Cu")
		(net "EXP_SIO_CLK_IN")
	)
	(segment
		(start 123.1265 -82.8802)
		(end 123.1265 -83.2739)
		(width 0.127)
		(layer "B.Cu")
		(net "EXP_SIO_CLK_IN")
	)
	(segment
		(start 122.39371 -78.689962)
		(end 122.352308 -78.731364)
		(width 0.127)
		(layer "B.Cu")
		(net "EXP_SIO_CLK_IN")
	)
	(segment
		(start 121.40057 -76.957682)
		(end 121.912888 -77.47)
		(width 0.127)
		(layer "B.Cu")
		(net "EXP_SIO_CLK_IN")
	)
	(segment
		(start 122.026934 -77.47)
		(end 122.39371 -77.836776)
		(width 0.127)
		(layer "B.Cu")
		(net "EXP_SIO_CLK_IN")
	)
	(segment
		(start 122.098308 -81.541366)
		(end 122.5423 -81.985358)
		(width 0.127)
		(layer "B.Cu")
		(net "EXP_SIO_CLK_IN")
	)
	(segment
		(start 122.39371 -77.836776)
		(end 122.39371 -78.689962)
		(width 0.127)
		(layer "B.Cu")
		(net "EXP_SIO_CLK_IN")
	)
	(segment
		(start 122.5423 -81.985358)
		(end 122.5423 -82.296)
		(width 0.127)
		(layer "B.Cu")
		(net "EXP_SIO_CLK_IN")
	)
	(segment
		(start 123.1265 -83.2739)
		(end 126.290324 -86.437724)
		(width 0.127)
		(layer "B.Cu")
		(net "EXP_SIO_CLK_IN")
	)
	(segment
		(start 126.290324 -86.437724)
		(end 126.290324 -86.812374)
		(width 0.127)
		(layer "B.Cu")
		(net "EXP_SIO_CLK_IN")
	)
	(segment
		(start 122.098308 -79.323438)
		(end 122.098308 -81.541366)
		(width 0.127)
		(layer "B.Cu")
		(net "EXP_SIO_CLK_IN")
	)
	(segment
		(start 122.5423 -82.296)
		(end 123.1265 -82.8802)
		(width 0.127)
		(layer "B.Cu")
		(net "EXP_SIO_CLK_IN")
	)
	(segment
		(start 122.00001 -75.000104)
		(end 121.625106 -75.000104)
		(width 0.127)
		(layer "B.Cu")
		(net "EXP_SIO_CLK_IN")
	)
	(segment
		(start 122.352308 -79.069438)
		(end 122.098308 -79.323438)
		(width 0.127)
		(layer "B.Cu")
		(net "EXP_SIO_CLK_IN")
	)
	(segment
		(start 121.625106 -75.000104)
		(end 121.40057 -75.22464)
		(width 0.127)
		(layer "B.Cu")
		(net "EXP_SIO_CLK_IN")
	)
	(segment
		(start 121.40057 -76.455524)
		(end 121.40057 -76.957682)
		(width 0.127)
		(layer "B.Cu")
		(net "EXP_SIO_CLK_IN")
	)
	(segment
		(start 122.352308 -78.731364)
		(end 122.352308 -79.069438)
		(width 0.127)
		(layer "B.Cu")
		(net "EXP_SIO_CLK_IN")
	)
	(segment
		(start 92.323412 -57.500012)
		(end 89.662 -54.8386)
		(width 0.127)
		(layer "F.Cu")
		(net "EXP_REF_CLK_P")
	)
	(segment
		(start 89.157048 -54.8386)
		(end 88.854788 -55.14086)
		(width 0.127)
		(layer "F.Cu")
		(net "EXP_REF_CLK_P")
	)
	(segment
		(start 88.854788 -55.14086)
		(end 88.543638 -55.14086)
		(width 0.127)
		(layer "F.Cu")
		(net "EXP_REF_CLK_P")
	)
	(segment
		(start 89.662 -54.8386)
		(end 89.157048 -54.8386)
		(width 0.127)
		(layer "F.Cu")
		(net "EXP_REF_CLK_P")
	)
	(segment
		(start 87.192104 -55.743094)
		(end 86.806278 -55.743094)
		(width 0.127)
		(layer "F.Cu")
		(net "EXP_REF_CLK_P")
	)
	(segment
		(start 87.794338 -55.14086)
		(end 87.192104 -55.743094)
		(width 0.127)
		(layer "F.Cu")
		(net "EXP_REF_CLK_P")
	)
	(segment
		(start 99.499928 -57.500012)
		(end 92.323412 -57.500012)
		(width 0.127)
		(layer "F.Cu")
		(net "EXP_REF_CLK_P")
	)
	(segment
		(start 88.543638 -55.14086)
		(end 87.794338 -55.14086)
		(width 0.127)
		(layer "F.Cu")
		(net "EXP_REF_CLK_P")
	)
	(segment
		(start 89.060528 -54.3306)
		(end 89.872566 -54.3306)
		(width 0.127)
		(layer "F.Cu")
		(net "EXP_REF_CLK_N")
	)
	(segment
		(start 99.991926 -56.992012)
		(end 100.499926 -57.500012)
		(width 0.127)
		(layer "F.Cu")
		(net "EXP_REF_CLK_N")
	)
	(segment
		(start 88.543638 -54.12486)
		(end 88.854788 -54.12486)
		(width 0.127)
		(layer "F.Cu")
		(net "EXP_REF_CLK_N")
	)
	(segment
		(start 92.533978 -56.992012)
		(end 99.991926 -56.992012)
		(width 0.127)
		(layer "F.Cu")
		(net "EXP_REF_CLK_N")
	)
	(segment
		(start 88.854788 -54.12486)
		(end 89.060528 -54.3306)
		(width 0.127)
		(layer "F.Cu")
		(net "EXP_REF_CLK_N")
	)
	(segment
		(start 89.872566 -54.3306)
		(end 92.533978 -56.992012)
		(width 0.127)
		(layer "F.Cu")
		(net "EXP_REF_CLK_N")
	)
	(segment
		(start 109.499908 -78.500224)
		(end 109.000036 -79.000096)
		(width 0.127)
		(layer "F.Cu")
		(net "EXP_IDDT")
	)
	(via
		(at 110.499906 -80.499966)
		(size 0.6096)
		(drill 0.3048)
		(layers "F.Cu" "B.Cu")
		(net "EXP_IDDT")
	)
	(via
		(at 109.000036 -79.000096)
		(size 0.4572)
		(drill 0.2032)
		(layers "F.Cu" "B.Cu")
		(net "EXP_IDDT")
	)
	(segment
		(start 110.971076 -85.850984)
		(end 111.061754 -85.760306)
		(width 0.127)
		(layer "B.Cu")
		(net "EXP_IDDT")
	)
	(segment
		(start 109.390688 -79.390748)
		(end 109.833664 -79.390748)
		(width 0.127)
		(layer "B.Cu")
		(net "EXP_IDDT")
	)
	(segment
		(start 110.9853 -85.10524)
		(end 110.9853 -83.62442)
		(width 0.127)
		(layer "B.Cu")
		(net "EXP_IDDT")
	)
	(segment
		(start 109.833664 -79.390748)
		(end 109.836712 -79.393796)
		(width 0.127)
		(layer "B.Cu")
		(net "EXP_IDDT")
	)
	(segment
		(start 110.971076 -83.610196)
		(end 110.971076 -81.528412)
		(width 0.127)
		(layer "B.Cu")
		(net "EXP_IDDT")
	)
	(segment
		(start 110.499906 -81.057242)
		(end 110.499906 -80.499966)
		(width 0.127)
		(layer "B.Cu")
		(net "EXP_IDDT")
	)
	(segment
		(start 109.836712 -79.393796)
		(end 109.994446 -79.393796)
		(width 0.127)
		(layer "B.Cu")
		(net "EXP_IDDT")
	)
	(segment
		(start 111.061754 -85.181694)
		(end 110.9853 -85.10524)
		(width 0.127)
		(layer "B.Cu")
		(net "EXP_IDDT")
	)
	(segment
		(start 110.971076 -89.200482)
		(end 110.971076 -85.850984)
		(width 0.127)
		(layer "B.Cu")
		(net "EXP_IDDT")
	)
	(segment
		(start 109.000036 -79.000096)
		(end 109.390688 -79.390748)
		(width 0.127)
		(layer "B.Cu")
		(net "EXP_IDDT")
	)
	(segment
		(start 110.930944 -89.240614)
		(end 110.971076 -89.200482)
		(width 0.127)
		(layer "B.Cu")
		(net "EXP_IDDT")
	)
	(segment
		(start 110.9853 -83.62442)
		(end 110.971076 -83.610196)
		(width 0.127)
		(layer "B.Cu")
		(net "EXP_IDDT")
	)
	(segment
		(start 109.994446 -79.393796)
		(end 110.499906 -79.899256)
		(width 0.127)
		(layer "B.Cu")
		(net "EXP_IDDT")
	)
	(segment
		(start 110.499906 -79.899256)
		(end 110.499906 -80.499966)
		(width 0.127)
		(layer "B.Cu")
		(net "EXP_IDDT")
	)
	(segment
		(start 111.061754 -85.760306)
		(end 111.061754 -85.181694)
		(width 0.127)
		(layer "B.Cu")
		(net "EXP_IDDT")
	)
	(segment
		(start 110.971076 -81.528412)
		(end 110.499906 -81.057242)
		(width 0.127)
		(layer "B.Cu")
		(net "EXP_IDDT")
	)
	(segment
		(start 120.50014 -72.500236)
		(end 120.000268 -73.000108)
		(width 0.127)
		(layer "F.Cu")
		(net "EXP_I2C_SDA9")
	)
	(via
		(at 120.000268 -73.000108)
		(size 0.4572)
		(drill 0.2032)
		(layers "F.Cu" "B.Cu")
		(net "EXP_I2C_SDA9")
	)
	(via
		(at 141.4272 -86.1822)
		(size 0.508)
		(drill 0.254)
		(layers "F.Cu" "B.Cu")
		(net "EXP_I2C_SDA9")
	)
	(segment
		(start 141.732 -87.3379)
		(end 141.605 -87.2109)
		(width 0.127)
		(layer "B.Cu")
		(net "EXP_I2C_SDA9")
	)
	(segment
		(start 141.4272 -86.1822)
		(end 141.4272 -87.0331)
		(width 0.127)
		(layer "B.Cu")
		(net "EXP_I2C_SDA9")
	)
	(segment
		(start 141.732 -88.4555)
		(end 141.732 -87.3379)
		(width 0.127)
		(layer "B.Cu")
		(net "EXP_I2C_SDA9")
	)
	(segment
		(start 141.4272 -87.0331)
		(end 141.605 -87.2109)
		(width 0.127)
		(layer "B.Cu")
		(net "EXP_I2C_SDA9")
	)
	(segment
		(start 140.665708 -85.420708)
		(end 141.4272 -86.1822)
		(width 0.127)
		(layer "In2.Cu")
		(net "EXP_I2C_SDA9")
	)
	(segment
		(start 120.000268 -73.000108)
		(end 120.393968 -72.606408)
		(width 0.127)
		(layer "In2.Cu")
		(net "EXP_I2C_SDA9")
	)
	(segment
		(start 131.5085 -84.426298)
		(end 132.50291 -85.420708)
		(width 0.127)
		(layer "In2.Cu")
		(net "EXP_I2C_SDA9")
	)
	(segment
		(start 127.14351 -73.547224)
		(end 127.606298 -74.010012)
		(width 0.127)
		(layer "In2.Cu")
		(net "EXP_I2C_SDA9")
	)
	(segment
		(start 130.56235 -77.11948)
		(end 130.56235 -82.54746)
		(width 0.127)
		(layer "In2.Cu")
		(net "EXP_I2C_SDA9")
	)
	(segment
		(start 131.5085 -83.49361)
		(end 131.5085 -84.426298)
		(width 0.127)
		(layer "In2.Cu")
		(net "EXP_I2C_SDA9")
	)
	(segment
		(start 132.50291 -85.420708)
		(end 140.665708 -85.420708)
		(width 0.127)
		(layer "In2.Cu")
		(net "EXP_I2C_SDA9")
	)
	(segment
		(start 120.393968 -72.606408)
		(end 125.209808 -72.606408)
		(width 0.127)
		(layer "In2.Cu")
		(net "EXP_I2C_SDA9")
	)
	(segment
		(start 125.4506 -73.166224)
		(end 125.8316 -73.547224)
		(width 0.127)
		(layer "In2.Cu")
		(net "EXP_I2C_SDA9")
	)
	(segment
		(start 128.16332 -74.606404)
		(end 128.393698 -74.836782)
		(width 0.127)
		(layer "In2.Cu")
		(net "EXP_I2C_SDA9")
	)
	(segment
		(start 130.56235 -82.54746)
		(end 131.5085 -83.49361)
		(width 0.127)
		(layer "In2.Cu")
		(net "EXP_I2C_SDA9")
	)
	(segment
		(start 128.393698 -74.950828)
		(end 130.56235 -77.11948)
		(width 0.127)
		(layer "In2.Cu")
		(net "EXP_I2C_SDA9")
	)
	(segment
		(start 127.606298 -74.163428)
		(end 128.049274 -74.606404)
		(width 0.127)
		(layer "In2.Cu")
		(net "EXP_I2C_SDA9")
	)
	(segment
		(start 125.8316 -73.547224)
		(end 127.14351 -73.547224)
		(width 0.127)
		(layer "In2.Cu")
		(net "EXP_I2C_SDA9")
	)
	(segment
		(start 127.606298 -74.010012)
		(end 127.606298 -74.163428)
		(width 0.127)
		(layer "In2.Cu")
		(net "EXP_I2C_SDA9")
	)
	(segment
		(start 128.049274 -74.606404)
		(end 128.16332 -74.606404)
		(width 0.127)
		(layer "In2.Cu")
		(net "EXP_I2C_SDA9")
	)
	(segment
		(start 125.209808 -72.606408)
		(end 125.4506 -72.8472)
		(width 0.127)
		(layer "In2.Cu")
		(net "EXP_I2C_SDA9")
	)
	(segment
		(start 128.393698 -74.836782)
		(end 128.393698 -74.950828)
		(width 0.127)
		(layer "In2.Cu")
		(net "EXP_I2C_SDA9")
	)
	(segment
		(start 125.4506 -72.8472)
		(end 125.4506 -73.166224)
		(width 0.127)
		(layer "In2.Cu")
		(net "EXP_I2C_SDA9")
	)
	(segment
		(start 127.500126 -80.50022)
		(end 127.999998 -81.000092)
		(width 0.127)
		(layer "F.Cu")
		(net "EXP_I2C_SDA11")
	)
	(via
		(at 127.999998 -81.000092)
		(size 0.4572)
		(drill 0.2032)
		(layers "F.Cu" "B.Cu")
		(net "EXP_I2C_SDA11")
	)
	(segment
		(start 133.140196 -86.073996)
		(end 132.69595 -86.073996)
		(width 0.127)
		(layer "B.Cu")
		(net "EXP_I2C_SDA11")
	)
	(segment
		(start 133.482588 -86.816184)
		(end 133.482588 -86.416388)
		(width 0.127)
		(layer "B.Cu")
		(net "EXP_I2C_SDA11")
	)
	(segment
		(start 131.056888 -84.473288)
		(end 127.999998 -81.416398)
		(width 0.127)
		(layer "B.Cu")
		(net "EXP_I2C_SDA11")
	)
	(segment
		(start 131.113276 -84.491322)
		(end 131.113276 -84.473288)
		(width 0.127)
		(layer "B.Cu")
		(net "EXP_I2C_SDA11")
	)
	(segment
		(start 132.69595 -86.073996)
		(end 131.113276 -84.491322)
		(width 0.127)
		(layer "B.Cu")
		(net "EXP_I2C_SDA11")
	)
	(segment
		(start 127.999998 -81.416398)
		(end 127.999998 -81.000092)
		(width 0.127)
		(layer "B.Cu")
		(net "EXP_I2C_SDA11")
	)
	(segment
		(start 133.482588 -86.416388)
		(end 133.140196 -86.073996)
		(width 0.127)
		(layer "B.Cu")
		(net "EXP_I2C_SDA11")
	)
	(segment
		(start 131.113276 -84.473288)
		(end 131.056888 -84.473288)
		(width 0.127)
		(layer "B.Cu")
		(net "EXP_I2C_SDA11")
	)
	(segment
		(start 129.786126 -83.057746)
		(end 131.691126 -84.962746)
		(width 0.127)
		(layer "F.Cu")
		(net "EXP_I2C_SDA10")
	)
	(segment
		(start 129.081022 -82.673952)
		(end 129.326386 -82.919316)
		(width 0.127)
		(layer "F.Cu")
		(net "EXP_I2C_SDA10")
	)
	(segment
		(start 129.573782 -82.919316)
		(end 129.712212 -83.057746)
		(width 0.127)
		(layer "F.Cu")
		(net "EXP_I2C_SDA10")
	)
	(segment
		(start 129.081022 -82.394298)
		(end 129.081022 -82.673952)
		(width 0.127)
		(layer "F.Cu")
		(net "EXP_I2C_SDA10")
	)
	(segment
		(start 134.8105 -87.736934)
		(end 134.8105 -87.6935)
		(width 0.127)
		(layer "F.Cu")
		(net "EXP_I2C_SDA10")
	)
	(segment
		(start 131.691126 -84.962746)
		(end 131.887468 -84.962746)
		(width 0.127)
		(layer "F.Cu")
		(net "EXP_I2C_SDA10")
	)
	(segment
		(start 129.326386 -82.919316)
		(end 129.573782 -82.919316)
		(width 0.127)
		(layer "F.Cu")
		(net "EXP_I2C_SDA10")
	)
	(segment
		(start 128.500124 -81.500218)
		(end 128.500124 -81.8134)
		(width 0.127)
		(layer "F.Cu")
		(net "EXP_I2C_SDA10")
	)
	(segment
		(start 134.05231 -86.509352)
		(end 134.341108 -86.79815)
		(width 0.127)
		(layer "F.Cu")
		(net "EXP_I2C_SDA10")
	)
	(segment
		(start 134.8105 -87.6935)
		(end 134.341108 -87.224108)
		(width 0.127)
		(layer "F.Cu")
		(net "EXP_I2C_SDA10")
	)
	(segment
		(start 129.712212 -83.057746)
		(end 129.786126 -83.057746)
		(width 0.127)
		(layer "F.Cu")
		(net "EXP_I2C_SDA10")
	)
	(segment
		(start 134.341108 -87.224108)
		(end 134.341108 -86.79815)
		(width 0.127)
		(layer "F.Cu")
		(net "EXP_I2C_SDA10")
	)
	(segment
		(start 131.887468 -84.962746)
		(end 133.434074 -86.509352)
		(width 0.127)
		(layer "F.Cu")
		(net "EXP_I2C_SDA10")
	)
	(segment
		(start 128.500124 -81.8134)
		(end 129.081022 -82.394298)
		(width 0.127)
		(layer "F.Cu")
		(net "EXP_I2C_SDA10")
	)
	(segment
		(start 135.355076 -88.28151)
		(end 134.8105 -87.736934)
		(width 0.127)
		(layer "F.Cu")
		(net "EXP_I2C_SDA10")
	)
	(segment
		(start 133.434074 -86.509352)
		(end 134.05231 -86.509352)
		(width 0.127)
		(layer "F.Cu")
		(net "EXP_I2C_SDA10")
	)
	(segment
		(start 132.677408 -85.03412)
		(end 133.64464 -86.001352)
		(width 0.127)
		(layer "F.Cu")
		(net "EXP_I2C_SCL9")
	)
	(segment
		(start 139.314682 -87.44204)
		(end 140.2588 -86.497922)
		(width 0.127)
		(layer "F.Cu")
		(net "EXP_I2C_SCL9")
	)
	(segment
		(start 134.316724 -86.001352)
		(end 135.0899 -86.774528)
		(width 0.127)
		(layer "F.Cu")
		(net "EXP_I2C_SCL9")
	)
	(segment
		(start 135.466582 -87.44204)
		(end 139.314682 -87.44204)
		(width 0.127)
		(layer "F.Cu")
		(net "EXP_I2C_SCL9")
	)
	(segment
		(start 140.2588 -86.497922)
		(end 140.2588 -86.1822)
		(width 0.127)
		(layer "F.Cu")
		(net "EXP_I2C_SCL9")
	)
	(segment
		(start 135.0899 -87.065358)
		(end 135.466582 -87.44204)
		(width 0.127)
		(layer "F.Cu")
		(net "EXP_I2C_SCL9")
	)
	(segment
		(start 129.500122 -82.500216)
		(end 129.85877 -82.500216)
		(width 0.127)
		(layer "F.Cu")
		(net "EXP_I2C_SCL9")
	)
	(segment
		(start 132.392674 -85.03412)
		(end 132.677408 -85.03412)
		(width 0.127)
		(layer "F.Cu")
		(net "EXP_I2C_SCL9")
	)
	(segment
		(start 135.0899 -86.774528)
		(end 135.0899 -87.065358)
		(width 0.127)
		(layer "F.Cu")
		(net "EXP_I2C_SCL9")
	)
	(segment
		(start 133.64464 -86.001352)
		(end 134.316724 -86.001352)
		(width 0.127)
		(layer "F.Cu")
		(net "EXP_I2C_SCL9")
	)
	(segment
		(start 129.85877 -82.500216)
		(end 132.392674 -85.03412)
		(width 0.127)
		(layer "F.Cu")
		(net "EXP_I2C_SCL9")
	)
	(via
		(at 140.2588 -86.1822)
		(size 0.508)
		(drill 0.254)
		(layers "F.Cu" "B.Cu")
		(net "EXP_I2C_SCL9")
	)
	(segment
		(start 140.716 -88.4555)
		(end 140.716 -87.6808)
		(width 0.127)
		(layer "B.Cu")
		(net "EXP_I2C_SCL9")
	)
	(segment
		(start 140.716 -87.6808)
		(end 140.2334 -87.1982)
		(width 0.127)
		(layer "B.Cu")
		(net "EXP_I2C_SCL9")
	)
	(segment
		(start 140.2588 -87.1728)
		(end 140.2334 -87.1982)
		(width 0.127)
		(layer "B.Cu")
		(net "EXP_I2C_SCL9")
	)
	(segment
		(start 140.2588 -86.1822)
		(end 140.2588 -87.1728)
		(width 0.127)
		(layer "B.Cu")
		(net "EXP_I2C_SCL9")
	)
	(segment
		(start 127.500126 -79.500222)
		(end 127.000254 -80.000094)
		(width 0.127)
		(layer "F.Cu")
		(net "EXP_I2C_SCL11")
	)
	(via
		(at 127.000254 -80.000094)
		(size 0.4572)
		(drill 0.2032)
		(layers "F.Cu" "B.Cu")
		(net "EXP_I2C_SCL11")
	)
	(segment
		(start 133.223 -85.217)
		(end 133.3754 -85.217)
		(width 0.127)
		(layer "B.Cu")
		(net "EXP_I2C_SCL11")
	)
	(segment
		(start 127.43688 -80.43672)
		(end 128.06172 -80.43672)
		(width 0.127)
		(layer "B.Cu")
		(net "EXP_I2C_SCL11")
	)
	(segment
		(start 128.5367 -80.9117)
		(end 128.5367 -81.4197)
		(width 0.127)
		(layer "B.Cu")
		(net "EXP_I2C_SCL11")
	)
	(segment
		(start 131.81203 -84.352892)
		(end 131.81203 -84.56803)
		(width 0.127)
		(layer "B.Cu")
		(net "EXP_I2C_SCL11")
	)
	(segment
		(start 131.279138 -83.82)
		(end 131.81203 -84.352892)
		(width 0.127)
		(layer "B.Cu")
		(net "EXP_I2C_SCL11")
	)
	(segment
		(start 128.06172 -80.43672)
		(end 128.5367 -80.9117)
		(width 0.127)
		(layer "B.Cu")
		(net "EXP_I2C_SCL11")
	)
	(segment
		(start 132.461 -85.217)
		(end 133.223 -85.217)
		(width 0.127)
		(layer "B.Cu")
		(net "EXP_I2C_SCL11")
	)
	(segment
		(start 127.000254 -80.000094)
		(end 127.43688 -80.43672)
		(width 0.127)
		(layer "B.Cu")
		(net "EXP_I2C_SCL11")
	)
	(segment
		(start 134.523988 -86.365588)
		(end 134.523988 -86.816184)
		(width 0.127)
		(layer "B.Cu")
		(net "EXP_I2C_SCL11")
	)
	(segment
		(start 131.81203 -84.56803)
		(end 132.461 -85.217)
		(width 0.127)
		(layer "B.Cu")
		(net "EXP_I2C_SCL11")
	)
	(segment
		(start 133.3754 -85.217)
		(end 134.523988 -86.365588)
		(width 0.127)
		(layer "B.Cu")
		(net "EXP_I2C_SCL11")
	)
	(segment
		(start 128.5367 -81.4197)
		(end 130.937 -83.82)
		(width 0.127)
		(layer "B.Cu")
		(net "EXP_I2C_SCL11")
	)
	(segment
		(start 130.937 -83.82)
		(end 131.279138 -83.82)
		(width 0.127)
		(layer "B.Cu")
		(net "EXP_I2C_SCL11")
	)
	(segment
		(start 129.311654 -83.311746)
		(end 128.500124 -82.500216)
		(width 0.127)
		(layer "F.Cu")
		(net "EXP_I2C_SCL10")
	)
	(segment
		(start 129.517648 -83.311746)
		(end 129.311654 -83.311746)
		(width 0.127)
		(layer "F.Cu")
		(net "EXP_I2C_SCL10")
	)
	(segment
		(start 132.994908 -87.827866)
		(end 132.994908 -86.789006)
		(width 0.127)
		(layer "F.Cu")
		(net "EXP_I2C_SCL10")
	)
	(segment
		(start 132.994908 -86.789006)
		(end 129.517648 -83.311746)
		(width 0.127)
		(layer "F.Cu")
		(net "EXP_I2C_SCL10")
	)
	(segment
		(start 132.994908 -87.827866)
		(end 133.448552 -88.28151)
		(width 0.127)
		(layer "F.Cu")
		(net "EXP_I2C_SCL10")
	)
	(segment
		(start 133.448552 -88.28151)
		(end 134.339076 -88.28151)
		(width 0.127)
		(layer "F.Cu")
		(net "EXP_I2C_SCL10")
	)
	(segment
		(start 79.6671 -76.1238)
		(end 80.17383 -76.63053)
		(width 0.127)
		(layer "F.Cu")
		(net "EXP_HW_LED_R")
	)
	(segment
		(start 80.17383 -76.63053)
		(end 80.888586 -76.63053)
		(width 0.127)
		(layer "F.Cu")
		(net "EXP_HW_LED_R")
	)
	(segment
		(start 79.9592 -75.3491)
		(end 79.6671 -75.6412)
		(width 0.127)
		(layer "F.Cu")
		(net "EXP_HW_LED_R")
	)
	(segment
		(start 80.7847 -75.3491)
		(end 79.9592 -75.3491)
		(width 0.127)
		(layer "F.Cu")
		(net "EXP_HW_LED_R")
	)
	(segment
		(start 79.6671 -75.6412)
		(end 79.6671 -75.9079)
		(width 0.127)
		(layer "F.Cu")
		(net "EXP_HW_LED_R")
	)
	(segment
		(start 79.6671 -75.9079)
		(end 79.6671 -76.1238)
		(width 0.127)
		(layer "F.Cu")
		(net "EXP_HW_LED_R")
	)
	(via
		(at 79.6671 -75.9079)
		(size 0.6604)
		(drill 0.3302)
		(layers "F.Cu" "B.Cu")
		(net "EXP_HW_LED_R")
	)
	(segment
		(start 82.412586 -76.63053)
		(end 82.412586 -75.535282)
		(width 0.127)
		(layer "F.Cu")
		(net "EXP_HW_LED_D")
	)
	(segment
		(start 86.092538 -74.747882)
		(end 86.4235 -74.41692)
		(width 0.127)
		(layer "F.Cu")
		(net "EXP_HW_LED_D")
	)
	(segment
		(start 83.199986 -74.747882)
		(end 86.092538 -74.747882)
		(width 0.127)
		(layer "F.Cu")
		(net "EXP_HW_LED_D")
	)
	(segment
		(start 82.705194 -75.242674)
		(end 83.199986 -74.747882)
		(width 0.127)
		(layer "F.Cu")
		(net "EXP_HW_LED_D")
	)
	(segment
		(start 82.412586 -75.535282)
		(end 82.705194 -75.242674)
		(width 0.127)
		(layer "F.Cu")
		(net "EXP_HW_LED_D")
	)
	(via
		(at 82.705194 -75.242674)
		(size 0.6604)
		(drill 0.3302)
		(layers "F.Cu" "B.Cu")
		(net "EXP_HW_LED_D")
	)
	(segment
		(start 118.500144 -76.500228)
		(end 119.000016 -76.000356)
		(width 0.127)
		(layer "F.Cu")
		(net "EXP_GPIO1")
	)
	(via
		(at 119.000016 -76.000356)
		(size 0.4572)
		(drill 0.2032)
		(layers "F.Cu" "B.Cu")
		(net "EXP_GPIO1")
	)
	(segment
		(start 118.49989 -77.499972)
		(end 118.49989 -76.500482)
		(width 0.127)
		(layer "B.Cu")
		(net "EXP_GPIO1")
	)
	(segment
		(start 118.49989 -76.500482)
		(end 119.000016 -76.000356)
		(width 0.127)
		(layer "B.Cu")
		(net "EXP_GPIO1")
	)
	(segment
		(start 17.368012 -79.990188)
		(end 17.5768 -79.7814)
		(width 0.127)
		(layer "F.Cu")
		(net "EXP_EEPROM_WP")
	)
	(segment
		(start 17.6022 -79.756)
		(end 17.5768 -79.7814)
		(width 0.127)
		(layer "F.Cu")
		(net "EXP_EEPROM_WP")
	)
	(segment
		(start 15.850616 -79.990188)
		(end 17.368012 -79.990188)
		(width 0.127)
		(layer "F.Cu")
		(net "EXP_EEPROM_WP")
	)
	(segment
		(start 18.7325 -79.756)
		(end 17.6022 -79.756)
		(width 0.127)
		(layer "F.Cu")
		(net "EXP_EEPROM_WP")
	)
	(via
		(at 17.5768 -79.7814)
		(size 0.6604)
		(drill 0.3302)
		(layers "F.Cu" "B.Cu")
		(net "EXP_EEPROM_WP")
	)
	(segment
		(start 17.1704 -77.1906)
		(end 17.6276 -77.1906)
		(width 0.127)
		(layer "F.Cu")
		(net "EXP_EEPROM_SDA")
	)
	(segment
		(start 15.850616 -77.450188)
		(end 16.910812 -77.450188)
		(width 0.127)
		(layer "F.Cu")
		(net "EXP_EEPROM_SDA")
	)
	(segment
		(start 16.910812 -77.450188)
		(end 17.1704 -77.1906)
		(width 0.127)
		(layer "F.Cu")
		(net "EXP_EEPROM_SDA")
	)
	(segment
		(start 18.7833 -77.343)
		(end 18.161 -77.343)
		(width 0.127)
		(layer "F.Cu")
		(net "EXP_EEPROM_SDA")
	)
	(segment
		(start 18.0086 -77.1906)
		(end 17.6276 -77.1906)
		(width 0.127)
		(layer "F.Cu")
		(net "EXP_EEPROM_SDA")
	)
	(segment
		(start 18.161 -77.343)
		(end 18.0086 -77.1906)
		(width 0.127)
		(layer "F.Cu")
		(net "EXP_EEPROM_SDA")
	)
	(via
		(at 17.6276 -77.1906)
		(size 0.6604)
		(drill 0.3302)
		(layers "F.Cu" "B.Cu")
		(net "EXP_EEPROM_SDA")
	)
	(segment
		(start 17.394428 -78.720188)
		(end 17.603216 -78.5114)
		(width 0.127)
		(layer "F.Cu")
		(net "EXP_EEPROM_SCL")
	)
	(segment
		(start 18.0594 -78.5114)
		(end 17.603216 -78.5114)
		(width 0.127)
		(layer "F.Cu")
		(net "EXP_EEPROM_SCL")
	)
	(segment
		(start 15.850616 -78.720188)
		(end 17.394428 -78.720188)
		(width 0.127)
		(layer "F.Cu")
		(net "EXP_EEPROM_SCL")
	)
	(segment
		(start 18.7833 -78.613)
		(end 18.161 -78.613)
		(width 0.127)
		(layer "F.Cu")
		(net "EXP_EEPROM_SCL")
	)
	(segment
		(start 18.161 -78.613)
		(end 18.0594 -78.5114)
		(width 0.127)
		(layer "F.Cu")
		(net "EXP_EEPROM_SCL")
	)
	(via
		(at 17.603216 -78.5114)
		(size 0.6604)
		(drill 0.3302)
		(layers "F.Cu" "B.Cu")
		(net "EXP_EEPROM_SCL")
	)
	(segment
		(start 10.770616 -78.720188)
		(end 9.72185 -78.720188)
		(width 0.127)
		(layer "F.Cu")
		(net "EXP_EEPROM_A2")
	)
	(segment
		(start 7.9756 -77.5335)
		(end 8.535162 -77.5335)
		(width 0.127)
		(layer "F.Cu")
		(net "EXP_EEPROM_A2")
	)
	(segment
		(start 8.535162 -77.5335)
		(end 9.123172 -78.12151)
		(width 0.127)
		(layer "F.Cu")
		(net "EXP_EEPROM_A2")
	)
	(segment
		(start 9.72185 -78.720188)
		(end 9.123172 -78.12151)
		(width 0.127)
		(layer "F.Cu")
		(net "EXP_EEPROM_A2")
	)
	(segment
		(start 6.9088 -77.5335)
		(end 7.9756 -77.5335)
		(width 0.127)
		(layer "F.Cu")
		(net "EXP_EEPROM_A2")
	)
	(via
		(at 9.123172 -78.12151)
		(size 0.6604)
		(drill 0.3302)
		(layers "F.Cu" "B.Cu")
		(net "EXP_EEPROM_A2")
	)
	(segment
		(start 7.8105 -78.613)
		(end 7.8105 -79.756)
		(width 0.127)
		(layer "F.Cu")
		(net "EXP_EEPROM_A1")
	)
	(segment
		(start 7.8105 -79.756)
		(end 9.017 -79.756)
		(width 0.127)
		(layer "F.Cu")
		(net "EXP_EEPROM_A1")
	)
	(segment
		(start 10.770616 -79.990188)
		(end 9.327388 -79.990188)
		(width 0.127)
		(layer "F.Cu")
		(net "EXP_EEPROM_A1")
	)
	(segment
		(start 9.327388 -79.990188)
		(end 9.0932 -79.756)
		(width 0.127)
		(layer "F.Cu")
		(net "EXP_EEPROM_A1")
	)
	(segment
		(start 9.0932 -79.756)
		(end 9.017 -79.756)
		(width 0.127)
		(layer "F.Cu")
		(net "EXP_EEPROM_A1")
	)
	(via
		(at 9.017 -79.756)
		(size 0.6604)
		(drill 0.3302)
		(layers "F.Cu" "B.Cu")
		(net "EXP_EEPROM_A1")
	)
	(segment
		(start 9.225788 -81.260188)
		(end 9.017 -81.0514)
		(width 0.127)
		(layer "F.Cu")
		(net "EXP_EEPROM_A0")
	)
	(segment
		(start 8.8646 -80.899)
		(end 9.017 -81.0514)
		(width 0.127)
		(layer "F.Cu")
		(net "EXP_EEPROM_A0")
	)
	(segment
		(start 7.8105 -82.042)
		(end 7.8105 -80.899)
		(width 0.127)
		(layer "F.Cu")
		(net "EXP_EEPROM_A0")
	)
	(segment
		(start 10.770616 -81.260188)
		(end 9.225788 -81.260188)
		(width 0.127)
		(layer "F.Cu")
		(net "EXP_EEPROM_A0")
	)
	(segment
		(start 7.8105 -80.899)
		(end 8.8646 -80.899)
		(width 0.127)
		(layer "F.Cu")
		(net "EXP_EEPROM_A0")
	)
	(via
		(at 9.017 -81.0514)
		(size 0.6604)
		(drill 0.3302)
		(layers "F.Cu" "B.Cu")
		(net "EXP_EEPROM_A0")
	)
	(segment
		(start 109.499908 -79.500222)
		(end 109.000036 -80.000094)
		(width 0.127)
		(layer "F.Cu")
		(net "EXP_CPU_MODE_1")
	)
	(via
		(at 109.000036 -80.000094)
		(size 0.4572)
		(drill 0.2032)
		(layers "F.Cu" "B.Cu")
		(net "EXP_CPU_MODE_1")
	)
	(via
		(at 108.49991 -80.499966)
		(size 0.6096)
		(drill 0.3048)
		(layers "F.Cu" "B.Cu")
		(net "EXP_CPU_MODE_1")
	)
	(segment
		(start 108.585 -83.9851)
		(end 108.585 -83.60791)
		(width 0.127)
		(layer "B.Cu")
		(net "EXP_CPU_MODE_1")
	)
	(segment
		(start 108.500164 -80.499966)
		(end 109.000036 -80.000094)
		(width 0.127)
		(layer "B.Cu")
		(net "EXP_CPU_MODE_1")
	)
	(segment
		(start 108.49991 -81.388458)
		(end 108.49991 -80.499966)
		(width 0.127)
		(layer "B.Cu")
		(net "EXP_CPU_MODE_1")
	)
	(segment
		(start 108.585 -83.60791)
		(end 108.769658 -83.423252)
		(width 0.127)
		(layer "B.Cu")
		(net "EXP_CPU_MODE_1")
	)
	(segment
		(start 108.769658 -83.423252)
		(end 108.769658 -81.658206)
		(width 0.127)
		(layer "B.Cu")
		(net "EXP_CPU_MODE_1")
	)
	(segment
		(start 108.769658 -81.658206)
		(end 108.49991 -81.388458)
		(width 0.127)
		(layer "B.Cu")
		(net "EXP_CPU_MODE_1")
	)
	(segment
		(start 108.49991 -80.499966)
		(end 108.500164 -80.499966)
		(width 0.127)
		(layer "B.Cu")
		(net "EXP_CPU_MODE_1")
	)
	(segment
		(start 97.6884 -72.5424)
		(end 97.2566 -72.1106)
		(width 0.127)
		(layer "F.Cu")
		(net "EXP_CPU_MODE_0")
	)
	(segment
		(start 95.885 -72.1106)
		(end 94.6277 -72.1106)
		(width 0.127)
		(layer "F.Cu")
		(net "EXP_CPU_MODE_0")
	)
	(segment
		(start 110.499906 -73.500234)
		(end 110.000034 -74.000106)
		(width 0.127)
		(layer "F.Cu")
		(net "EXP_CPU_MODE_0")
	)
	(segment
		(start 97.2566 -72.1106)
		(end 95.885 -72.1106)
		(width 0.127)
		(layer "F.Cu")
		(net "EXP_CPU_MODE_0")
	)
	(via
		(at 97.6884 -72.5424)
		(size 0.508)
		(drill 0.254)
		(layers "F.Cu" "B.Cu")
		(net "EXP_CPU_MODE_0")
	)
	(via
		(at 95.885 -72.1106)
		(size 0.6604)
		(drill 0.3302)
		(layers "F.Cu" "B.Cu")
		(net "EXP_CPU_MODE_0")
	)
	(via
		(at 110.000034 -74.000106)
		(size 0.4572)
		(drill 0.2032)
		(layers "F.Cu" "B.Cu")
		(net "EXP_CPU_MODE_0")
	)
	(segment
		(start 106.985308 -72.5424)
		(end 107.887262 -73.444354)
		(width 0.127)
		(layer "In5.Cu")
		(net "EXP_CPU_MODE_0")
	)
	(segment
		(start 109.001306 -73.444354)
		(end 109.557058 -74.000106)
		(width 0.127)
		(layer "In5.Cu")
		(net "EXP_CPU_MODE_0")
	)
	(segment
		(start 109.557058 -74.000106)
		(end 110.000034 -74.000106)
		(width 0.127)
		(layer "In5.Cu")
		(net "EXP_CPU_MODE_0")
	)
	(segment
		(start 97.6884 -72.5424)
		(end 106.985308 -72.5424)
		(width 0.127)
		(layer "In5.Cu")
		(net "EXP_CPU_MODE_0")
	)
	(segment
		(start 107.887262 -73.444354)
		(end 109.001306 -73.444354)
		(width 0.127)
		(layer "In5.Cu")
		(net "EXP_CPU_MODE_0")
	)
	(segment
		(start 96.139 -77.851)
		(end 96.620584 -77.851)
		(width 0.127)
		(layer "F.Cu")
		(net "EXP_CLK_SEL1")
	)
	(segment
		(start 94.1705 -77.0128)
		(end 93.0275 -77.0128)
		(width 0.127)
		(layer "F.Cu")
		(net "EXP_CLK_SEL1")
	)
	(segment
		(start 95.0087 -77.851)
		(end 96.139 -77.851)
		(width 0.127)
		(layer "F.Cu")
		(net "EXP_CLK_SEL1")
	)
	(segment
		(start 110.499906 -75.50023)
		(end 110.000034 -76.000102)
		(width 0.127)
		(layer "F.Cu")
		(net "EXP_CLK_SEL1")
	)
	(segment
		(start 94.1705 -77.0128)
		(end 95.0087 -77.851)
		(width 0.127)
		(layer "F.Cu")
		(net "EXP_CLK_SEL1")
	)
	(segment
		(start 96.620584 -77.851)
		(end 96.874584 -77.597)
		(width 0.127)
		(layer "F.Cu")
		(net "EXP_CLK_SEL1")
	)
	(segment
		(start 96.874584 -77.597)
		(end 96.874584 -76.86294)
		(width 0.127)
		(layer "F.Cu")
		(net "EXP_CLK_SEL1")
	)
	(via
		(at 96.139 -77.851)
		(size 0.6604)
		(drill 0.3302)
		(layers "F.Cu" "B.Cu")
		(net "EXP_CLK_SEL1")
	)
	(via
		(at 96.874584 -76.86294)
		(size 0.508)
		(drill 0.254)
		(layers "F.Cu" "B.Cu")
		(net "EXP_CLK_SEL1")
	)
	(via
		(at 110.000034 -76.000102)
		(size 0.4572)
		(drill 0.2032)
		(layers "F.Cu" "B.Cu")
		(net "EXP_CLK_SEL1")
	)
	(segment
		(start 109.393736 -76.6064)
		(end 110.000034 -76.000102)
		(width 0.127)
		(layer "In5.Cu")
		(net "EXP_CLK_SEL1")
	)
	(segment
		(start 97.131124 -76.6064)
		(end 109.393736 -76.6064)
		(width 0.127)
		(layer "In5.Cu")
		(net "EXP_CLK_SEL1")
	)
	(segment
		(start 96.874584 -76.86294)
		(end 97.131124 -76.6064)
		(width 0.127)
		(layer "In5.Cu")
		(net "EXP_CLK_SEL1")
	)
	(segment
		(start 96.44761 -75.89139)
		(end 96.331278 -75.89139)
		(width 0.127)
		(layer "F.Cu")
		(net "EXP_CLK_SEL0")
	)
	(segment
		(start 110.499906 -74.500232)
		(end 110.000034 -75.000104)
		(width 0.127)
		(layer "F.Cu")
		(net "EXP_CLK_SEL0")
	)
	(segment
		(start 96.331278 -75.89139)
		(end 95.83039 -75.89139)
		(width 0.127)
		(layer "F.Cu")
		(net "EXP_CLK_SEL0")
	)
	(segment
		(start 95.287846 -75.348846)
		(end 94.818454 -75.348846)
		(width 0.127)
		(layer "F.Cu")
		(net "EXP_CLK_SEL0")
	)
	(segment
		(start 97.028 -75.311)
		(end 96.44761 -75.89139)
		(width 0.127)
		(layer "F.Cu")
		(net "EXP_CLK_SEL0")
	)
	(segment
		(start 94.818454 -75.348846)
		(end 94.1705 -75.9968)
		(width 0.127)
		(layer "F.Cu")
		(net "EXP_CLK_SEL0")
	)
	(segment
		(start 95.83039 -75.89139)
		(end 95.287846 -75.348846)
		(width 0.127)
		(layer "F.Cu")
		(net "EXP_CLK_SEL0")
	)
	(segment
		(start 93.0275 -75.9968)
		(end 94.1705 -75.9968)
		(width 0.127)
		(layer "F.Cu")
		(net "EXP_CLK_SEL0")
	)
	(via
		(at 96.331278 -75.89139)
		(size 0.6604)
		(drill 0.3302)
		(layers "F.Cu" "B.Cu")
		(net "EXP_CLK_SEL0")
	)
	(via
		(at 97.028 -75.311)
		(size 0.508)
		(drill 0.254)
		(layers "F.Cu" "B.Cu")
		(net "EXP_CLK_SEL0")
	)
	(via
		(at 110.000034 -75.000104)
		(size 0.4572)
		(drill 0.2032)
		(layers "F.Cu" "B.Cu")
		(net "EXP_CLK_SEL0")
	)
	(segment
		(start 97.028 -75.311)
		(end 97.323402 -75.606402)
		(width 0.127)
		(layer "In5.Cu")
		(net "EXP_CLK_SEL0")
	)
	(segment
		(start 109.393736 -75.606402)
		(end 110.000034 -75.000104)
		(width 0.127)
		(layer "In5.Cu")
		(net "EXP_CLK_SEL0")
	)
	(segment
		(start 97.323402 -75.606402)
		(end 109.393736 -75.606402)
		(width 0.127)
		(layer "In5.Cu")
		(net "EXP_CLK_SEL0")
	)
	(segment
		(start 96.884998 -78.656688)
		(end 98.015298 -77.526388)
		(width 0.127)
		(layer "F.Cu")
		(net "EXP_BLINK_OUT")
	)
	(segment
		(start 87.122 -77.6605)
		(end 91.1225 -77.6605)
		(width 0.127)
		(layer "F.Cu")
		(net "EXP_BLINK_OUT")
	)
	(segment
		(start 84.5185 -76.473558)
		(end 85.02269 -76.977748)
		(width 0.127)
		(layer "F.Cu")
		(net "EXP_BLINK_OUT")
	)
	(segment
		(start 85.02269 -76.977748)
		(end 85.705442 -77.6605)
		(width 0.127)
		(layer "F.Cu")
		(net "EXP_BLINK_OUT")
	)
	(segment
		(start 108.49991 -76.500228)
		(end 108.000038 -77.0001)
		(width 0.127)
		(layer "F.Cu")
		(net "EXP_BLINK_OUT")
	)
	(segment
		(start 92.118688 -78.656688)
		(end 96.884998 -78.656688)
		(width 0.127)
		(layer "F.Cu")
		(net "EXP_BLINK_OUT")
	)
	(segment
		(start 84.5185 -75.40117)
		(end 84.5185 -76.473558)
		(width 0.127)
		(layer "F.Cu")
		(net "EXP_BLINK_OUT")
	)
	(segment
		(start 85.705442 -77.6605)
		(end 87.122 -77.6605)
		(width 0.127)
		(layer "F.Cu")
		(net "EXP_BLINK_OUT")
	)
	(segment
		(start 91.1225 -77.6605)
		(end 92.118688 -78.656688)
		(width 0.127)
		(layer "F.Cu")
		(net "EXP_BLINK_OUT")
	)
	(via
		(at 108.000038 -77.0001)
		(size 0.4572)
		(drill 0.2032)
		(layers "F.Cu" "B.Cu")
		(net "EXP_BLINK_OUT")
	)
	(via
		(at 85.02269 -76.977748)
		(size 0.6604)
		(drill 0.3302)
		(layers "F.Cu" "B.Cu")
		(net "EXP_BLINK_OUT")
	)
	(via
		(at 98.015298 -77.526388)
		(size 0.508)
		(drill 0.254)
		(layers "F.Cu" "B.Cu")
		(net "EXP_BLINK_OUT")
	)
	(segment
		(start 98.059494 -77.570584)
		(end 98.015298 -77.526388)
		(width 0.127)
		(layer "In5.Cu")
		(net "EXP_BLINK_OUT")
	)
	(segment
		(start 108.000038 -77.0001)
		(end 107.429554 -77.570584)
		(width 0.127)
		(layer "In5.Cu")
		(net "EXP_BLINK_OUT")
	)
	(segment
		(start 107.429554 -77.570584)
		(end 98.059494 -77.570584)
		(width 0.127)
		(layer "In5.Cu")
		(net "EXP_BLINK_OUT")
	)
	(segment
		(start 108.49991 -80.50022)
		(end 108.000038 -81.000092)
		(width 0.127)
		(layer "F.Cu")
		(net "EXP_BLINK_IN")
	)
	(via
		(at 108.000038 -81.000092)
		(size 0.4572)
		(drill 0.2032)
		(layers "F.Cu" "B.Cu")
		(net "EXP_BLINK_IN")
	)
	(via
		(at 108.137198 -82.73161)
		(size 0.6096)
		(drill 0.3048)
		(layers "F.Cu" "B.Cu")
		(net "EXP_BLINK_IN")
	)
	(segment
		(start 107.823 -83.624166)
		(end 108.137198 -83.309968)
		(width 0.127)
		(layer "B.Cu")
		(net "EXP_BLINK_IN")
	)
	(segment
		(start 107.823 -87.20074)
		(end 107.823 -83.624166)
		(width 0.127)
		(layer "B.Cu")
		(net "EXP_BLINK_IN")
	)
	(segment
		(start 107.50804 -87.5157)
		(end 107.823 -87.20074)
		(width 0.127)
		(layer "B.Cu")
		(net "EXP_BLINK_IN")
	)
	(segment
		(start 107.061 -87.5157)
		(end 107.50804 -87.5157)
		(width 0.127)
		(layer "B.Cu")
		(net "EXP_BLINK_IN")
	)
	(segment
		(start 108.137198 -82.73161)
		(end 108.137198 -81.137252)
		(width 0.127)
		(layer "B.Cu")
		(net "EXP_BLINK_IN")
	)
	(segment
		(start 108.137198 -81.137252)
		(end 108.000038 -81.000092)
		(width 0.127)
		(layer "B.Cu")
		(net "EXP_BLINK_IN")
	)
	(segment
		(start 108.137198 -83.309968)
		(end 108.137198 -82.73161)
		(width 0.127)
		(layer "B.Cu")
		(net "EXP_BLINK_IN")
	)
	(segment
		(start 95.758 -73.533)
		(end 95.0087 -73.533)
		(width 0.127)
		(layer "F.Cu")
		(net "EXP_ADC_IN1")
	)
	(segment
		(start 95.0087 -73.533)
		(end 94.6277 -73.152)
		(width 0.127)
		(layer "F.Cu")
		(net "EXP_ADC_IN1")
	)
	(segment
		(start 108.49991 -73.500234)
		(end 108.000038 -74.000106)
		(width 0.127)
		(layer "F.Cu")
		(net "EXP_ADC_IN1")
	)
	(segment
		(start 95.758 -73.533)
		(end 96.0882 -73.533)
		(width 0.127)
		(layer "F.Cu")
		(net "EXP_ADC_IN1")
	)
	(segment
		(start 96.0882 -73.533)
		(end 96.6216 -72.9996)
		(width 0.127)
		(layer "F.Cu")
		(net "EXP_ADC_IN1")
	)
	(via
		(at 96.6216 -72.9996)
		(size 0.508)
		(drill 0.254)
		(layers "F.Cu" "B.Cu")
		(net "EXP_ADC_IN1")
	)
	(via
		(at 108.000038 -74.000106)
		(size 0.4572)
		(drill 0.2032)
		(layers "F.Cu" "B.Cu")
		(net "EXP_ADC_IN1")
	)
	(via
		(at 95.758 -73.533)
		(size 0.6604)
		(drill 0.3302)
		(layers "F.Cu" "B.Cu")
		(net "EXP_ADC_IN1")
	)
	(segment
		(start 107.624372 -74.000106)
		(end 107.079034 -73.454768)
		(width 0.127)
		(layer "In5.Cu")
		(net "EXP_ADC_IN1")
	)
	(segment
		(start 98.0948 -73.454768)
		(end 97.639632 -72.9996)
		(width 0.127)
		(layer "In5.Cu")
		(net "EXP_ADC_IN1")
	)
	(segment
		(start 107.079034 -73.454768)
		(end 98.0948 -73.454768)
		(width 0.127)
		(layer "In5.Cu")
		(net "EXP_ADC_IN1")
	)
	(segment
		(start 97.639632 -72.9996)
		(end 96.6216 -72.9996)
		(width 0.127)
		(layer "In5.Cu")
		(net "EXP_ADC_IN1")
	)
	(segment
		(start 108.000038 -74.000106)
		(end 107.624372 -74.000106)
		(width 0.127)
		(layer "In5.Cu")
		(net "EXP_ADC_IN1")
	)
	(segment
		(start 105.499916 -79.500222)
		(end 105.000044 -79.00035)
		(width 0.127)
		(layer "F.Cu")
		(net "EXP_ADC_IN0")
	)
	(via
		(at 104.93121 -82.09661)
		(size 0.6096)
		(drill 0.3048)
		(layers "F.Cu" "B.Cu")
		(net "EXP_ADC_IN0")
	)
	(via
		(at 105.000044 -79.00035)
		(size 0.4572)
		(drill 0.2032)
		(layers "F.Cu" "B.Cu")
		(net "EXP_ADC_IN0")
	)
	(segment
		(start 104.93121 -82.5119)
		(end 104.606344 -82.836766)
		(width 0.127)
		(layer "B.Cu")
		(net "EXP_ADC_IN0")
	)
	(segment
		(start 104.606344 -82.836766)
		(end 104.606344 -83.587844)
		(width 0.127)
		(layer "B.Cu")
		(net "EXP_ADC_IN0")
	)
	(segment
		(start 104.93121 -82.09661)
		(end 104.93121 -82.5119)
		(width 0.127)
		(layer "B.Cu")
		(net "EXP_ADC_IN0")
	)
	(segment
		(start 104.580944 -79.543656)
		(end 104.580944 -81.746344)
		(width 0.127)
		(layer "B.Cu")
		(net "EXP_ADC_IN0")
	)
	(segment
		(start 105.000044 -79.00035)
		(end 105.000044 -79.124556)
		(width 0.127)
		(layer "B.Cu")
		(net "EXP_ADC_IN0")
	)
	(segment
		(start 104.580944 -81.746344)
		(end 104.93121 -82.09661)
		(width 0.127)
		(layer "B.Cu")
		(net "EXP_ADC_IN0")
	)
	(segment
		(start 104.606344 -83.587844)
		(end 104.902 -83.8835)
		(width 0.127)
		(layer "B.Cu")
		(net "EXP_ADC_IN0")
	)
	(segment
		(start 105.000044 -79.124556)
		(end 104.580944 -79.543656)
		(width 0.127)
		(layer "B.Cu")
		(net "EXP_ADC_IN0")
	)
	(segment
		(start 104.499918 -66.499994)
		(end 104.000046 -66.000122)
		(width 0.127)
		(layer "F.Cu")
		(net "DDR_BZ")
	)
	(via
		(at 103.500936 -66.789808)
		(size 0.6096)
		(drill 0.3048)
		(layers "F.Cu" "B.Cu")
		(net "DDR_BZ")
	)
	(via
		(at 104.000046 -66.000122)
		(size 0.4572)
		(drill 0.2032)
		(layers "F.Cu" "B.Cu")
		(net "DDR_BZ")
	)
	(segment
		(start 104.000046 -66.000122)
		(end 104.000046 -66.541396)
		(width 0.127)
		(layer "B.Cu")
		(net "DDR_BZ")
	)
	(segment
		(start 103.500936 -66.789808)
		(end 102.287832 -66.789808)
		(width 0.127)
		(layer "B.Cu")
		(net "DDR_BZ")
	)
	(segment
		(start 104.000046 -66.541396)
		(end 103.751634 -66.789808)
		(width 0.127)
		(layer "B.Cu")
		(net "DDR_BZ")
	)
	(segment
		(start 103.751634 -66.789808)
		(end 103.500936 -66.789808)
		(width 0.127)
		(layer "B.Cu")
		(net "DDR_BZ")
	)
	(segment
		(start 190.594742 -37.65423)
		(end 189.885828 -37.65423)
		(width 0.127)
		(layer "F.Cu")
		(net "CP_DONE")
	)
	(segment
		(start 187.923424 -38.800024)
		(end 188.725048 -37.9984)
		(width 0.127)
		(layer "F.Cu")
		(net "CP_DONE")
	)
	(segment
		(start 186.59983 -38.800024)
		(end 187.923424 -38.800024)
		(width 0.127)
		(layer "F.Cu")
		(net "CP_DONE")
	)
	(segment
		(start 188.725048 -37.9984)
		(end 189.4078 -37.9984)
		(width 0.127)
		(layer "F.Cu")
		(net "CP_DONE")
	)
	(segment
		(start 189.541658 -37.9984)
		(end 189.4078 -37.9984)
		(width 0.127)
		(layer "F.Cu")
		(net "CP_DONE")
	)
	(segment
		(start 189.885828 -37.65423)
		(end 189.541658 -37.9984)
		(width 0.127)
		(layer "F.Cu")
		(net "CP_DONE")
	)
	(via
		(at 189.4078 -37.9984)
		(size 0.6604)
		(drill 0.3302)
		(layers "F.Cu" "B.Cu")
		(net "CP_DONE")
	)
	(segment
		(start 173.240192 -53.898546)
		(end 173.2407 -53.899054)
		(width 0.127)
		(layer "F.Cu")
		(net "AVSO_VREF")
	)
	(segment
		(start 178.995578 -67.220338)
		(end 176.568354 -64.793114)
		(width 0.127)
		(layer "F.Cu")
		(net "AVSO_VREF")
	)
	(segment
		(start 173.36389 -54.904132)
		(end 171.560998 -56.707024)
		(width 0.127)
		(layer "F.Cu")
		(net "AVSO_VREF")
	)
	(segment
		(start 173.2407 -53.899054)
		(end 173.2407 -54.301136)
		(width 0.127)
		(layer "F.Cu")
		(net "AVSO_VREF")
	)
	(segment
		(start 178.995832 -67.220338)
		(end 178.995578 -67.220338)
		(width 0.127)
		(layer "F.Cu")
		(net "AVSO_VREF")
	)
	(segment
		(start 171.560998 -61.252608)
		(end 173.998382 -63.689992)
		(width 0.127)
		(layer "F.Cu")
		(net "AVSO_VREF")
	)
	(segment
		(start 173.342808 -51.432968)
		(end 173.342808 -53.606192)
		(width 0.127)
		(layer "F.Cu")
		(net "AVSO_VREF")
	)
	(segment
		(start 172.999908 -50.8)
		(end 172.999908 -51.090068)
		(width 0.127)
		(layer "F.Cu")
		(net "AVSO_VREF")
	)
	(segment
		(start 171.560998 -56.707024)
		(end 171.560998 -61.252608)
		(width 0.127)
		(layer "F.Cu")
		(net "AVSO_VREF")
	)
	(segment
		(start 176.568354 -64.779906)
		(end 176.568354 -64.793114)
		(width 0.127)
		(layer "F.Cu")
		(net "AVSO_VREF")
	)
	(segment
		(start 173.998382 -63.689992)
		(end 175.47844 -63.689992)
		(width 0.127)
		(layer "F.Cu")
		(net "AVSO_VREF")
	)
	(segment
		(start 173.240192 -53.708808)
		(end 173.240192 -53.898546)
		(width 0.127)
		(layer "F.Cu")
		(net "AVSO_VREF")
	)
	(segment
		(start 172.999908 -51.090068)
		(end 173.342808 -51.432968)
		(width 0.127)
		(layer "F.Cu")
		(net "AVSO_VREF")
	)
	(segment
		(start 173.2407 -54.301136)
		(end 173.36389 -54.424326)
		(width 0.127)
		(layer "F.Cu")
		(net "AVSO_VREF")
	)
	(segment
		(start 173.36389 -54.424326)
		(end 173.36389 -54.904132)
		(width 0.127)
		(layer "F.Cu")
		(net "AVSO_VREF")
	)
	(segment
		(start 173.342808 -53.606192)
		(end 173.240192 -53.708808)
		(width 0.127)
		(layer "F.Cu")
		(net "AVSO_VREF")
	)
	(segment
		(start 175.47844 -63.689992)
		(end 176.568354 -64.779906)
		(width 0.127)
		(layer "F.Cu")
		(net "AVSO_VREF")
	)
	(via
		(at 172.7962 -97.7646)
		(size 0.508)
		(drill 0.254)
		(layers "F.Cu" "B.Cu")
		(net "AVSO_VREF")
	)
	(via
		(at 178.995832 -67.220338)
		(size 0.508)
		(drill 0.254)
		(layers "F.Cu" "B.Cu")
		(net "AVSO_VREF")
	)
	(via
		(at 176.568354 -64.793114)
		(size 0.6604)
		(drill 0.3302)
		(layers "F.Cu" "B.Cu")
		(net "AVSO_VREF")
	)
	(segment
		(start 172.610018 -97.950782)
		(end 172.7962 -97.7646)
		(width 0.127)
		(layer "B.Cu")
		(net "AVSO_VREF")
	)
	(segment
		(start 170.721274 -97.315782)
		(end 170.847258 -97.315782)
		(width 0.127)
		(layer "B.Cu")
		(net "AVSO_VREF")
	)
	(segment
		(start 170.847258 -97.315782)
		(end 171.482258 -97.950782)
		(width 0.127)
		(layer "B.Cu")
		(net "AVSO_VREF")
	)
	(segment
		(start 171.838874 -97.950782)
		(end 172.610018 -97.950782)
		(width 0.127)
		(layer "B.Cu")
		(net "AVSO_VREF")
	)
	(segment
		(start 171.482258 -97.950782)
		(end 171.838874 -97.950782)
		(width 0.127)
		(layer "B.Cu")
		(net "AVSO_VREF")
	)
	(segment
		(start 189.516258 -106.15041)
		(end 191.8462 -103.820468)
		(width 0.127)
		(layer "In5.Cu")
		(net "AVSO_VREF")
	)
	(segment
		(start 175.196246 -106.15041)
		(end 189.516258 -106.15041)
		(width 0.127)
		(layer "In5.Cu")
		(net "AVSO_VREF")
	)
	(segment
		(start 178.502056 -69.770244)
		(end 178.502056 -67.714114)
		(width 0.127)
		(layer "In5.Cu")
		(net "AVSO_VREF")
	)
	(segment
		(start 178.502056 -67.714114)
		(end 178.995832 -67.220338)
		(width 0.127)
		(layer "In5.Cu")
		(net "AVSO_VREF")
	)
	(segment
		(start 172.834808 -103.788972)
		(end 175.196246 -106.15041)
		(width 0.127)
		(layer "In5.Cu")
		(net "AVSO_VREF")
	)
	(segment
		(start 191.8462 -83.114388)
		(end 178.502056 -69.770244)
		(width 0.127)
		(layer "In5.Cu")
		(net "AVSO_VREF")
	)
	(segment
		(start 172.7962 -97.7646)
		(end 172.834808 -97.803208)
		(width 0.127)
		(layer "In5.Cu")
		(net "AVSO_VREF")
	)
	(segment
		(start 191.8462 -103.820468)
		(end 191.8462 -83.114388)
		(width 0.127)
		(layer "In5.Cu")
		(net "AVSO_VREF")
	)
	(segment
		(start 172.834808 -97.803208)
		(end 172.834808 -103.788972)
		(width 0.127)
		(layer "In5.Cu")
		(net "AVSO_VREF")
	)
	(segment
		(start 172.199808 -51.000406)
		(end 172.199808 -50.8)
		(width 0.127)
		(layer "F.Cu")
		(net "AVSO_IDDTN18")
	)
	(segment
		(start 172.580808 -53.29301)
		(end 172.580808 -51.381406)
		(width 0.127)
		(layer "F.Cu")
		(net "AVSO_IDDTN18")
	)
	(segment
		(start 172.580808 -51.381406)
		(end 172.199808 -51.000406)
		(width 0.127)
		(layer "F.Cu")
		(net "AVSO_IDDTN18")
	)
	(via
		(at 172.82795 -52.319936)
		(size 0.6096)
		(drill 0.3048)
		(layers "F.Cu" "B.Cu")
		(net "AVSO_IDDTN18")
	)
	(via
		(at 172.580808 -53.29301)
		(size 0.508)
		(drill 0.254)
		(layers "F.Cu" "B.Cu")
		(net "AVSO_IDDTN18")
	)
	(segment
		(start 172.550836 -51.19243)
		(end 172.82795 -51.469544)
		(width 0.127)
		(layer "B.Cu")
		(net "AVSO_IDDTN18")
	)
	(segment
		(start 172.580808 -53.29301)
		(end 172.82795 -53.045868)
		(width 0.127)
		(layer "B.Cu")
		(net "AVSO_IDDTN18")
	)
	(segment
		(start 172.82795 -51.469544)
		(end 172.82795 -52.319936)
		(width 0.127)
		(layer "B.Cu")
		(net "AVSO_IDDTN18")
	)
	(segment
		(start 172.82795 -53.045868)
		(end 172.82795 -52.319936)
		(width 0.127)
		(layer "B.Cu")
		(net "AVSO_IDDTN18")
	)
	(segment
		(start 64.897 -106.4895)
		(end 64.897 -107.533694)
		(width 0.254)
		(layer "F.Cu")
		(net "AGND_P3V3")
	)
	(via
		(at 71.259446 -99.502976)
		(size 0.6604)
		(drill 0.3302)
		(layers "F.Cu" "B.Cu")
		(net "AGND_P3V3")
	)
	(via
		(at 70.048628 -98.621596)
		(size 0.6604)
		(drill 0.3302)
		(layers "F.Cu" "B.Cu")
		(net "AGND_P3V3")
	)
	(via
		(at 71.048626 -97.421446)
		(size 0.6604)
		(drill 0.3302)
		(layers "F.Cu" "B.Cu")
		(net "AGND_P3V3")
	)
	(via
		(at 70.12178 -100.420678)
		(size 0.7112)
		(drill 0.4064)
		(layers "F.Cu" "B.Cu")
		(net "AGND_P3V3")
	)
	(via
		(at 70.12178 -101.8794)
		(size 0.6096)
		(drill 0.3048)
		(layers "F.Cu" "B.Cu")
		(net "AGND_P3V3")
	)
	(via
		(at 64.897 -107.533694)
		(size 0.508)
		(drill 0.254)
		(layers "F.Cu" "B.Cu")
		(net "AGND_P3V3")
	)
	(segment
		(start 70.12178 -100.420678)
		(end 70.12178 -101.8794)
		(width 0.508)
		(layer "B.Cu")
		(net "AGND_P3V3")
	)
	(segment
		(start 64.897 -107.533694)
		(end 66.456306 -109.093)
		(width 0.508)
		(layer "B.Cu")
		(net "AGND_P3V3")
	)
	(segment
		(start 70.12178 -107.737656)
		(end 70.12178 -101.8794)
		(width 0.508)
		(layer "B.Cu")
		(net "AGND_P3V3")
	)
	(segment
		(start 68.766436 -109.093)
		(end 70.12178 -107.737656)
		(width 0.508)
		(layer "B.Cu")
		(net "AGND_P3V3")
	)
	(segment
		(start 66.456306 -109.093)
		(end 68.766436 -109.093)
		(width 0.508)
		(layer "B.Cu")
		(net "AGND_P3V3")
	)
	(segment
		(start 48.268382 -33.418018)
		(end 48.035464 -33.650936)
		(width 0.3048)
		(layer "F.Cu")
		(net "AGND_P0V9")
	)
	(segment
		(start 49.089056 -34.365692)
		(end 49.570894 -33.883854)
		(width 0.508)
		(layer "F.Cu")
		(net "AGND_P0V9")
	)
	(segment
		(start 50.343308 -34.365692)
		(end 49.089056 -34.365692)
		(width 0.508)
		(layer "F.Cu")
		(net "AGND_P0V9")
	)
	(segment
		(start 48.035464 -33.650936)
		(end 46.712124 -33.650936)
		(width 0.3048)
		(layer "F.Cu")
		(net "AGND_P0V9")
	)
	(segment
		(start 49.570894 -33.418018)
		(end 48.268382 -33.418018)
		(width 0.3048)
		(layer "F.Cu")
		(net "AGND_P0V9")
	)
	(segment
		(start 39.7637 -30.988)
		(end 39.7637 -31.644082)
		(width 0.508)
		(layer "F.Cu")
		(net "AGND_P0V9")
	)
	(segment
		(start 39.7637 -31.644082)
		(end 40.287448 -32.16783)
		(width 0.508)
		(layer "F.Cu")
		(net "AGND_P0V9")
	)
	(segment
		(start 49.570894 -33.883854)
		(end 49.570894 -33.418018)
		(width 0.508)
		(layer "F.Cu")
		(net "AGND_P0V9")
	)
	(via
		(at 40.287448 -32.16783)
		(size 0.508)
		(drill 0.254)
		(layers "F.Cu" "B.Cu")
		(net "AGND_P0V9")
	)
	(via
		(at 43.345608 -30.4292)
		(size 0.6096)
		(drill 0.3048)
		(layers "F.Cu" "B.Cu")
		(net "AGND_P0V9")
	)
	(via
		(at 50.343308 -34.365692)
		(size 0.508)
		(drill 0.254)
		(layers "F.Cu" "B.Cu")
		(net "AGND_P0V9")
	)
	(segment
		(start 40.654478 -30.4292)
		(end 43.345608 -30.4292)
		(width 0.508)
		(layer "B.Cu")
		(net "AGND_P0V9")
	)
	(segment
		(start 40.287448 -30.79623)
		(end 40.654478 -30.4292)
		(width 0.508)
		(layer "B.Cu")
		(net "AGND_P0V9")
	)
	(segment
		(start 47.067216 -30.4292)
		(end 43.345608 -30.4292)
		(width 0.508)
		(layer "B.Cu")
		(net "AGND_P0V9")
	)
	(segment
		(start 50.343308 -33.705292)
		(end 47.067216 -30.4292)
		(width 0.508)
		(layer "B.Cu")
		(net "AGND_P0V9")
	)
	(segment
		(start 40.287448 -32.16783)
		(end 40.287448 -30.79623)
		(width 0.508)
		(layer "B.Cu")
		(net "AGND_P0V9")
	)
	(segment
		(start 50.343308 -34.365692)
		(end 50.343308 -33.705292)
		(width 0.508)
		(layer "B.Cu")
		(net "AGND_P0V9")
	)
	(zone
		(layer "F.Cu")
		(hatch none 0.5)
		(connect_pads
			(clearance 0)
		)
		(min_thickness 0.25)
		(keepout
			(tracks not_allowed)
			(vias allowed)
			(pads allowed)
			(copperpour not_allowed)
			(footprints allowed)
		)
		(placement
			(enabled no)
			(sheetname "")
		)
		(fill
			(thermal_gap 0.5)
			(thermal_bridge_width 0.5)
			(island_removal_mode 0)
		)
		(polygon
			(pts
				(arc
					(start 129.00025 -62.641988)
					(mid 128.683087 -62.833296)
					(end 128.704848 -63.203074)
				)
				(arc
					(start 128.789684 -63.118238)
					(mid 129.170556 -62.829568)
					(end 128.881886 -63.21044)
				)
				(arc
					(start 128.79705 -63.295276)
					(mid 128.893747 -63.342161)
					(end 128.999996 -63.358268)
				)
				(xy 129.549652 -63.358268)
				(arc
					(start 129.789682 -63.118238)
					(mid 130.170554 -62.829568)
					(end 129.881884 -63.21044)
				)
				(xy 129.734056 -63.358268)
				(arc
					(start 129.999994 -63.358268)
					(mid 130.358134 -63.000128)
					(end 129.999994 -62.641988)
				)
			)
		)
	)
	(zone
		(net "P3V3")
		(layer "F.Cu")
		(hatch none 0.5)
		(connect_pads
			(clearance 0.5)
		)
		(min_thickness 0.25)
		(fill yes
			(thermal_gap 0.5)
			(thermal_bridge_width 0.5)
			(island_removal_mode 0)
		)
		(polygon
			(pts
				(xy 71.364094 -12.72921) (xy 71.160894 -12.93241) (xy 71.160894 -14.68501) (xy 71.287894 -14.81201)
				(xy 72.773794 -14.81201) (xy 73.186544 -14.39926) (xy 73.326244 -14.39926) (xy 73.700894 -14.02461)
				(xy 73.700894 -12.83081) (xy 73.599294 -12.72921)
			)
		)
	)
	(zone
		(layer "F.Cu")
		(hatch none 0.5)
		(connect_pads
			(clearance 0)
		)
		(min_thickness 0.25)
		(keepout
			(tracks not_allowed)
			(vias allowed)
			(pads allowed)
			(copperpour not_allowed)
			(footprints allowed)
		)
		(placement
			(enabled no)
			(sheetname "")
		)
		(fill
			(thermal_gap 0.5)
			(thermal_bridge_width 0.5)
			(island_removal_mode 0)
		)
		(polygon
			(pts
				(arc
					(start 176.75225 -23.103332)
					(mid 176.36871 -22.719792)
					(end 175.98517 -23.103332)
				)
				(xy 175.98517 -23.306532) (xy 176.075086 -23.306532)
				(arc
					(start 176.079658 -23.306532)
					(mid 176.127483 -23.300762)
					(end 176.172622 -23.283926)
				)
				(arc
					(start 176.172622 -23.283926)
					(mid 176.487367 -22.864728)
					(end 176.344326 -23.369016)
				)
				(arc
					(start 176.344326 -23.369016)
					(mid 176.239938 -23.442371)
					(end 176.116996 -23.476458)
				)
				(xy 176.115218 -23.478236) (xy 176.08931 -23.478236) (xy 176.079658 -23.478236) (xy 176.075086 -23.478236)
				(xy 175.98517 -23.478236) (xy 175.98517 -23.617936) (xy 176.07534 -23.617936) (xy 176.079912 -23.617682)
				(xy 176.089564 -23.617936) (xy 176.115472 -23.617936)
				(arc
					(start 176.11725 -23.61946)
					(mid 176.239921 -23.653474)
					(end 176.344072 -23.726648)
				)
				(arc
					(start 176.344072 -23.726648)
					(mid 176.487121 -24.231443)
					(end 176.172368 -23.811738)
				)
				(arc
					(start 176.172368 -23.811738)
					(mid 176.127465 -23.795098)
					(end 176.079912 -23.789386)
				)
				(xy 176.07534 -23.789132) (xy 175.98517 -23.789132)
				(arc
					(start 175.98517 -23.992078)
					(mid 176.368583 -24.375872)
					(end 176.75225 -23.992332)
				)
			)
		)
	)
	(zone
		(layer "F.Cu")
		(hatch none 0.5)
		(connect_pads
			(clearance 0)
		)
		(min_thickness 0.25)
		(keepout
			(tracks allowed)
			(vias allowed)
			(pads allowed)
			(copperpour allowed)
			(footprints allowed)
		)
		(placement
			(enabled no)
			(sheetname "")
		)
		(fill
			(thermal_gap 0.5)
			(thermal_bridge_width 0.5)
			(island_removal_mode 0)
		)
		(polygon
			(pts
				(xy 148.391118 -54.262528) (xy 148.18487 -55.127398) (xy 147.814284 -55.039006) (xy 148.020532 -54.174136)
			)
		)
	)
	(zone
		(layer "F.Cu")
		(hatch none 0.5)
		(connect_pads
			(clearance 0)
		)
		(min_thickness 0.25)
		(keepout
			(tracks not_allowed)
			(vias allowed)
			(pads allowed)
			(copperpour not_allowed)
			(footprints allowed)
		)
		(placement
			(enabled no)
			(sheetname "")
		)
		(fill
			(thermal_gap 0.5)
			(thermal_bridge_width 0.5)
			(island_removal_mode 0)
		)
		(polygon
			(pts
				(arc
					(start 129.00025 -67.641978)
					(mid 128.893876 -67.658061)
					(end 128.79705 -67.70497)
				)
				(arc
					(start 128.881886 -67.789806)
					(mid 129.170556 -68.170678)
					(end 128.789684 -67.882008)
				)
				(arc
					(start 128.704848 -67.797172)
					(mid 128.682985 -68.166861)
					(end 128.999996 -68.358258)
				)
				(arc
					(start 129.999994 -68.358258)
					(mid 130.358134 -68.000118)
					(end 129.999994 -67.641978)
				)
				(xy 129.734056 -67.641978)
				(arc
					(start 129.881884 -67.789806)
					(mid 130.170554 -68.170678)
					(end 129.789682 -67.882008)
				)
				(xy 129.549652 -67.641978)
			)
		)
	)
	(zone
		(layer "F.Cu")
		(hatch none 0.5)
		(connect_pads
			(clearance 0)
		)
		(min_thickness 0.25)
		(keepout
			(tracks not_allowed)
			(vias allowed)
			(pads allowed)
			(copperpour not_allowed)
			(footprints allowed)
		)
		(placement
			(enabled no)
			(sheetname "")
		)
		(fill
			(thermal_gap 0.5)
			(thermal_bridge_width 0.5)
			(island_removal_mode 0)
		)
		(polygon
			(pts
				(arc
					(start 171.358052 -30.39999)
					(mid 170.999785 -30.04185)
					(end 170.641772 -30.400244)
				)
				(xy 170.641772 -30.734) (xy 170.688 -30.780228) (xy 170.688 -30.840172) (xy 170.641772 -30.8864)
				(arc
					(start 170.642026 -31.199836)
					(mid 170.825499 -31.512749)
					(end 171.188126 -31.50489)
				)
				(arc
					(start 171.10202 -31.418784)
					(mid 170.829577 -31.029501)
					(end 171.21886 -31.301944)
				)
				(arc
					(start 171.304966 -31.38805)
					(mid 171.344714 -31.297653)
					(end 171.358306 -31.199836)
				)
				(xy 171.358306 -30.95879) (xy 171.358306 -30.879542)
				(arc
					(start 171.098718 -30.620208)
					(mid 170.829239 -30.229317)
					(end 171.22013 -30.498796)
				)
				(xy 171.358052 -30.636972) (xy 171.358052 -30.498796)
			)
		)
	)
	(zone
		(net "P1V5_E_LL")
		(layer "F.Cu")
		(hatch none 0.5)
		(connect_pads
			(clearance 0.5)
		)
		(min_thickness 0.25)
		(fill yes
			(thermal_gap 0.5)
			(thermal_bridge_width 0.5)
			(island_removal_mode 0)
		)
		(polygon
			(pts
				(xy 146.716242 -109.982) (xy 146.29511 -110.403132) (xy 146.29511 -115.297712) (xy 147.176998 -116.1796)
				(xy 148.8694 -116.1796) (xy 149.0472 -116.0018) (xy 151.5872 -116.0018) (xy 151.638 -115.951) (xy 151.638 -110.109)
				(xy 151.511 -109.982)
			)
		)
		(polygon
			(pts
				(xy 151.1046 -110.5662) (xy 150.9014 -110.5662) (xy 150.9014 -110.7694) (xy 151.1046 -110.7694)
			)
		)
	)
	(zone
		(net "GND")
		(layer "F.Cu")
		(hatch none 0.5)
		(connect_pads
			(clearance 0.5)
		)
		(min_thickness 0.25)
		(fill yes
			(thermal_gap 0.5)
			(thermal_bridge_width 0.5)
			(island_removal_mode 0)
		)
		(polygon
			(pts
				(xy 73.048368 -51.792632) (xy 72.517 -52.324) (xy 72.517 -56.896) (xy 72.771 -57.15) (xy 75.8571 -57.15)
				(xy 75.8952 -57.1119) (xy 75.8952 -51.971194) (xy 75.716638 -51.792632)
			)
		)
		(polygon
			(pts
				(xy 75.1078 -55.9943) (xy 74.9046 -55.9943) (xy 74.9046 -56.1975) (xy 75.1078 -56.1975)
			)
		)
		(polygon
			(pts
				(xy 74.9808 -52.6288) (xy 74.7776 -52.6288) (xy 74.7776 -52.832) (xy 74.9808 -52.832)
			)
		)
	)
	(zone
		(layer "F.Cu")
		(hatch none 0.5)
		(connect_pads
			(clearance 0)
		)
		(min_thickness 0.25)
		(keepout
			(tracks not_allowed)
			(vias allowed)
			(pads allowed)
			(copperpour not_allowed)
			(footprints allowed)
		)
		(placement
			(enabled no)
			(sheetname "")
		)
		(fill
			(thermal_gap 0.5)
			(thermal_bridge_width 0.5)
			(island_removal_mode 0)
		)
		(polygon
			(pts
				(arc
					(start 205.000098 -139.224258)
					(mid 191.499908 -131.430014)
					(end 205.000098 -123.63577)
				)
			)
		)
	)
	(zone
		(layer "F.Cu")
		(hatch none 0.5)
		(connect_pads
			(clearance 0)
		)
		(min_thickness 0.25)
		(keepout
			(tracks not_allowed)
			(vias allowed)
			(pads allowed)
			(copperpour not_allowed)
			(footprints allowed)
		)
		(placement
			(enabled no)
			(sheetname "")
		)
		(fill
			(thermal_gap 0.5)
			(thermal_bridge_width 0.5)
			(island_removal_mode 0)
		)
		(polygon
			(pts
				(arc
					(start 116.358162 -55.000144)
					(mid 116.000022 -54.642004)
					(end 115.641882 -55.000144)
				)
				(xy 115.641882 -55.266082)
				(arc
					(start 115.78971 -55.118254)
					(mid 116.170582 -54.829584)
					(end 115.881912 -55.210456)
				)
				(xy 115.641882 -55.450486)
				(arc
					(start 115.641882 -55.999888)
					(mid 115.657965 -56.106262)
					(end 115.704874 -56.203088)
				)
				(arc
					(start 115.78971 -56.118252)
					(mid 116.170582 -55.829582)
					(end 115.881912 -56.210454)
				)
				(arc
					(start 115.797076 -56.29529)
					(mid 116.166765 -56.317153)
					(end 116.358162 -56.000142)
				)
			)
		)
	)
	(zone
		(layer "F.Cu")
		(hatch none 0.5)
		(connect_pads
			(clearance 0)
		)
		(min_thickness 0.25)
		(keepout
			(tracks allowed)
			(vias allowed)
			(pads allowed)
			(copperpour allowed)
			(footprints not_allowed)
		)
		(placement
			(enabled no)
			(sheetname "")
		)
		(fill
			(thermal_gap 0.5)
			(thermal_bridge_width 0.5)
			(island_removal_mode 0)
		)
		(polygon
			(pts
				(arc
					(start 139.750038 -134.999984)
					(mid 134.999984 -139.750038)
					(end 130.24993 -134.999984)
				)
				(arc
					(start 130.24993 -134.999984)
					(mid 134.999984 -130.24993)
					(end 139.750038 -134.999984)
				)
			)
		)
	)
	(zone
		(layer "F.Cu")
		(hatch none 0.5)
		(connect_pads
			(clearance 0)
		)
		(min_thickness 0.25)
		(keepout
			(tracks not_allowed)
			(vias allowed)
			(pads allowed)
			(copperpour not_allowed)
			(footprints allowed)
		)
		(placement
			(enabled no)
			(sheetname "")
		)
		(fill
			(thermal_gap 0.5)
			(thermal_bridge_width 0.5)
			(island_removal_mode 0)
		)
		(polygon
			(pts
				(arc
					(start 165.399974 -36.416488)
					(mid 165.016434 -36.800028)
					(end 165.399974 -37.183568)
				)
				(xy 165.677596 -37.183568)
				(arc
					(start 165.52799 -37.033962)
					(mid 165.211409 -36.611463)
					(end 165.633908 -36.928044)
				)
				(xy 165.830758 -37.124894) (xy 165.831012 -37.124894) (xy 165.874954 -37.168836) (xy 165.874954 -37.183568)
				(arc
					(start 166.199566 -37.183568)
					(mid 166.311042 -37.167165)
					(end 166.412926 -37.119052)
				)
				(arc
					(start 166.327836 -37.033962)
					(mid 166.011255 -36.611463)
					(end 166.433754 -36.928044)
				)
				(arc
					(start 166.518844 -37.013134)
					(mid 166.538161 -36.619153)
					(end 166.19982 -36.416488)
				)
				(xy 166.021512 -36.416488) (xy 165.862 -36.576) (xy 165.742112 -36.576) (xy 165.5826 -36.416488)
			)
		)
	)
	(zone
		(net "SAS0_AVDD")
		(layer "F.Cu")
		(hatch none 0.5)
		(connect_pads
			(clearance 0.5)
		)
		(min_thickness 0.25)
		(fill yes
			(thermal_gap 0.5)
			(thermal_bridge_width 0.5)
			(island_removal_mode 0)
		)
		(polygon
			(pts
				(xy 179.117244 -97.907856) (xy 178.9176 -98.1075) (xy 178.9176 -100.457) (xy 179.1208 -100.6602)
				(xy 180.7718 -100.6602) (xy 181.229 -101.1174) (xy 181.229 -105.407206) (xy 181.3052 -105.483406)
				(xy 188.029342 -105.483406) (xy 188.428122 -105.084626) (xy 188.428122 -98.994722) (xy 187.380626 -97.947226)
				(xy 180.965348 -97.947226) (xy 180.925978 -97.907856)
			)
		)
		(polygon
			(pts
				(xy 182.3466 -98.7298) (xy 182.1434 -98.7298) (xy 182.1434 -98.933) (xy 182.3466 -98.933)
			)
		)
		(polygon
			(pts
				(xy 181.483 -98.7298) (xy 181.2798 -98.7298) (xy 181.2798 -98.933) (xy 181.483 -98.933)
			)
		)
	)
	(zone
		(layer "F.Cu")
		(hatch none 0.5)
		(connect_pads
			(clearance 0)
		)
		(min_thickness 0.25)
		(keepout
			(tracks not_allowed)
			(vias allowed)
			(pads allowed)
			(copperpour not_allowed)
			(footprints allowed)
		)
		(placement
			(enabled no)
			(sheetname "")
		)
		(fill
			(thermal_gap 0.5)
			(thermal_bridge_width 0.5)
			(island_removal_mode 0)
		)
		(polygon
			(pts
				(arc
					(start 113.358168 -55.000144)
					(mid 113.000028 -54.642004)
					(end 112.641888 -55.000144)
				)
				(arc
					(start 112.641888 -55.999888)
					(mid 112.833196 -56.317051)
					(end 113.202974 -56.29529)
				)
				(arc
					(start 113.118138 -56.210454)
					(mid 112.829468 -55.829582)
					(end 113.21034 -56.118252)
				)
				(arc
					(start 113.295176 -56.203088)
					(mid 113.342061 -56.106391)
					(end 113.358168 -56.000142)
				)
				(xy 113.358168 -55.450486)
				(arc
					(start 113.118138 -55.210456)
					(mid 112.829468 -54.829584)
					(end 113.21034 -55.118254)
				)
				(xy 113.358168 -55.266082)
			)
		)
	)
	(zone
		(layer "F.Cu")
		(hatch none 0.5)
		(connect_pads
			(clearance 0)
		)
		(min_thickness 0.25)
		(keepout
			(tracks not_allowed)
			(vias allowed)
			(pads allowed)
			(copperpour not_allowed)
			(footprints allowed)
		)
		(placement
			(enabled no)
			(sheetname "")
		)
		(fill
			(thermal_gap 0.5)
			(thermal_bridge_width 0.5)
			(island_removal_mode 0)
		)
		(polygon
			(pts
				(arc
					(start 121.358152 -55.000144)
					(mid 121.000012 -54.642004)
					(end 120.641872 -55.000144)
				)
				(xy 120.641872 -55.266082)
				(arc
					(start 120.7897 -55.118254)
					(mid 121.170572 -54.829584)
					(end 120.881902 -55.210456)
				)
				(xy 120.641872 -55.450486)
				(arc
					(start 120.641872 -55.999888)
					(mid 120.657955 -56.106262)
					(end 120.704864 -56.203088)
				)
				(arc
					(start 120.7897 -56.118252)
					(mid 121.170572 -55.829582)
					(end 120.881902 -56.210454)
				)
				(arc
					(start 120.797066 -56.29529)
					(mid 121.166755 -56.317153)
					(end 121.358152 -56.000142)
				)
			)
		)
	)
	(zone
		(net "P0V9")
		(layer "F.Cu")
		(hatch none 0.5)
		(connect_pads
			(clearance 0.5)
		)
		(min_thickness 0.25)
		(fill yes
			(thermal_gap 0.5)
			(thermal_bridge_width 0.5)
			(island_removal_mode 0)
		)
		(polygon
			(pts
				(xy 64.076326 -32.888936) (xy 62.264544 -34.700718) (xy 62.264544 -63.302896) (xy 63.046102 -64.084454)
				(xy 69.957442 -64.084454) (xy 70.363334 -63.678562) (xy 70.363334 -33.534858) (xy 69.717412 -32.888936)
			)
		)
		(polygon
			(pts
				(xy 69.4436 -62.8142) (xy 69.2404 -62.8142) (xy 69.2404 -63.0174) (xy 69.4436 -63.0174)
			)
		)
		(polygon
			(pts
				(xy 69.4436 -61.9506) (xy 69.2404 -61.9506) (xy 69.2404 -62.1538) (xy 69.4436 -62.1538)
			)
		)
		(polygon
			(pts
				(xy 69.5706 -57.3532) (xy 69.3674 -57.3532) (xy 69.3674 -57.5564) (xy 69.5706 -57.5564)
			)
		)
		(polygon
			(pts
				(xy 69.5706 -56.4896) (xy 69.3674 -56.4896) (xy 69.3674 -56.6928) (xy 69.5706 -56.6928)
			)
		)
		(polygon
			(pts
				(xy 69.5706 -52.2732) (xy 69.3674 -52.2732) (xy 69.3674 -52.4764) (xy 69.5706 -52.4764)
			)
		)
		(polygon
			(pts
				(xy 69.5706 -51.4096) (xy 69.3674 -51.4096) (xy 69.3674 -51.6128) (xy 69.5706 -51.6128)
			)
		)
		(polygon
			(pts
				(xy 69.4436 -46.8122) (xy 69.2404 -46.8122) (xy 69.2404 -47.0154) (xy 69.4436 -47.0154)
			)
		)
		(polygon
			(pts
				(xy 69.4436 -45.9486) (xy 69.2404 -45.9486) (xy 69.2404 -46.1518) (xy 69.4436 -46.1518)
			)
		)
		(polygon
			(pts
				(xy 69.4436 -41.7322) (xy 69.2404 -41.7322) (xy 69.2404 -41.9354) (xy 69.4436 -41.9354)
			)
		)
		(polygon
			(pts
				(xy 69.4436 -40.8686) (xy 69.2404 -40.8686) (xy 69.2404 -41.0718) (xy 69.4436 -41.0718)
			)
		)
		(polygon
			(pts
				(xy 69.5706 -36.1442) (xy 69.3674 -36.1442) (xy 69.3674 -36.3474) (xy 69.5706 -36.3474)
			)
		)
		(polygon
			(pts
				(xy 69.5706 -35.2806) (xy 69.3674 -35.2806) (xy 69.3674 -35.4838) (xy 69.5706 -35.4838)
			)
		)
	)
	(zone
		(layer "F.Cu")
		(hatch none 0.5)
		(connect_pads
			(clearance 0)
		)
		(min_thickness 0.25)
		(keepout
			(tracks allowed)
			(vias allowed)
			(pads allowed)
			(copperpour allowed)
			(footprints allowed)
		)
		(placement
			(enabled no)
			(sheetname "")
		)
		(fill
			(thermal_gap 0.5)
			(thermal_bridge_width 0.5)
			(island_removal_mode 0)
		)
		(polygon
			(pts
				(xy 152.4 -99.0854) (xy 152.4 -98.2726) (xy 153.797 -98.2726) (xy 153.797 -99.0854)
			)
		)
	)
	(zone
		(layer "F.Cu")
		(hatch none 0.5)
		(connect_pads
			(clearance 0)
		)
		(min_thickness 0.25)
		(keepout
			(tracks allowed)
			(vias allowed)
			(pads allowed)
			(copperpour allowed)
			(footprints allowed)
		)
		(placement
			(enabled no)
			(sheetname "")
		)
		(fill
			(thermal_gap 0.5)
			(thermal_bridge_width 0.5)
			(island_removal_mode 0)
		)
		(polygon
			(pts
				(xy 70.941692 -19.413982) (xy 70.941692 -14.486382) (xy 74.142092 -14.486382) (xy 74.142092 -15.375382)
				(xy 73.380092 -15.375382) (xy 73.227692 -15.527782) (xy 73.227692 -19.413982)
			)
		)
	)
	(zone
		(layer "F.Cu")
		(hatch none 0.5)
		(connect_pads
			(clearance 0)
		)
		(min_thickness 0.25)
		(keepout
			(tracks allowed)
			(vias allowed)
			(pads allowed)
			(copperpour allowed)
			(footprints not_allowed)
		)
		(placement
			(enabled no)
			(sheetname "")
		)
		(fill
			(thermal_gap 0.5)
			(thermal_bridge_width 0.5)
			(island_removal_mode 0)
		)
		(polygon
			(pts
				(xy 205.000098 -105.000044) (xy 205.000098 0) (xy 4.99999 0) (xy 4.99999 -105.000044) (xy 19.99996 -105.000044)
				(xy 19.99996 -125.000004) (xy 85.002624 -125.000004) (xy 85.002624 -119.000016) (xy 125.002544 -119.000016)
				(xy 125.002544 -125.000004) (xy 189.999874 -125.000004) (xy 189.999874 -105.000044)
			)
		)
	)
	(zone
		(layer "F.Cu")
		(hatch none 0.5)
		(connect_pads
			(clearance 0)
		)
		(min_thickness 0.25)
		(keepout
			(tracks not_allowed)
			(vias allowed)
			(pads allowed)
			(copperpour not_allowed)
			(footprints allowed)
		)
		(placement
			(enabled no)
			(sheetname "")
		)
		(fill
			(thermal_gap 0.5)
			(thermal_bridge_width 0.5)
			(island_removal_mode 0)
		)
		(polygon
			(pts
				(arc
					(start 130.24993 -134.999984)
					(mid 134.999984 -130.24993)
					(end 139.750038 -134.999984)
				)
				(arc
					(start 139.750038 -134.999984)
					(mid 134.999984 -139.750038)
					(end 130.24993 -134.999984)
				)
			)
		)
	)
	(zone
		(net "P3V3")
		(layer "F.Cu")
		(hatch none 0.5)
		(connect_pads
			(clearance 0.5)
		)
		(min_thickness 0.25)
		(fill yes
			(thermal_gap 0.5)
			(thermal_bridge_width 0.5)
			(island_removal_mode 0)
		)
		(polygon
			(pts
				(xy 57.7342 -71.1962) (xy 57.3151 -71.6153) (xy 57.3151 -72.4535) (xy 57.404 -72.5424) (xy 58.674 -72.5424)
				(xy 58.9026 -72.3138) (xy 58.9026 -71.3486) (xy 58.7502 -71.1962)
			)
		)
		(polygon
			(pts
				(xy 58.42 -71.882) (xy 58.2168 -71.882) (xy 58.2168 -72.0852) (xy 58.42 -72.0852)
			)
		)
		(polygon
			(pts
				(xy 57.9374 -71.882) (xy 57.7342 -71.882) (xy 57.7342 -72.0852) (xy 57.9374 -72.0852)
			)
		)
	)
	(zone
		(layer "F.Cu")
		(hatch none 0.5)
		(connect_pads
			(clearance 0)
		)
		(min_thickness 0.25)
		(keepout
			(tracks not_allowed)
			(vias allowed)
			(pads allowed)
			(copperpour not_allowed)
			(footprints allowed)
		)
		(placement
			(enabled no)
			(sheetname "")
		)
		(fill
			(thermal_gap 0.5)
			(thermal_bridge_width 0.5)
			(island_removal_mode 0)
		)
		(polygon
			(pts
				(arc
					(start 126.000256 -60.641992)
					(mid 125.683093 -60.8333)
					(end 125.704854 -61.203078)
				)
				(arc
					(start 125.78969 -61.118242)
					(mid 126.170562 -60.829572)
					(end 125.881892 -61.210444)
				)
				(arc
					(start 125.797056 -61.29528)
					(mid 125.893753 -61.342165)
					(end 126.000002 -61.358272)
				)
				(xy 126.549658 -61.358272)
				(arc
					(start 126.789688 -61.118242)
					(mid 127.17056 -60.829572)
					(end 126.88189 -61.210444)
				)
				(xy 126.734062 -61.358272)
				(arc
					(start 127 -61.358272)
					(mid 127.35814 -61.000132)
					(end 127 -60.641992)
				)
			)
		)
	)
	(zone
		(layer "F.Cu")
		(hatch none 0.5)
		(connect_pads
			(clearance 0)
		)
		(min_thickness 0.25)
		(keepout
			(tracks allowed)
			(vias allowed)
			(pads allowed)
			(copperpour allowed)
			(footprints allowed)
		)
		(placement
			(enabled no)
			(sheetname "")
		)
		(fill
			(thermal_gap 0.5)
			(thermal_bridge_width 0.5)
			(island_removal_mode 0)
		)
		(polygon
			(pts
				(xy 46.2534 -33.9344) (xy 46.2534 -33.0962) (xy 47.9806 -33.0962) (xy 47.9806 -33.9344)
			)
		)
	)
	(zone
		(layer "F.Cu")
		(hatch none 0.5)
		(connect_pads
			(clearance 0)
		)
		(min_thickness 0.25)
		(keepout
			(tracks allowed)
			(vias allowed)
			(pads allowed)
			(copperpour allowed)
			(footprints allowed)
		)
		(placement
			(enabled no)
			(sheetname "")
		)
		(fill
			(thermal_gap 0.5)
			(thermal_bridge_width 0.5)
			(island_removal_mode 0)
		)
		(polygon
			(pts
				(xy 12.40663 -87.857076) (xy 12.40663 -86.451694) (xy 13.379196 -86.451694) (xy 13.379196 -87.857076)
			)
		)
	)
	(zone
		(layer "F.Cu")
		(hatch none 0.5)
		(connect_pads
			(clearance 0)
		)
		(min_thickness 0.25)
		(keepout
			(tracks not_allowed)
			(vias allowed)
			(pads allowed)
			(copperpour not_allowed)
			(footprints allowed)
		)
		(placement
			(enabled no)
			(sheetname "")
		)
		(fill
			(thermal_gap 0.5)
			(thermal_bridge_width 0.5)
			(island_removal_mode 0)
		)
		(polygon
			(pts
				(arc
					(start 172.65269 -23.112984)
					(mid 172.26915 -22.729444)
					(end 171.88561 -23.112984)
				)
				(xy 171.88561 -23.316184) (xy 171.975526 -23.316184)
				(arc
					(start 171.980098 -23.316184)
					(mid 172.027923 -23.310414)
					(end 172.073062 -23.293578)
				)
				(arc
					(start 172.073062 -23.293578)
					(mid 172.387807 -22.87438)
					(end 172.244766 -23.378668)
				)
				(arc
					(start 172.244766 -23.378668)
					(mid 172.140378 -23.452023)
					(end 172.017436 -23.48611)
				)
				(xy 172.015658 -23.487888) (xy 171.98975 -23.487888) (xy 171.980098 -23.487888) (xy 171.975526 -23.487888)
				(xy 171.88561 -23.487888) (xy 171.88561 -23.627588) (xy 171.97578 -23.627588) (xy 171.980352 -23.627334)
				(xy 171.990004 -23.627588) (xy 172.015912 -23.627588)
				(arc
					(start 172.01769 -23.629112)
					(mid 172.140361 -23.663126)
					(end 172.244512 -23.7363)
				)
				(arc
					(start 172.244512 -23.7363)
					(mid 172.387561 -24.241095)
					(end 172.072808 -23.82139)
				)
				(arc
					(start 172.072808 -23.82139)
					(mid 172.027905 -23.80475)
					(end 171.980352 -23.799038)
				)
				(xy 171.97578 -23.798784) (xy 171.88561 -23.798784)
				(arc
					(start 171.88561 -24.00173)
					(mid 172.269023 -24.385524)
					(end 172.65269 -24.001984)
				)
			)
		)
	)
	(zone
		(layer "F.Cu")
		(hatch none 0.5)
		(connect_pads
			(clearance 0)
		)
		(min_thickness 0.25)
		(keepout
			(tracks not_allowed)
			(vias allowed)
			(pads allowed)
			(copperpour not_allowed)
			(footprints allowed)
		)
		(placement
			(enabled no)
			(sheetname "")
		)
		(fill
			(thermal_gap 0.5)
			(thermal_bridge_width 0.5)
			(island_removal_mode 0)
		)
		(polygon
			(pts
				(xy 138.843512 -81.924906) (xy 138.843258 -81.92516)
				(arc
					(start 138.843258 -81.925668)
					(mid 138.46048 -82.308446)
					(end 138.843258 -82.691224)
				)
				(xy 138.843258 -82.691986) (xy 139.986258 -82.691986)
				(arc
					(start 139.986258 -82.691224)
					(mid 140.369036 -82.308446)
					(end 139.986258 -81.925668)
				)
				(xy 139.986258 -81.924906) (xy 139.692888 -81.924906)
				(arc
					(start 139.692888 -82.183224)
					(mid 139.69678 -82.202319)
					(end 139.70762 -82.21853)
				)
				(arc
					(start 139.70762 -82.21853)
					(mid 139.718283 -82.226788)
					(end 139.730734 -82.231992)
				)
				(arc
					(start 139.730734 -82.231992)
					(mid 140.252973 -82.309249)
					(end 139.730226 -82.383376)
				)
				(xy 139.712446 -82.383376)
				(arc
					(start 139.709398 -82.380582)
					(mid 139.651101 -82.360997)
					(end 139.601448 -82.324702)
				)
				(arc
					(start 139.601448 -82.324448)
					(mid 139.565347 -82.275154)
					(end 139.545822 -82.21726)
				)
				(xy 139.543028 -82.214212) (xy 139.543028 -81.924906) (xy 139.286488 -81.924906) (xy 139.286488 -82.213196)
				(arc
					(start 139.28344 -82.216244)
					(mid 139.271024 -82.259176)
					(end 139.249404 -82.298286)
				)
				(xy 139.249404 -82.30235) (xy 139.227814 -82.324194) (xy 139.227306 -82.324448) (xy 139.22629 -82.325464)
				(xy 139.205208 -82.346546)
				(arc
					(start 139.201398 -82.346546)
					(mid 139.162543 -82.368151)
					(end 139.119864 -82.380582)
				)
				(xy 139.116816 -82.383376)
				(arc
					(start 139.09929 -82.383376)
					(mid 138.576488 -82.30937)
					(end 139.098782 -82.231738)
				)
				(arc
					(start 139.098782 -82.231738)
					(mid 139.110514 -82.226935)
					(end 139.120626 -82.219292)
				)
				(arc
					(start 139.121642 -82.218276)
					(mid 139.132728 -82.201729)
					(end 139.136628 -82.182208)
				)
				(xy 139.136628 -81.924906)
			)
		)
	)
	(zone
		(layer "F.Cu")
		(hatch none 0.5)
		(connect_pads
			(clearance 0)
		)
		(min_thickness 0.25)
		(keepout
			(tracks not_allowed)
			(vias allowed)
			(pads allowed)
			(copperpour not_allowed)
			(footprints allowed)
		)
		(placement
			(enabled no)
			(sheetname "")
		)
		(fill
			(thermal_gap 0.5)
			(thermal_bridge_width 0.5)
			(island_removal_mode 0)
		)
		(polygon
			(pts
				(arc
					(start 125.139958 -45.858938)
					(mid 124.682758 -45.401738)
					(end 124.225558 -45.858938)
				)
				(arc
					(start 124.225558 -47.001684)
					(mid 124.682631 -47.459138)
					(end 125.139958 -47.001938)
				)
				(xy 125.139958 -46.708568)
				(arc
					(start 124.793756 -46.708568)
					(mid 124.780007 -46.711396)
					(end 124.768356 -46.719236)
				)
				(arc
					(start 124.768356 -46.719236)
					(mid 124.760487 -46.730875)
					(end 124.757688 -46.744636)
				)
				(arc
					(start 124.757688 -46.745906)
					(mid 124.682758 -47.268709)
					(end 124.607828 -46.745906)
				)
				(xy 124.607828 -46.713648)
				(arc
					(start 124.610876 -46.710346)
					(mid 124.62918 -46.657829)
					(end 124.662184 -46.613064)
				)
				(arc
					(start 124.662184 -46.613064)
					(mid 124.706947 -46.580056)
					(end 124.759466 -46.561756)
				)
				(xy 124.762768 -46.558708) (xy 125.139958 -46.558708) (xy 125.139958 -46.302168) (xy 124.762768 -46.302168)
				(arc
					(start 124.759466 -46.29912)
					(mid 124.706949 -46.280816)
					(end 124.662184 -46.247812)
				)
				(arc
					(start 124.662184 -46.247812)
					(mid 124.629176 -46.203049)
					(end 124.610876 -46.15053)
				)
				(xy 124.607828 -46.147228)
				(arc
					(start 124.607828 -46.11497)
					(mid 124.682758 -45.592167)
					(end 124.757688 -46.11497)
				)
				(arc
					(start 124.757688 -46.11624)
					(mid 124.760516 -46.129989)
					(end 124.768356 -46.14164)
				)
				(arc
					(start 124.768356 -46.14164)
					(mid 124.779995 -46.149509)
					(end 124.793756 -46.152308)
				)
				(xy 125.139958 -46.152308)
			)
		)
	)
	(zone
		(net "AGND_P1V5_E")
		(layer "F.Cu")
		(hatch none 0.5)
		(connect_pads
			(clearance 0.5)
		)
		(min_thickness 0.25)
		(fill yes
			(thermal_gap 0.5)
			(thermal_bridge_width 0.5)
			(island_removal_mode 0)
		)
		(polygon
			(pts
				(xy 156.266388 -120.664986) (xy 156.154374 -120.777) (xy 152.2222 -120.777) (xy 151.6507 -121.3485)
				(xy 150.7744 -121.3485) (xy 150.6982 -121.4247) (xy 150.6982 -123.2662) (xy 151.638 -124.206) (xy 159.01924 -124.206)
				(xy 159.263334 -123.961906) (xy 159.263334 -120.865392) (xy 159.062928 -120.664986)
			)
		)
		(polygon
			(pts
				(xy 151.3586 -121.8692) (xy 151.1554 -121.8692) (xy 151.1554 -122.0724) (xy 151.3586 -122.0724)
			)
		)
		(polygon
			(pts
				(xy 158.806642 -121.546874) (xy 158.603442 -121.546874) (xy 158.603442 -121.750074) (xy 158.806642 -121.750074)
			)
		)
		(polygon
			(pts
				(xy 158.242 -121.1326) (xy 158.0388 -121.1326) (xy 158.0388 -121.3358) (xy 158.242 -121.3358)
			)
		)
		(polygon
			(pts
				(xy 157.6832 -121.1326) (xy 157.48 -121.1326) (xy 157.48 -121.3358) (xy 157.6832 -121.3358)
			)
		)
		(polygon
			(pts
				(xy 157.099 -121.1326) (xy 156.8958 -121.1326) (xy 156.8958 -121.3358) (xy 157.099 -121.3358)
			)
		)
		(polygon
			(pts
				(xy 156.5402 -121.1326) (xy 156.337 -121.1326) (xy 156.337 -121.3358) (xy 156.5402 -121.3358)
			)
		)
		(polygon
			(pts
				(xy 158.806642 -120.988074) (xy 158.603442 -120.988074) (xy 158.603442 -121.191274) (xy 158.806642 -121.191274)
			)
		)
	)
	(zone
		(layer "F.Cu")
		(hatch none 0.5)
		(connect_pads
			(clearance 0)
		)
		(min_thickness 0.25)
		(keepout
			(tracks allowed)
			(vias allowed)
			(pads allowed)
			(copperpour allowed)
			(footprints allowed)
		)
		(placement
			(enabled no)
			(sheetname "")
		)
		(fill
			(thermal_gap 0.5)
			(thermal_bridge_width 0.5)
			(island_removal_mode 0)
		)
		(polygon
			(pts
				(xy 148.57603 -44.10075) (xy 148.369782 -44.96562) (xy 147.999196 -44.877228) (xy 148.205444 -44.012358)
			)
		)
	)
	(zone
		(layer "F.Cu")
		(hatch none 0.5)
		(connect_pads
			(clearance 0)
		)
		(min_thickness 0.25)
		(keepout
			(tracks allowed)
			(vias allowed)
			(pads allowed)
			(copperpour allowed)
			(footprints allowed)
		)
		(placement
			(enabled no)
			(sheetname "")
		)
		(fill
			(thermal_gap 0.5)
			(thermal_bridge_width 0.5)
			(island_removal_mode 0)
		)
		(polygon
			(pts
				(xy 195.73494 -97.26803) (xy 196.991478 -97.26803) (xy 196.991478 -99.8728) (xy 195.73494 -99.8728)
			)
		)
	)
	(zone
		(layer "F.Cu")
		(hatch none 0.5)
		(connect_pads
			(clearance 0)
		)
		(min_thickness 0.25)
		(keepout
			(tracks allowed)
			(vias allowed)
			(pads allowed)
			(copperpour allowed)
			(footprints allowed)
		)
		(placement
			(enabled no)
			(sheetname "")
		)
		(fill
			(thermal_gap 0.5)
			(thermal_bridge_width 0.5)
			(island_removal_mode 0)
		)
		(polygon
			(pts
				(xy 157.0228 -77.1906) (xy 157.0228 -74.8538) (xy 159.0294 -74.8538) (xy 159.0294 -77.1906)
			)
		)
	)
	(zone
		(layer "F.Cu")
		(hatch none 0.5)
		(connect_pads
			(clearance 0)
		)
		(min_thickness 0.25)
		(keepout
			(tracks allowed)
			(vias allowed)
			(pads allowed)
			(copperpour allowed)
			(footprints not_allowed)
		)
		(placement
			(enabled no)
			(sheetname "")
		)
		(fill
			(thermal_gap 0.5)
			(thermal_bridge_width 0.5)
			(island_removal_mode 0)
		)
		(polygon
			(pts
				(arc
					(start 201.499978 -50.500026)
					(mid 198.499984 -53.50002)
					(end 195.49999 -50.500026)
				)
				(arc
					(start 195.49999 -50.500026)
					(mid 198.499984 -47.500032)
					(end 201.499978 -50.500026)
				)
			)
		)
	)
	(zone
		(layer "F.Cu")
		(hatch none 0.5)
		(connect_pads
			(clearance 0)
		)
		(min_thickness 0.25)
		(keepout
			(tracks allowed)
			(vias allowed)
			(pads allowed)
			(copperpour allowed)
			(footprints allowed)
		)
		(placement
			(enabled no)
			(sheetname "")
		)
		(fill
			(thermal_gap 0.5)
			(thermal_bridge_width 0.5)
			(island_removal_mode 0)
		)
		(polygon
			(pts
				(xy 16.1036 -53.2384) (xy 16.1036 -51.2318) (xy 18.2118 -51.2318) (xy 18.2118 -53.2384)
			)
		)
	)
	(zone
		(layer "F.Cu")
		(hatch none 0.5)
		(connect_pads
			(clearance 0)
		)
		(min_thickness 0.25)
		(keepout
			(tracks allowed)
			(vias allowed)
			(pads allowed)
			(copperpour allowed)
			(footprints allowed)
		)
		(placement
			(enabled no)
			(sheetname "")
		)
		(fill
			(thermal_gap 0.5)
			(thermal_bridge_width 0.5)
			(island_removal_mode 0)
		)
		(polygon
			(pts
				(xy 13.208 -94.488) (xy 13.208 -92.1512) (xy 14.859 -92.1512) (xy 14.859 -94.488)
			)
		)
	)
	(zone
		(layer "F.Cu")
		(hatch none 0.5)
		(connect_pads
			(clearance 0)
		)
		(min_thickness 0.25)
		(keepout
			(tracks not_allowed)
			(vias allowed)
			(pads allowed)
			(copperpour not_allowed)
			(footprints allowed)
		)
		(placement
			(enabled no)
			(sheetname "")
		)
		(fill
			(thermal_gap 0.5)
			(thermal_bridge_width 0.5)
			(island_removal_mode 0)
		)
		(polygon
			(pts
				(arc
					(start 4.99999 -123.63577)
					(mid 18.50018 -131.430014)
					(end 4.99999 -139.224258)
				)
			)
		)
	)
	(zone
		(net "P1V8_E")
		(layer "F.Cu")
		(hatch none 0.5)
		(connect_pads
			(clearance 0.5)
		)
		(min_thickness 0.25)
		(fill yes
			(thermal_gap 0.5)
			(thermal_bridge_width 0.5)
			(island_removal_mode 0)
		)
		(polygon
			(pts
				(xy 159.9692 -97.4852) (xy 159.8676 -97.5868) (xy 159.8676 -98.7044) (xy 160.4772 -99.314) (xy 162.1282 -99.314)
				(xy 162.3822 -99.06) (xy 162.3822 -97.6884) (xy 162.179 -97.4852)
			)
		)
		(polygon
			(pts
				(xy 160.535112 -98.045016) (xy 160.331912 -98.045016) (xy 160.331912 -98.248216) (xy 160.535112 -98.248216)
			)
		)
	)
	(zone
		(layer "F.Cu")
		(hatch none 0.5)
		(connect_pads
			(clearance 0)
		)
		(min_thickness 0.25)
		(keepout
			(tracks not_allowed)
			(vias allowed)
			(pads allowed)
			(copperpour not_allowed)
			(footprints allowed)
		)
		(placement
			(enabled no)
			(sheetname "")
		)
		(fill
			(thermal_gap 0.5)
			(thermal_bridge_width 0.5)
			(island_removal_mode 0)
		)
		(polygon
			(pts
				(arc
					(start 101.358192 -52.00015)
					(mid 101.000052 -51.64201)
					(end 100.641912 -52.00015)
				)
				(arc
					(start 100.641912 -52.999894)
					(mid 100.83322 -53.317057)
					(end 101.202998 -53.295296)
				)
				(arc
					(start 101.118162 -53.21046)
					(mid 100.829492 -52.829588)
					(end 101.210364 -53.118258)
				)
				(arc
					(start 101.2952 -53.203094)
					(mid 101.342085 -53.106397)
					(end 101.358192 -53.000148)
				)
				(xy 101.358192 -52.450492)
				(arc
					(start 101.118162 -52.210462)
					(mid 100.829492 -51.82959)
					(end 101.210364 -52.11826)
				)
				(xy 101.358192 -52.266088)
			)
		)
	)
	(zone
		(layer "F.Cu")
		(hatch none 0.5)
		(connect_pads
			(clearance 0)
		)
		(min_thickness 0.25)
		(keepout
			(tracks allowed)
			(vias allowed)
			(pads allowed)
			(copperpour allowed)
			(footprints allowed)
		)
		(placement
			(enabled no)
			(sheetname "")
		)
		(fill
			(thermal_gap 0.5)
			(thermal_bridge_width 0.5)
			(island_removal_mode 0)
		)
		(polygon
			(pts
				(xy 152.527 -86.9442) (xy 152.527 -85.6234) (xy 152.527 -84.8614) (xy 152.7175 -84.6709) (xy 153.67 -84.6709)
				(xy 153.68905 -84.68995) (xy 154.92095 -84.68995) (xy 155.1686 -84.9376) (xy 155.1686 -85.6234)
				(xy 155.1686 -86.9442)
			)
		)
	)
	(zone
		(net "P12V_STBY_SCC")
		(layer "F.Cu")
		(hatch none 0.5)
		(connect_pads
			(clearance 0.5)
		)
		(min_thickness 0.25)
		(fill yes
			(thermal_gap 0.5)
			(thermal_bridge_width 0.5)
			(island_removal_mode 0)
		)
		(polygon
			(pts
				(xy 166.3192 -75.69073) (xy 165.85184 -76.15809) (xy 165.85184 -81.0006) (xy 165.92804 -81.0768)
				(xy 169.418 -81.0768) (xy 169.552874 -80.941926) (xy 169.552874 -79.853282) (xy 169.551096 -79.851504)
				(xy 169.551096 -76.101702) (xy 169.140124 -75.69073)
			)
		)
	)
	(zone
		(net "P3V3_OUT")
		(layer "F.Cu")
		(hatch none 0.5)
		(connect_pads
			(clearance 0.5)
		)
		(min_thickness 0.25)
		(fill yes
			(thermal_gap 0.5)
			(thermal_bridge_width 0.5)
			(island_removal_mode 0)
		)
		(polygon
			(pts
				(xy 56.448198 -110.099602) (xy 56.0324 -110.5154) (xy 56.0324 -123.19) (xy 56.0832 -123.2408) (xy 63.4492 -123.2408)
				(xy 63.7794 -122.9106) (xy 63.7794 -110.7694) (xy 63.109602 -110.099602)
			)
		)
		(polygon
			(pts
				(xy 56.7436 -122.5296) (xy 56.5404 -122.5296) (xy 56.5404 -122.7328) (xy 56.7436 -122.7328)
			)
		)
	)
	(zone
		(net "GND")
		(layer "F.Cu")
		(hatch none 0.5)
		(connect_pads
			(clearance 0.5)
		)
		(min_thickness 0.25)
		(fill yes
			(thermal_gap 0.5)
			(thermal_bridge_width 0.5)
			(island_removal_mode 0)
		)
		(polygon
			(pts
				(xy 51.308 -113.538) (xy 50.546 -114.3) (xy 50.546 -122.936) (xy 50.9016 -123.2916) (xy 55.6514 -123.2916)
				(xy 55.7276 -123.2154) (xy 55.7276 -114.0079) (xy 55.2577 -113.538)
			)
		)
		(polygon
			(pts
				(xy 55.2196 -122.5296) (xy 55.0164 -122.5296) (xy 55.0164 -122.7328) (xy 55.2196 -122.7328)
			)
		)
	)
	(zone
		(layer "F.Cu")
		(hatch none 0.5)
		(connect_pads
			(clearance 0)
		)
		(min_thickness 0.25)
		(keepout
			(tracks allowed)
			(vias allowed)
			(pads allowed)
			(copperpour allowed)
			(footprints allowed)
		)
		(placement
			(enabled no)
			(sheetname "")
		)
		(fill
			(thermal_gap 0.5)
			(thermal_bridge_width 0.5)
			(island_removal_mode 0)
		)
		(polygon
			(pts
				(xy 197.4342 -101.5746) (xy 197.4342 -100.457) (xy 200.3552 -100.457) (xy 200.3552 -101.5746)
			)
		)
	)
	(zone
		(net "P3V3_LL")
		(layer "F.Cu")
		(hatch none 0.5)
		(connect_pads
			(clearance 0.5)
		)
		(min_thickness 0.25)
		(fill yes
			(thermal_gap 0.5)
			(thermal_bridge_width 0.5)
			(island_removal_mode 0)
		)
		(polygon
			(pts
				(xy 58.7248 -102.489) (xy 57.8358 -103.378) (xy 57.0992 -103.378) (xy 57.023 -103.4542) (xy 57.023 -106.9594)
				(xy 57.526174 -107.462574) (xy 63.75146 -107.462574) (xy 64.008 -107.206034) (xy 64.008 -102.616)
				(xy 63.881 -102.489)
			)
		)
		(polygon
			(pts
				(xy 57.8612 -103.886) (xy 57.658 -103.886) (xy 57.658 -104.0892) (xy 57.8612 -104.0892)
			)
		)
	)
	(zone
		(net "GND")
		(layer "F.Cu")
		(hatch none 0.5)
		(connect_pads
			(clearance 0.5)
		)
		(min_thickness 0.25)
		(fill yes
			(thermal_gap 0.5)
			(thermal_bridge_width 0.5)
			(island_removal_mode 0)
		)
		(polygon
			(pts
				(xy 178.6382 -101.0412) (xy 178.4604 -101.219) (xy 178.4604 -105.4354) (xy 178.661568 -105.636568)
				(xy 180.689504 -105.636568) (xy 180.941472 -105.3846) (xy 180.941472 -101.312472) (xy 180.6702 -101.0412)
			)
		)
	)
	(zone
		(layer "F.Cu")
		(hatch none 0.5)
		(connect_pads
			(clearance 0)
		)
		(min_thickness 0.25)
		(keepout
			(tracks allowed)
			(vias allowed)
			(pads allowed)
			(copperpour allowed)
			(footprints allowed)
		)
		(placement
			(enabled no)
			(sheetname "")
		)
		(fill
			(thermal_gap 0.5)
			(thermal_bridge_width 0.5)
			(island_removal_mode 0)
		)
		(polygon
			(pts
				(xy 192.343278 -70.53453) (xy 193.7512 -70.53453) (xy 193.7512 -72.3265) (xy 192.343278 -72.3265)
			)
		)
	)
	(zone
		(layer "F.Cu")
		(hatch none 0.5)
		(connect_pads
			(clearance 0)
		)
		(min_thickness 0.25)
		(keepout
			(tracks not_allowed)
			(vias allowed)
			(pads allowed)
			(copperpour not_allowed)
			(footprints allowed)
		)
		(placement
			(enabled no)
			(sheetname "")
		)
		(fill
			(thermal_gap 0.5)
			(thermal_bridge_width 0.5)
			(island_removal_mode 0)
		)
		(polygon
			(pts
				(arc
					(start 130.000248 -70.641972)
					(mid 129.893874 -70.658055)
					(end 129.797048 -70.704964)
				)
				(arc
					(start 129.881884 -70.7898)
					(mid 130.170554 -71.170672)
					(end 129.789682 -70.882002)
				)
				(arc
					(start 129.704846 -70.797166)
					(mid 129.682983 -71.166855)
					(end 129.999994 -71.358252)
				)
				(xy 130.307842 -71.358252) (xy 130.399282 -71.266812) (xy 130.601466 -71.266812) (xy 130.692906 -71.358252)
				(arc
					(start 130.999992 -71.358252)
					(mid 131.358132 -71.000112)
					(end 130.999992 -70.641972)
				)
				(xy 130.734054 -70.641972)
				(arc
					(start 130.881882 -70.7898)
					(mid 131.170552 -71.170672)
					(end 130.78968 -70.882002)
				)
				(xy 130.54965 -70.641972)
			)
		)
	)
	(zone
		(net "P1V8_C")
		(layer "F.Cu")
		(hatch none 0.5)
		(connect_pads
			(clearance 0.5)
		)
		(min_thickness 0.25)
		(fill yes
			(thermal_gap 0.5)
			(thermal_bridge_width 0.5)
			(island_removal_mode 0)
		)
		(polygon
			(pts
				(xy 189.738 -21.0312) (xy 189.484 -21.2852) (xy 189.484 -23.0632) (xy 189.5856 -23.1648) (xy 192.4812 -23.1648)
				(xy 192.532 -23.114) (xy 192.532 -21.1074) (xy 192.4558 -21.0312)
			)
		)
		(polygon
			(pts
				(xy 190.0936 -22.5806) (xy 189.8904 -22.5806) (xy 189.8904 -22.7838) (xy 190.0936 -22.7838)
			)
		)
		(polygon
			(pts
				(xy 192.283842 -22.50821) (xy 192.080642 -22.50821) (xy 192.080642 -22.71141) (xy 192.283842 -22.71141)
			)
		)
		(polygon
			(pts
				(xy 191.725042 -22.50821) (xy 191.521842 -22.50821) (xy 191.521842 -22.71141) (xy 191.725042 -22.71141)
			)
		)
		(polygon
			(pts
				(xy 191.140842 -22.50821) (xy 190.937642 -22.50821) (xy 190.937642 -22.71141) (xy 191.140842 -22.71141)
			)
		)
		(polygon
			(pts
				(xy 190.582042 -22.50821) (xy 190.378842 -22.50821) (xy 190.378842 -22.71141) (xy 190.582042 -22.71141)
			)
		)
		(polygon
			(pts
				(xy 190.0936 -22.098) (xy 189.8904 -22.098) (xy 189.8904 -22.3012) (xy 190.0936 -22.3012)
			)
		)
		(polygon
			(pts
				(xy 190.0936 -21.5392) (xy 189.8904 -21.5392) (xy 189.8904 -21.7424) (xy 190.0936 -21.7424)
			)
		)
	)
	(zone
		(layer "F.Cu")
		(hatch none 0.5)
		(connect_pads
			(clearance 0)
		)
		(min_thickness 0.25)
		(keepout
			(tracks allowed)
			(vias allowed)
			(pads allowed)
			(copperpour allowed)
			(footprints allowed)
		)
		(placement
			(enabled no)
			(sheetname "")
		)
		(fill
			(thermal_gap 0.5)
			(thermal_bridge_width 0.5)
			(island_removal_mode 0)
		)
		(polygon
			(pts
				(xy 9.0932 -94.5134) (xy 9.0932 -92.1766) (xy 10.2616 -92.1766) (xy 10.2616 -94.5134)
			)
		)
	)
	(zone
		(layer "F.Cu")
		(hatch none 0.5)
		(connect_pads
			(clearance 0)
		)
		(min_thickness 0.25)
		(keepout
			(tracks allowed)
			(vias allowed)
			(pads allowed)
			(copperpour allowed)
			(footprints not_allowed)
		)
		(placement
			(enabled no)
			(sheetname "")
		)
		(fill
			(thermal_gap 0.5)
			(thermal_bridge_width 0.5)
			(island_removal_mode 0)
		)
		(polygon
			(pts
				(xy 146.99996 -71.000112) (xy 203.000102 -71.000112) (xy 203.000102 -18.999962) (xy 146.99996 -18.999962)
			)
		)
	)
	(zone
		(layer "F.Cu")
		(hatch none 0.5)
		(connect_pads
			(clearance 0)
		)
		(min_thickness 0.25)
		(keepout
			(tracks not_allowed)
			(vias allowed)
			(pads allowed)
			(copperpour not_allowed)
			(footprints allowed)
		)
		(placement
			(enabled no)
			(sheetname "")
		)
		(fill
			(thermal_gap 0.5)
			(thermal_bridge_width 0.5)
			(island_removal_mode 0)
		)
		(polygon
			(pts
				(arc
					(start 138.739118 -64.517524)
					(mid 138.284458 -64.972184)
					(end 138.739118 -65.426844)
				)
				(arc
					(start 139.881864 -65.426844)
					(mid 140.336778 -64.972311)
					(end 139.882118 -64.517524)
				)
				(xy 139.588748 -64.517524)
				(arc
					(start 139.588748 -64.845946)
					(mid 139.592702 -64.865444)
					(end 139.603734 -64.882014)
				)
				(arc
					(start 139.60475 -64.88303)
					(mid 139.61487 -64.890658)
					(end 139.626594 -64.895476)
				)
				(arc
					(start 139.626594 -64.895476)
					(mid 140.148906 -64.973109)
					(end 139.626086 -65.047114)
				)
				(xy 139.60856 -65.047114)
				(arc
					(start 139.605512 -65.04432)
					(mid 139.562847 -65.031854)
					(end 139.523978 -65.010284)
				)
				(xy 139.520168 -65.010284) (xy 139.499086 -64.989202) (xy 139.49807 -64.988186) (xy 139.497562 -64.987932)
				(xy 139.475972 -64.966088)
				(arc
					(start 139.475972 -64.962024)
					(mid 139.45438 -64.922902)
					(end 139.441936 -64.879982)
				)
				(xy 139.438888 -64.876934) (xy 139.438888 -64.517524) (xy 139.182348 -64.517524) (xy 139.182348 -64.87795)
				(arc
					(start 139.179554 -64.880998)
					(mid 139.160015 -64.938884)
					(end 139.123928 -64.988186)
				)
				(arc
					(start 139.123928 -64.98844)
					(mid 139.074288 -65.024758)
					(end 139.015978 -65.04432)
				)
				(xy 139.01293 -65.047114)
				(arc
					(start 138.99515 -65.047114)
					(mid 138.472348 -64.972987)
					(end 138.994642 -64.89573)
				)
				(arc
					(start 138.994642 -64.89573)
					(mid 139.00712 -64.890573)
					(end 139.017756 -64.882268)
				)
				(arc
					(start 139.017756 -64.882268)
					(mid 139.028662 -64.866085)
					(end 139.032488 -64.846962)
				)
				(xy 139.032488 -64.517524)
			)
		)
	)
	(zone
		(layer "F.Cu")
		(hatch none 0.5)
		(connect_pads
			(clearance 0)
		)
		(min_thickness 0.25)
		(keepout
			(tracks not_allowed)
			(vias allowed)
			(pads allowed)
			(copperpour not_allowed)
			(footprints allowed)
		)
		(placement
			(enabled no)
			(sheetname "")
		)
		(fill
			(thermal_gap 0.5)
			(thermal_bridge_width 0.5)
			(island_removal_mode 0)
		)
		(polygon
			(pts
				(xy 166.706042 -29.983684) (xy 166.999412 -29.983684)
				(arc
					(start 167.008048 -29.983684)
					(mid 167.383275 -29.595953)
					(end 166.999666 -29.216604)
				)
				(xy 166.820596 -29.216604) (xy 166.6748 -29.3624) (xy 166.54145 -29.3624) (xy 166.3954 -29.21635)
				(arc
					(start 166.200074 -29.21635)
					(mid 165.861639 -29.418957)
					(end 165.880796 -29.812996)
				)
				(arc
					(start 165.965886 -29.727906)
					(mid 166.388385 -29.411325)
					(end 166.071804 -29.833824)
				)
				(arc
					(start 165.986714 -29.918914)
					(mid 166.088484 -29.966964)
					(end 166.19982 -29.98343)
				)
				(xy 166.53637 -29.98343) (xy 166.53637 -29.973524)
				(arc
					(start 166.771574 -29.73832)
					(mid 167.188238 -29.411572)
					(end 166.86149 -29.828236)
				)
			)
		)
	)
	(zone
		(net "GND")
		(layer "F.Cu")
		(hatch none 0.5)
		(connect_pads
			(clearance 0.5)
		)
		(min_thickness 0.25)
		(fill yes
			(thermal_gap 0.5)
			(thermal_bridge_width 0.5)
			(island_removal_mode 0)
		)
		(polygon
			(pts
				(xy 153.192988 -110.869984) (xy 153.066496 -110.996476) (xy 152.21966 -110.996476) (xy 151.9555 -111.26089)
				(xy 151.9555 -119.6975) (xy 152.4 -120.142) (xy 154.686 -120.142) (xy 155.067 -119.761) (xy 155.067 -111.182658)
				(xy 155.063444 -111.179356) (xy 155.063444 -111.053372) (xy 154.880056 -110.869984)
			)
		)
	)
	(zone
		(layer "F.Cu")
		(hatch none 0.5)
		(connect_pads
			(clearance 0)
		)
		(min_thickness 0.25)
		(keepout
			(tracks not_allowed)
			(vias allowed)
			(pads allowed)
			(copperpour not_allowed)
			(footprints allowed)
		)
		(placement
			(enabled no)
			(sheetname "")
		)
		(fill
			(thermal_gap 0.5)
			(thermal_bridge_width 0.5)
			(island_removal_mode 0)
		)
		(polygon
			(pts
				(arc
					(start 126.000256 -70.641972)
					(mid 125.893882 -70.658055)
					(end 125.797056 -70.704964)
				)
				(arc
					(start 125.881892 -70.7898)
					(mid 126.170562 -71.170672)
					(end 125.78969 -70.882002)
				)
				(arc
					(start 125.704854 -70.797166)
					(mid 125.682991 -71.166855)
					(end 126.000002 -71.358252)
				)
				(arc
					(start 127 -71.358252)
					(mid 127.35814 -71.000112)
					(end 127 -70.641972)
				)
				(xy 126.734062 -70.641972)
				(arc
					(start 126.88189 -70.7898)
					(mid 127.17056 -71.170672)
					(end 126.789688 -70.882002)
				)
				(xy 126.549658 -70.641972)
			)
		)
	)
	(zone
		(layer "F.Cu")
		(hatch none 0.5)
		(connect_pads
			(clearance 0)
		)
		(min_thickness 0.25)
		(keepout
			(tracks allowed)
			(vias allowed)
			(pads allowed)
			(copperpour allowed)
			(footprints allowed)
		)
		(placement
			(enabled no)
			(sheetname "")
		)
		(fill
			(thermal_gap 0.5)
			(thermal_bridge_width 0.5)
			(island_removal_mode 0)
		)
		(polygon
			(pts
				(xy 61.31433 -99.54514) (xy 61.31433 -96.98228) (xy 67.529456 -96.98228) (xy 67.529456 -99.54514)
			)
		)
	)
	(zone
		(layer "F.Cu")
		(hatch none 0.5)
		(connect_pads
			(clearance 0)
		)
		(min_thickness 0.25)
		(keepout
			(tracks not_allowed)
			(vias allowed)
			(pads allowed)
			(copperpour not_allowed)
			(footprints allowed)
		)
		(placement
			(enabled no)
			(sheetname "")
		)
		(fill
			(thermal_gap 0.5)
			(thermal_bridge_width 0.5)
			(island_removal_mode 0)
		)
		(polygon
			(pts
				(arc
					(start 114.358166 -55.000144)
					(mid 114.000026 -54.642004)
					(end 113.641886 -55.000144)
				)
				(arc
					(start 113.641886 -55.999888)
					(mid 113.833194 -56.317051)
					(end 114.202972 -56.29529)
				)
				(arc
					(start 114.118136 -56.210454)
					(mid 113.829466 -55.829582)
					(end 114.210338 -56.118252)
				)
				(arc
					(start 114.295174 -56.203088)
					(mid 114.342059 -56.106391)
					(end 114.358166 -56.000142)
				)
				(xy 114.358166 -55.450486)
				(arc
					(start 114.118136 -55.210456)
					(mid 113.829466 -54.829584)
					(end 114.210338 -55.118254)
				)
				(xy 114.358166 -55.266082)
			)
		)
	)
	(zone
		(net "MB0_CM_GATE_R")
		(layer "F.Cu")
		(hatch none 0.5)
		(connect_pads
			(clearance 0.5)
		)
		(min_thickness 0.25)
		(fill yes
			(thermal_gap 0.5)
			(thermal_bridge_width 0.5)
			(island_removal_mode 0)
		)
		(polygon
			(pts
				(xy 7.736078 -39.81831) (xy 7.643114 -39.911274) (xy 7.643114 -44.181522) (xy 7.802372 -44.34078)
				(xy 8.977122 -44.34078) (xy 9.291066 -44.026836) (xy 9.291066 -41.628568) (xy 9.102598 -41.4401)
				(xy 9.102598 -39.882064) (xy 9.038844 -39.81831)
			)
		)
		(polygon
			(pts
				(xy 8.255 -42.2148) (xy 8.0518 -42.2148) (xy 8.0518 -42.418) (xy 8.255 -42.418)
			)
		)
		(polygon
			(pts
				(xy 8.255 -41.656) (xy 8.0518 -41.656) (xy 8.0518 -41.8592) (xy 8.255 -41.8592)
			)
		)
	)
	(zone
		(layer "F.Cu")
		(hatch none 0.5)
		(connect_pads
			(clearance 0)
		)
		(min_thickness 0.25)
		(keepout
			(tracks not_allowed)
			(vias allowed)
			(pads allowed)
			(copperpour not_allowed)
			(footprints allowed)
		)
		(placement
			(enabled no)
			(sheetname "")
		)
		(fill
			(thermal_gap 0.5)
			(thermal_bridge_width 0.5)
			(island_removal_mode 0)
		)
		(polygon
			(pts
				(arc
					(start 168.543478 -23.123906)
					(mid 168.159938 -22.740366)
					(end 167.776398 -23.123906)
				)
				(xy 167.776398 -23.32736) (xy 167.866314 -23.32736)
				(arc
					(start 167.870886 -23.327106)
					(mid 167.918711 -23.321336)
					(end 167.96385 -23.3045)
				)
				(arc
					(start 167.96385 -23.3045)
					(mid 168.278595 -22.885302)
					(end 168.135554 -23.38959)
				)
				(arc
					(start 168.135554 -23.38959)
					(mid 168.031166 -23.462945)
					(end 167.908224 -23.497032)
				)
				(xy 167.906446 -23.498556) (xy 167.880538 -23.498556) (xy 167.870886 -23.49881) (xy 167.866314 -23.498556)
				(xy 167.776398 -23.498556) (xy 167.776398 -23.638256) (xy 167.866568 -23.638256) (xy 167.87114 -23.638256)
				(xy 167.880792 -23.638256) (xy 167.9067 -23.638256)
				(arc
					(start 167.908478 -23.640034)
					(mid 168.031149 -23.674048)
					(end 168.1353 -23.747222)
				)
				(arc
					(start 168.1353 -23.747222)
					(mid 168.278349 -24.252017)
					(end 167.963596 -23.832312)
				)
				(arc
					(start 167.963596 -23.832312)
					(mid 167.918693 -23.815672)
					(end 167.87114 -23.80996)
				)
				(xy 167.866568 -23.80996) (xy 167.776398 -23.80996)
				(arc
					(start 167.776398 -24.012652)
					(mid 168.159811 -24.396446)
					(end 168.543478 -24.012906)
				)
			)
		)
	)
	(zone
		(net "GB_VDDA")
		(layer "F.Cu")
		(hatch none 0.5)
		(connect_pads
			(clearance 0.5)
		)
		(min_thickness 0.25)
		(fill yes
			(thermal_gap 0.5)
			(thermal_bridge_width 0.5)
			(island_removal_mode 0)
		)
		(polygon
			(pts
				(xy 70.993 -35.179) (xy 70.739 -35.433) (xy 70.739 -62.865) (xy 70.866 -62.992) (xy 71.628 -62.992)
				(xy 72.5932 -62.0268) (xy 78.6384 -62.0268) (xy 78.8416 -61.8236) (xy 78.8416 -36.4236) (xy 78.486 -36.068)
				(xy 72.517 -36.068) (xy 71.628 -35.179)
			)
		)
		(polygon
			(pts
				(xy 71.7296 -61.9506) (xy 71.5264 -61.9506) (xy 71.5264 -62.1538) (xy 71.7296 -62.1538)
			)
		)
		(polygon
			(pts
				(xy 75.8444 -61.0235) (xy 75.6412 -61.0235) (xy 75.6412 -61.2267) (xy 75.8444 -61.2267)
			)
		)
		(polygon
			(pts
				(xy 74.9808 -61.0235) (xy 74.7776 -61.0235) (xy 74.7776 -61.2267) (xy 74.9808 -61.2267)
			)
		)
		(polygon
			(pts
				(xy 75.9714 -58.2803) (xy 75.7682 -58.2803) (xy 75.7682 -58.4835) (xy 75.9714 -58.4835)
			)
		)
		(polygon
			(pts
				(xy 75.1078 -58.2803) (xy 74.9046 -58.2803) (xy 74.9046 -58.4835) (xy 75.1078 -58.4835)
			)
		)
		(polygon
			(pts
				(xy 71.8566 -57.3532) (xy 71.6534 -57.3532) (xy 71.6534 -57.5564) (xy 71.8566 -57.5564)
			)
		)
		(polygon
			(pts
				(xy 71.8566 -56.4896) (xy 71.6534 -56.4896) (xy 71.6534 -56.6928) (xy 71.8566 -56.6928)
			)
		)
		(polygon
			(pts
				(xy 75.1078 -55.9943) (xy 74.9046 -55.9943) (xy 74.9046 -56.1975) (xy 75.1078 -56.1975)
			)
		)
		(polygon
			(pts
				(xy 74.9808 -52.6288) (xy 74.7776 -52.6288) (xy 74.7776 -52.832) (xy 74.9808 -52.832)
			)
		)
		(polygon
			(pts
				(xy 71.8566 -52.2732) (xy 71.6534 -52.2732) (xy 71.6534 -52.4764) (xy 71.8566 -52.4764)
			)
		)
		(polygon
			(pts
				(xy 71.8566 -51.4096) (xy 71.6534 -51.4096) (xy 71.6534 -51.6128) (xy 71.8566 -51.6128)
			)
		)
		(polygon
			(pts
				(xy 75.8444 -50.3428) (xy 75.6412 -50.3428) (xy 75.6412 -50.546) (xy 75.8444 -50.546)
			)
		)
		(polygon
			(pts
				(xy 74.9808 -50.3428) (xy 74.7776 -50.3428) (xy 74.7776 -50.546) (xy 74.9808 -50.546)
			)
		)
		(polygon
			(pts
				(xy 75.8444 -47.5996) (xy 75.6412 -47.5996) (xy 75.6412 -47.8028) (xy 75.8444 -47.8028)
			)
		)
		(polygon
			(pts
				(xy 74.9808 -47.5996) (xy 74.7776 -47.5996) (xy 74.7776 -47.8028) (xy 74.9808 -47.8028)
			)
		)
		(polygon
			(pts
				(xy 71.7296 -46.8122) (xy 71.5264 -46.8122) (xy 71.5264 -47.0154) (xy 71.7296 -47.0154)
			)
		)
		(polygon
			(pts
				(xy 71.7296 -45.9486) (xy 71.5264 -45.9486) (xy 71.5264 -46.1518) (xy 71.7296 -46.1518)
			)
		)
		(polygon
			(pts
				(xy 71.7296 -41.7322) (xy 71.5264 -41.7322) (xy 71.5264 -41.9354) (xy 71.7296 -41.9354)
			)
		)
		(polygon
			(pts
				(xy 75.7682 -40.894) (xy 72.898 -40.894) (xy 71.882 -41.91) (xy 71.882 -46.482) (xy 72.2122 -46.8122)
				(xy 75.8952 -46.8122) (xy 76.2508 -46.4566) (xy 76.2508 -41.3766)
			)
		)
		(polygon
			(pts
				(xy 71.7296 -40.8686) (xy 71.5264 -40.8686) (xy 71.5264 -41.0718) (xy 71.7296 -41.0718)
			)
		)
		(polygon
			(pts
				(xy 75.9714 -39.9034) (xy 75.7682 -39.9034) (xy 75.7682 -40.1066) (xy 75.9714 -40.1066)
			)
		)
		(polygon
			(pts
				(xy 75.1078 -39.9034) (xy 74.9046 -39.9034) (xy 74.9046 -40.1066) (xy 75.1078 -40.1066)
			)
		)
		(polygon
			(pts
				(xy 75.8444 -36.9824) (xy 75.6412 -36.9824) (xy 75.6412 -37.1856) (xy 75.8444 -37.1856)
			)
		)
		(polygon
			(pts
				(xy 74.9808 -36.9824) (xy 74.7776 -36.9824) (xy 74.7776 -37.1856) (xy 74.9808 -37.1856)
			)
		)
		(polygon
			(pts
				(xy 71.8566 -36.1442) (xy 71.6534 -36.1442) (xy 71.6534 -36.3474) (xy 71.8566 -36.3474)
			)
		)
	)
	(zone
		(layer "F.Cu")
		(hatch none 0.5)
		(connect_pads
			(clearance 0)
		)
		(min_thickness 0.25)
		(keepout
			(tracks not_allowed)
			(vias allowed)
			(pads allowed)
			(copperpour not_allowed)
			(footprints allowed)
		)
		(placement
			(enabled no)
			(sheetname "")
		)
		(fill
			(thermal_gap 0.5)
			(thermal_bridge_width 0.5)
			(island_removal_mode 0)
		)
		(polygon
			(pts
				(arc
					(start 126.000256 -64.641984)
					(mid 125.683093 -64.833292)
					(end 125.704854 -65.20307)
				)
				(arc
					(start 125.78969 -65.118234)
					(mid 126.170562 -64.829564)
					(end 125.881892 -65.210436)
				)
				(arc
					(start 125.797056 -65.295272)
					(mid 125.893753 -65.342157)
					(end 126.000002 -65.358264)
				)
				(xy 126.549658 -65.358264)
				(arc
					(start 126.789688 -65.118234)
					(mid 127.17056 -64.829564)
					(end 126.88189 -65.210436)
				)
				(xy 126.734062 -65.358264)
				(arc
					(start 127 -65.358264)
					(mid 127.35814 -65.000124)
					(end 127 -64.641984)
				)
			)
		)
	)
	(zone
		(net "P5V")
		(layer "F.Cu")
		(hatch none 0.5)
		(connect_pads
			(clearance 0.5)
		)
		(min_thickness 0.25)
		(fill yes
			(thermal_gap 0.5)
			(thermal_bridge_width 0.5)
			(island_removal_mode 0)
		)
		(polygon
			(pts
				(xy 23.41626 -113.26876) (xy 23.1267 -113.55832) (xy 23.1267 -119.1641) (xy 23.2029 -119.2403) (xy 24.5618 -119.2403)
				(xy 24.6507 -119.1514) (xy 24.6507 -114.01806) (xy 24.69388 -113.97488) (xy 24.69388 -113.32972)
				(xy 24.63292 -113.26876)
			)
		)
		(polygon
			(pts
				(xy 24.1427 -115.1763) (xy 23.9395 -115.1763) (xy 23.9395 -115.3795) (xy 24.1427 -115.3795)
			)
		)
		(polygon
			(pts
				(xy 24.1427 -114.5667) (xy 23.9395 -114.5667) (xy 23.9395 -114.7699) (xy 24.1427 -114.7699)
			)
		)
	)
	(zone
		(layer "F.Cu")
		(hatch none 0.5)
		(connect_pads
			(clearance 0)
		)
		(min_thickness 0.25)
		(keepout
			(tracks not_allowed)
			(vias allowed)
			(pads allowed)
			(copperpour not_allowed)
			(footprints allowed)
		)
		(placement
			(enabled no)
			(sheetname "")
		)
		(fill
			(thermal_gap 0.5)
			(thermal_bridge_width 0.5)
			(island_removal_mode 0)
		)
		(polygon
			(pts
				(arc
					(start 126.000256 -63.641986)
					(mid 125.683093 -63.833294)
					(end 125.704854 -64.203072)
				)
				(arc
					(start 125.78969 -64.118236)
					(mid 126.170562 -63.829566)
					(end 125.881892 -64.210438)
				)
				(arc
					(start 125.797056 -64.295274)
					(mid 125.893753 -64.342159)
					(end 126.000002 -64.358266)
				)
				(xy 126.549658 -64.358266)
				(arc
					(start 126.789688 -64.118236)
					(mid 127.17056 -63.829566)
					(end 126.88189 -64.210438)
				)
				(xy 126.734062 -64.358266)
				(arc
					(start 127 -64.358266)
					(mid 127.35814 -64.000126)
					(end 127 -63.641986)
				)
			)
		)
	)
	(zone
		(net "P1V5_E_OUT")
		(layer "F.Cu")
		(hatch none 0.5)
		(connect_pads
			(clearance 0.5)
		)
		(min_thickness 0.25)
		(fill yes
			(thermal_gap 0.5)
			(thermal_bridge_width 0.5)
			(island_removal_mode 0)
		)
		(polygon
			(pts
				(xy 137.062972 -105.283762) (xy 136.658858 -105.687876) (xy 136.658858 -106.038142) (xy 136.652 -106.045)
				(xy 136.652 -115.189) (xy 136.8806 -115.4176) (xy 143.7386 -115.4176) (xy 143.9672 -115.189) (xy 143.9672 -108.520738)
				(xy 144.445228 -108.04271) (xy 144.445228 -105.586276) (xy 144.142714 -105.283762)
			)
		)
		(polygon
			(pts
				(xy 137.3886 -106.4768) (xy 137.1854 -106.4768) (xy 137.1854 -106.68) (xy 137.3886 -106.68)
			)
		)
		(polygon
			(pts
				(xy 137.3886 -105.8672) (xy 137.1854 -105.8672) (xy 137.1854 -106.0704) (xy 137.3886 -106.0704)
			)
		)
	)
	(zone
		(layer "F.Cu")
		(hatch none 0.5)
		(connect_pads
			(clearance 0)
		)
		(min_thickness 0.25)
		(keepout
			(tracks not_allowed)
			(vias allowed)
			(pads allowed)
			(copperpour not_allowed)
			(footprints allowed)
		)
		(placement
			(enabled no)
			(sheetname "")
		)
		(fill
			(thermal_gap 0.5)
			(thermal_bridge_width 0.5)
			(island_removal_mode 0)
		)
		(polygon
			(pts
				(arc
					(start 130.000248 -61.64199)
					(mid 129.683085 -61.833298)
					(end 129.704846 -62.203076)
				)
				(arc
					(start 129.789682 -62.11824)
					(mid 130.170554 -61.82957)
					(end 129.881884 -62.210442)
				)
				(arc
					(start 129.797048 -62.295278)
					(mid 129.893745 -62.342163)
					(end 129.999994 -62.35827)
				)
				(xy 130.54965 -62.35827)
				(arc
					(start 130.78968 -62.11824)
					(mid 131.170552 -61.82957)
					(end 130.881882 -62.210442)
				)
				(xy 130.734054 -62.35827)
				(arc
					(start 130.999992 -62.35827)
					(mid 131.358132 -62.00013)
					(end 130.999992 -61.64199)
				)
				(xy 130.69697 -61.64199) (xy 130.603498 -61.735462) (xy 130.399028 -61.735462) (xy 130.305556 -61.64199)
			)
		)
	)
	(zone
		(layer "F.Cu")
		(hatch none 0.5)
		(connect_pads
			(clearance 0)
		)
		(min_thickness 0.25)
		(keepout
			(tracks allowed)
			(vias allowed)
			(pads allowed)
			(copperpour allowed)
			(footprints allowed)
		)
		(placement
			(enabled no)
			(sheetname "")
		)
		(fill
			(thermal_gap 0.5)
			(thermal_bridge_width 0.5)
			(island_removal_mode 0)
		)
		(polygon
			(pts
				(xy 145.317718 -32.240728) (xy 145.11147 -33.105598) (xy 144.740884 -33.017206) (xy 144.947132 -32.152336)
			)
		)
	)
	(zone
		(net "GND")
		(layer "F.Cu")
		(hatch none 0.5)
		(connect_pads
			(clearance 0.5)
		)
		(min_thickness 0.25)
		(fill yes
			(thermal_gap 0.5)
			(thermal_bridge_width 0.5)
			(island_removal_mode 0)
		)
		(polygon
			(pts
				(xy 197.65772 -78.25994) (xy 197.616318 -78.301342) (xy 197.616318 -78.869032) (xy 197.848474 -79.101188)
				(xy 199.907652 -79.101188) (xy 200.002902 -79.005938) (xy 200.002902 -78.388464) (xy 199.874378 -78.25994)
			)
		)
	)
	(zone
		(layer "F.Cu")
		(hatch none 0.5)
		(connect_pads
			(clearance 0)
		)
		(min_thickness 0.25)
		(keepout
			(tracks allowed)
			(vias allowed)
			(pads allowed)
			(copperpour allowed)
			(footprints allowed)
		)
		(placement
			(enabled no)
			(sheetname "")
		)
		(fill
			(thermal_gap 0.5)
			(thermal_bridge_width 0.5)
			(island_removal_mode 0)
		)
		(polygon
			(pts
				(xy 125.301756 -44.654216) (xy 125.301756 -44.273216) (xy 126.317756 -44.273216) (xy 126.317756 -44.654216)
			)
		)
	)
	(zone
		(layer "F.Cu")
		(hatch none 0.5)
		(connect_pads
			(clearance 0)
		)
		(min_thickness 0.25)
		(keepout
			(tracks allowed)
			(vias allowed)
			(pads allowed)
			(copperpour allowed)
			(footprints allowed)
		)
		(placement
			(enabled no)
			(sheetname "")
		)
		(fill
			(thermal_gap 0.5)
			(thermal_bridge_width 0.5)
			(island_removal_mode 0)
		)
		(polygon
			(pts
				(xy 42.4434 -34.5948) (xy 42.4434 -33.528) (xy 43.9674 -33.528) (xy 43.9674 -34.5948)
			)
		)
	)
	(zone
		(layer "F.Cu")
		(hatch none 0.5)
		(connect_pads
			(clearance 0)
		)
		(min_thickness 0.25)
		(keepout
			(tracks not_allowed)
			(vias allowed)
			(pads allowed)
			(copperpour not_allowed)
			(footprints allowed)
		)
		(placement
			(enabled no)
			(sheetname "")
		)
		(fill
			(thermal_gap 0.5)
			(thermal_bridge_width 0.5)
			(island_removal_mode 0)
		)
		(polygon
			(pts
				(xy 138.500866 -79.813912) (xy 138.500612 -79.814166)
				(arc
					(start 138.500612 -79.814674)
					(mid 138.117834 -80.197452)
					(end 138.500612 -80.58023)
				)
				(xy 138.500612 -80.580992) (xy 139.643612 -80.580992)
				(arc
					(start 139.643612 -80.58023)
					(mid 140.02639 -80.197452)
					(end 139.643612 -79.814674)
				)
				(xy 139.643612 -79.813912) (xy 139.350242 -79.813912)
				(arc
					(start 139.350242 -80.07223)
					(mid 139.354134 -80.091325)
					(end 139.364974 -80.107536)
				)
				(arc
					(start 139.364974 -80.107536)
					(mid 139.375637 -80.115794)
					(end 139.388088 -80.120998)
				)
				(arc
					(start 139.388088 -80.120998)
					(mid 139.910327 -80.198255)
					(end 139.38758 -80.272382)
				)
				(xy 139.3698 -80.272382)
				(arc
					(start 139.366752 -80.269588)
					(mid 139.308455 -80.250003)
					(end 139.258802 -80.213708)
				)
				(arc
					(start 139.258802 -80.213454)
					(mid 139.222701 -80.16416)
					(end 139.203176 -80.106266)
				)
				(xy 139.200382 -80.103218) (xy 139.200382 -79.813912) (xy 138.943842 -79.813912) (xy 138.943842 -80.102202)
				(arc
					(start 138.940794 -80.10525)
					(mid 138.928378 -80.148182)
					(end 138.906758 -80.187292)
				)
				(xy 138.906758 -80.191356) (xy 138.885168 -80.2132) (xy 138.88466 -80.213454) (xy 138.883644 -80.21447)
				(xy 138.862562 -80.235552)
				(arc
					(start 138.858752 -80.235552)
					(mid 138.819897 -80.257157)
					(end 138.777218 -80.269588)
				)
				(xy 138.77417 -80.272382)
				(arc
					(start 138.756644 -80.272382)
					(mid 138.233842 -80.198376)
					(end 138.756136 -80.120744)
				)
				(arc
					(start 138.756136 -80.120744)
					(mid 138.767868 -80.115941)
					(end 138.77798 -80.108298)
				)
				(arc
					(start 138.778996 -80.107282)
					(mid 138.790082 -80.090735)
					(end 138.793982 -80.071214)
				)
				(xy 138.793982 -79.813912)
			)
		)
	)
	(zone
		(net "P12V_STBY_VIN_U10")
		(layer "F.Cu")
		(hatch none 0.5)
		(connect_pads
			(clearance 0.5)
		)
		(min_thickness 0.25)
		(fill yes
			(thermal_gap 0.5)
			(thermal_bridge_width 0.5)
			(island_removal_mode 0)
		)
		(polygon
			(pts
				(xy 59.436 -91.186) (xy 59.309 -91.313) (xy 59.309 -98.298) (xy 59.563 -98.552) (xy 63.754 -98.552)
				(xy 64.008 -98.298) (xy 64.008 -91.821) (xy 63.373 -91.186)
			)
		)
		(polygon
			(pts
				(xy 60.2996 -97.917) (xy 60.0964 -97.917) (xy 60.0964 -98.1202) (xy 60.2996 -98.1202)
			)
		)
		(polygon
			(pts
				(xy 60.2996 -97.0534) (xy 60.0964 -97.0534) (xy 60.0964 -97.2566) (xy 60.2996 -97.2566)
			)
		)
		(polygon
			(pts
				(xy 62.5983 -92.5449) (xy 62.3951 -92.5449) (xy 62.3951 -92.7481) (xy 62.5983 -92.7481)
			)
		)
		(polygon
			(pts
				(xy 61.2013 -92.5449) (xy 60.9981 -92.5449) (xy 60.9981 -92.7481) (xy 61.2013 -92.7481)
			)
		)
		(polygon
			(pts
				(xy 62.5983 -91.4019) (xy 62.3951 -91.4019) (xy 62.3951 -91.6051) (xy 62.5983 -91.6051)
			)
		)
		(polygon
			(pts
				(xy 61.2013 -91.4019) (xy 60.9981 -91.4019) (xy 60.9981 -91.6051) (xy 61.2013 -91.6051)
			)
		)
	)
	(zone
		(layer "F.Cu")
		(hatch none 0.5)
		(connect_pads
			(clearance 0)
		)
		(min_thickness 0.25)
		(keepout
			(tracks allowed)
			(vias allowed)
			(pads allowed)
			(copperpour allowed)
			(footprints allowed)
		)
		(placement
			(enabled no)
			(sheetname "")
		)
		(fill
			(thermal_gap 0.5)
			(thermal_bridge_width 0.5)
			(island_removal_mode 0)
		)
		(polygon
			(pts
				(xy 167.386 -98.6282) (xy 167.386 -96.7232) (xy 172.1866 -96.7232) (xy 172.1866 -98.6282)
			)
		)
	)
	(zone
		(layer "F.Cu")
		(hatch none 0.5)
		(connect_pads
			(clearance 0)
		)
		(min_thickness 0.25)
		(keepout
			(tracks not_allowed)
			(vias allowed)
			(pads allowed)
			(copperpour not_allowed)
			(footprints allowed)
		)
		(placement
			(enabled no)
			(sheetname "")
		)
		(fill
			(thermal_gap 0.5)
			(thermal_bridge_width 0.5)
			(island_removal_mode 0)
		)
		(polygon
			(pts
				(arc
					(start 126.000256 -57.641998)
					(mid 125.683093 -57.833306)
					(end 125.704854 -58.203084)
				)
				(arc
					(start 125.78969 -58.118248)
					(mid 126.170562 -57.829578)
					(end 125.881892 -58.21045)
				)
				(arc
					(start 125.797056 -58.295286)
					(mid 125.893753 -58.342171)
					(end 126.000002 -58.358278)
				)
				(xy 126.549658 -58.358278)
				(arc
					(start 126.789688 -58.118248)
					(mid 127.17056 -57.829578)
					(end 126.88189 -58.21045)
				)
				(xy 126.734062 -58.358278)
				(arc
					(start 127 -58.358278)
					(mid 127.35814 -58.000138)
					(end 127 -57.641998)
				)
			)
		)
	)
	(zone
		(layer "F.Cu")
		(hatch none 0.5)
		(connect_pads
			(clearance 0)
		)
		(min_thickness 0.25)
		(keepout
			(tracks not_allowed)
			(vias allowed)
			(pads allowed)
			(copperpour not_allowed)
			(footprints allowed)
		)
		(placement
			(enabled no)
			(sheetname "")
		)
		(fill
			(thermal_gap 0.5)
			(thermal_bridge_width 0.5)
			(island_removal_mode 0)
		)
		(polygon
			(pts
				(arc
					(start 101.358192 -55.000144)
					(mid 101.000052 -54.642004)
					(end 100.641912 -55.000144)
				)
				(xy 100.641912 -55.304436) (xy 100.737416 -55.39994) (xy 100.737416 -55.631334) (xy 100.641912 -55.726838)
				(arc
					(start 100.641912 -55.999888)
					(mid 100.83322 -56.317051)
					(end 101.202998 -56.29529)
				)
				(arc
					(start 101.118162 -56.210454)
					(mid 100.829492 -55.829582)
					(end 101.210364 -56.118252)
				)
				(arc
					(start 101.2952 -56.203088)
					(mid 101.342085 -56.106391)
					(end 101.358192 -56.000142)
				)
				(xy 101.358192 -55.450486)
				(arc
					(start 101.118162 -55.210456)
					(mid 100.829492 -54.829584)
					(end 101.210364 -55.118254)
				)
				(xy 101.358192 -55.266082)
			)
		)
	)
	(zone
		(layer "F.Cu")
		(hatch none 0.5)
		(connect_pads
			(clearance 0)
		)
		(min_thickness 0.25)
		(keepout
			(tracks allowed)
			(vias allowed)
			(pads allowed)
			(copperpour allowed)
			(footprints allowed)
		)
		(placement
			(enabled no)
			(sheetname "")
		)
		(fill
			(thermal_gap 0.5)
			(thermal_bridge_width 0.5)
			(island_removal_mode 0)
		)
		(polygon
			(pts
				(xy 65.307972 -19.363182) (xy 65.307972 -16.721582) (xy 64.876172 -16.721582) (xy 64.876172 -16.264382)
				(xy 64.876172 -14.587982) (xy 67.543172 -14.587982) (xy 67.543172 -19.363182)
			)
		)
	)
	(zone
		(layer "F.Cu")
		(hatch none 0.5)
		(connect_pads
			(clearance 0)
		)
		(min_thickness 0.25)
		(keepout
			(tracks allowed)
			(vias allowed)
			(pads allowed)
			(copperpour allowed)
			(footprints not_allowed)
		)
		(placement
			(enabled no)
			(sheetname "")
		)
		(fill
			(thermal_gap 0.5)
			(thermal_bridge_width 0.5)
			(island_removal_mode 0)
		)
		(polygon
			(pts
				(arc
					(start 205.000098 -139.224258)
					(mid 191.499908 -131.430014)
					(end 205.000098 -123.63577)
				)
			)
		)
	)
	(zone
		(layer "F.Cu")
		(hatch none 0.5)
		(connect_pads
			(clearance 0)
		)
		(min_thickness 0.25)
		(keepout
			(tracks not_allowed)
			(vias allowed)
			(pads allowed)
			(copperpour not_allowed)
			(footprints allowed)
		)
		(placement
			(enabled no)
			(sheetname "")
		)
		(fill
			(thermal_gap 0.5)
			(thermal_bridge_width 0.5)
			(island_removal_mode 0)
		)
		(polygon
			(pts
				(arc
					(start 118.358158 -55.000144)
					(mid 118.000018 -54.642004)
					(end 117.641878 -55.000144)
				)
				(xy 117.641878 -55.266082)
				(arc
					(start 117.789706 -55.118254)
					(mid 118.170578 -54.829584)
					(end 117.881908 -55.210456)
				)
				(xy 117.641878 -55.450486)
				(arc
					(start 117.641878 -55.999888)
					(mid 117.657961 -56.106262)
					(end 117.70487 -56.203088)
				)
				(arc
					(start 117.789706 -56.118252)
					(mid 118.170578 -55.829582)
					(end 117.881908 -56.210454)
				)
				(arc
					(start 117.797072 -56.29529)
					(mid 118.166761 -56.317153)
					(end 118.358158 -56.000142)
				)
			)
		)
	)
	(zone
		(layer "F.Cu")
		(hatch none 0.5)
		(connect_pads
			(clearance 0)
		)
		(min_thickness 0.25)
		(keepout
			(tracks not_allowed)
			(vias allowed)
			(pads allowed)
			(copperpour not_allowed)
			(footprints allowed)
		)
		(placement
			(enabled no)
			(sheetname "")
		)
		(fill
			(thermal_gap 0.5)
			(thermal_bridge_width 0.5)
			(island_removal_mode 0)
		)
		(polygon
			(pts
				(arc
					(start 108.358178 -51.000152)
					(mid 108.000038 -50.642012)
					(end 107.641898 -51.000152)
				)
				(xy 107.641898 -51.308) (xy 107.7468 -51.412902) (xy 107.7468 -51.5874) (xy 107.641898 -51.692302)
				(arc
					(start 107.641898 -51.999896)
					(mid 107.833206 -52.317059)
					(end 108.202984 -52.295298)
				)
				(arc
					(start 108.118148 -52.210462)
					(mid 107.829478 -51.82959)
					(end 108.21035 -52.11826)
				)
				(arc
					(start 108.295186 -52.203096)
					(mid 108.342071 -52.106399)
					(end 108.358178 -52.00015)
				)
				(xy 108.358178 -51.450494)
				(arc
					(start 108.118148 -51.210464)
					(mid 107.829478 -50.829592)
					(end 108.21035 -51.118262)
				)
				(xy 108.358178 -51.26609)
			)
		)
	)
	(zone
		(net "P1V8_C")
		(layer "F.Cu")
		(hatch none 0.5)
		(connect_pads
			(clearance 0.5)
		)
		(min_thickness 0.25)
		(fill yes
			(thermal_gap 0.5)
			(thermal_bridge_width 0.5)
			(island_removal_mode 0)
		)
		(polygon
			(pts
				(xy 185.7756 -116.9416) (xy 185.55335 -117.16385) (xy 185.55335 -121.29135) (xy 185.822082 -121.560082)
				(xy 188.269118 -121.560082) (xy 188.6966 -121.1326) (xy 188.6966 -117.4496) (xy 188.69406 -117.44706)
				(xy 188.69406 -117.251988) (xy 188.383672 -116.9416)
			)
		)
		(polygon
			(pts
				(xy 186.2074 -120.9294) (xy 186.0042 -120.9294) (xy 186.0042 -121.1326) (xy 186.2074 -121.1326)
			)
		)
		(polygon
			(pts
				(xy 186.2074 -120.3706) (xy 186.0042 -120.3706) (xy 186.0042 -120.5738) (xy 186.2074 -120.5738)
			)
		)
		(polygon
			(pts
				(xy 186.2582 -118.0338) (xy 186.055 -118.0338) (xy 186.055 -118.237) (xy 186.2582 -118.237)
			)
		)
		(polygon
			(pts
				(xy 187.579 -117.729) (xy 187.3758 -117.729) (xy 187.3758 -117.9322) (xy 187.579 -117.9322)
			)
		)
		(polygon
			(pts
				(xy 186.7154 -117.729) (xy 186.5122 -117.729) (xy 186.5122 -117.9322) (xy 186.7154 -117.9322)
			)
		)
		(polygon
			(pts
				(xy 186.2582 -117.4242) (xy 186.055 -117.4242) (xy 186.055 -117.6274) (xy 186.2582 -117.6274)
			)
		)
	)
	(zone
		(layer "F.Cu")
		(hatch none 0.5)
		(connect_pads
			(clearance 0)
		)
		(min_thickness 0.25)
		(keepout
			(tracks not_allowed)
			(vias allowed)
			(pads allowed)
			(copperpour not_allowed)
			(footprints allowed)
		)
		(placement
			(enabled no)
			(sheetname "")
		)
		(fill
			(thermal_gap 0.5)
			(thermal_bridge_width 0.5)
			(island_removal_mode 0)
		)
		(polygon
			(pts
				(arc
					(start 180.819552 -23.596346)
					(mid 180.436012 -23.212806)
					(end 180.052472 -23.596346)
				)
				(xy 180.052472 -23.7998) (xy 180.142388 -23.7998)
				(arc
					(start 180.14696 -23.799546)
					(mid 180.194785 -23.793776)
					(end 180.239924 -23.77694)
				)
				(arc
					(start 180.239924 -23.77694)
					(mid 180.554669 -23.357742)
					(end 180.411628 -23.86203)
				)
				(arc
					(start 180.411628 -23.86203)
					(mid 180.30724 -23.935385)
					(end 180.184298 -23.969472)
				)
				(xy 180.18252 -23.970996) (xy 180.156612 -23.970996) (xy 180.14696 -23.97125) (xy 180.142388 -23.970996)
				(xy 180.052472 -23.970996) (xy 180.052472 -24.110696) (xy 180.142642 -24.110696) (xy 180.147214 -24.110696)
				(xy 180.156866 -24.110696) (xy 180.182774 -24.110696)
				(arc
					(start 180.184552 -24.112474)
					(mid 180.307223 -24.146488)
					(end 180.411374 -24.219662)
				)
				(arc
					(start 180.411374 -24.219662)
					(mid 180.554423 -24.724457)
					(end 180.23967 -24.304752)
				)
				(arc
					(start 180.23967 -24.304752)
					(mid 180.194767 -24.288112)
					(end 180.147214 -24.2824)
				)
				(xy 180.142642 -24.2824) (xy 180.052472 -24.2824)
				(arc
					(start 180.052472 -24.485092)
					(mid 180.435885 -24.868886)
					(end 180.819552 -24.485346)
				)
			)
		)
	)
	(zone
		(net "GND")
		(layer "F.Cu")
		(hatch none 0.5)
		(connect_pads
			(clearance 0.5)
		)
		(min_thickness 0.25)
		(fill yes
			(thermal_gap 0.5)
			(thermal_bridge_width 0.5)
			(island_removal_mode 0)
		)
		(polygon
			(pts
				(xy 7.86003 -68.124832) (xy 7.509002 -68.47586) (xy 7.509002 -70.186804) (xy 7.566914 -70.244716)
				(xy 8.920226 -70.244716) (xy 9.476994 -70.801484) (xy 11.620754 -70.801484) (xy 11.657584 -70.7644)
				(xy 11.657584 -69.91985) (xy 9.862312 -68.124832)
			)
		)
		(polygon
			(pts
				(xy 8.1788 -69.596) (xy 7.9756 -69.596) (xy 7.9756 -69.7992) (xy 8.1788 -69.7992)
			)
		)
	)
	(zone
		(layer "F.Cu")
		(hatch none 0.5)
		(connect_pads
			(clearance 0)
		)
		(min_thickness 0.25)
		(keepout
			(tracks allowed)
			(vias allowed)
			(pads allowed)
			(copperpour allowed)
			(footprints allowed)
		)
		(placement
			(enabled no)
			(sheetname "")
		)
		(fill
			(thermal_gap 0.5)
			(thermal_bridge_width 0.5)
			(island_removal_mode 0)
		)
		(polygon
			(pts
				(xy 58.847482 -80.049116) (xy 58.847482 -78.643734) (xy 59.820048 -78.643734) (xy 59.820048 -80.049116)
			)
		)
	)
	(zone
		(layer "F.Cu")
		(hatch none 0.5)
		(connect_pads
			(clearance 0)
		)
		(min_thickness 0.25)
		(keepout
			(tracks not_allowed)
			(vias allowed)
			(pads allowed)
			(copperpour not_allowed)
			(footprints allowed)
		)
		(placement
			(enabled no)
			(sheetname "")
		)
		(fill
			(thermal_gap 0.5)
			(thermal_bridge_width 0.5)
			(island_removal_mode 0)
		)
		(polygon
			(pts
				(arc
					(start 149.649434 -44.43349)
					(mid 149.845887 -43.944217)
					(end 149.804628 -44.469812)
				)
				(xy 149.798024 -44.501562)
				(arc
					(start 149.783038 -44.511214)
					(mid 149.690743 -44.581812)
					(end 149.576282 -44.601892)
				)
				(xy 149.573488 -44.60367) (xy 149.543262 -44.59732) (xy 149.247098 -44.53636) (xy 149.193758 -44.787058)
				(xy 149.202902 -44.788582) (xy 149.203664 -44.789598) (xy 149.52726 -44.856146) (xy 149.530562 -44.856654)
				(xy 149.561042 -44.862496)
				(arc
					(start 149.56409 -44.86656)
					(mid 149.653572 -44.941348)
					(end 149.681692 -45.05452)
				)
				(xy 149.682962 -45.056552) (xy 149.679152 -45.07484)
				(arc
					(start 149.676104 -45.088302)
					(mid 149.489368 -45.582426)
					(end 149.5298 -45.05579)
				)
				(arc
					(start 149.531832 -45.046138)
					(mid 149.525773 -45.019899)
					(end 149.503892 -45.004228)
				)
				(xy 149.498304 -45.002958) (xy 149.468586 -44.99737) (xy 149.468078 -44.996862) (xy 149.176486 -44.937172)
				(xy 149.159214 -44.949364)
				(arc
					(start 149.100286 -45.226986)
					(mid 149.452584 -45.769276)
					(end 149.994874 -45.416978)
				)
				(xy 150.114 -44.856654)
				(arc
					(start 150.230078 -44.309284)
					(mid 149.885514 -43.757915)
					(end 149.33803 -44.108878)
				)
				(xy 149.278848 -44.386754) (xy 149.283166 -44.390818)
				(arc
					(start 149.573234 -44.450508)
					(mid 149.613171 -44.450221)
					(end 149.649434 -44.43349)
				)
			)
		)
	)
	(zone
		(layer "F.Cu")
		(hatch none 0.5)
		(connect_pads
			(clearance 0)
		)
		(min_thickness 0.25)
		(keepout
			(tracks not_allowed)
			(vias allowed)
			(pads allowed)
			(copperpour not_allowed)
			(footprints allowed)
		)
		(placement
			(enabled no)
			(sheetname "")
		)
		(fill
			(thermal_gap 0.5)
			(thermal_bridge_width 0.5)
			(island_removal_mode 0)
		)
		(polygon
			(pts
				(arc
					(start 105.358184 -52.00015)
					(mid 105.000044 -51.64201)
					(end 104.641904 -52.00015)
				)
				(arc
					(start 104.641904 -52.999894)
					(mid 104.833212 -53.317057)
					(end 105.20299 -53.295296)
				)
				(arc
					(start 105.118154 -53.21046)
					(mid 104.829484 -52.829588)
					(end 105.210356 -53.118258)
				)
				(arc
					(start 105.295192 -53.203094)
					(mid 105.342077 -53.106397)
					(end 105.358184 -53.000148)
				)
				(xy 105.358184 -52.450492)
				(arc
					(start 105.118154 -52.210462)
					(mid 104.829484 -51.82959)
					(end 105.210356 -52.11826)
				)
				(xy 105.358184 -52.266088)
			)
		)
	)
	(zone
		(layer "F.Cu")
		(hatch none 0.5)
		(connect_pads
			(clearance 0)
		)
		(min_thickness 0.25)
		(keepout
			(tracks not_allowed)
			(vias allowed)
			(pads allowed)
			(copperpour not_allowed)
			(footprints allowed)
		)
		(placement
			(enabled no)
			(sheetname "")
		)
		(fill
			(thermal_gap 0.5)
			(thermal_bridge_width 0.5)
			(island_removal_mode 0)
		)
		(polygon
			(pts
				(arc
					(start 166.200074 -31.616396)
					(mid 165.861833 -31.819115)
					(end 165.88105 -32.213042)
				)
				(arc
					(start 165.96614 -32.127952)
					(mid 166.388639 -31.811371)
					(end 166.072058 -32.23387)
				)
				(arc
					(start 165.986968 -32.31896)
					(mid 166.088738 -32.36701)
					(end 166.200074 -32.383476)
				)
				(xy 166.52494 -32.383476) (xy 166.52494 -32.368998)
				(arc
					(start 166.765986 -32.127952)
					(mid 167.188485 -31.811371)
					(end 166.871904 -32.23387)
				)
				(xy 166.722298 -32.383476)
				(arc
					(start 166.999666 -32.383476)
					(mid 167.38346 -32.000063)
					(end 166.99992 -31.616396)
				)
				(xy 166.8272 -31.616396) (xy 166.668196 -31.7754) (xy 166.5478 -31.7754) (xy 166.388796 -31.616396)
			)
		)
	)
	(zone
		(layer "F.Cu")
		(hatch none 0.5)
		(connect_pads
			(clearance 0)
		)
		(min_thickness 0.25)
		(keepout
			(tracks allowed)
			(vias allowed)
			(pads allowed)
			(copperpour allowed)
			(footprints not_allowed)
		)
		(placement
			(enabled no)
			(sheetname "")
		)
		(fill
			(thermal_gap 0.5)
			(thermal_bridge_width 0.5)
			(island_removal_mode 0)
		)
		(polygon
			(pts
				(arc
					(start 4.99999 -123.63577)
					(mid 18.50018 -131.430014)
					(end 4.99999 -139.224258)
				)
			)
		)
	)
	(zone
		(net "GND")
		(layer "F.Cu")
		(hatch none 0.5)
		(connect_pads
			(clearance 0.5)
		)
		(min_thickness 0.25)
		(fill yes
			(thermal_gap 0.5)
			(thermal_bridge_width 0.5)
			(island_removal_mode 0)
		)
		(polygon
			(pts
				(xy 175.960532 -111.656368) (xy 175.8569 -111.76) (xy 175.8569 -112.6744) (xy 175.6156 -112.9157)
				(xy 175.6156 -114.4778) (xy 175.5013 -114.5921) (xy 174.9044 -114.5921) (xy 174.8663 -114.6302)
				(xy 174.8663 -117.602) (xy 174.9298 -117.6655) (xy 175.5648 -117.6655) (xy 175.6156 -117.7163) (xy 175.6156 -121.6152)
				(xy 175.8188 -121.8184) (xy 177.0126 -121.8184) (xy 177.2158 -121.6152) (xy 177.2158 -117.7417)
				(xy 177.3047 -117.6528) (xy 177.8381 -117.6528) (xy 177.927 -117.5639) (xy 177.927 -114.6429) (xy 177.8762 -114.5921)
				(xy 177.292 -114.5921) (xy 177.2285 -114.5286) (xy 177.2285 -114.2111) (xy 177.2666 -114.173) (xy 177.2666 -111.784384)
				(xy 177.138584 -111.656368)
			)
		)
		(polygon
			(pts
				(xy 176.56429 -112.266984) (xy 176.36109 -112.266984) (xy 176.36109 -112.470184) (xy 176.56429 -112.470184)
			)
		)
	)
	(zone
		(layer "F.Cu")
		(hatch none 0.5)
		(connect_pads
			(clearance 0)
		)
		(min_thickness 0.25)
		(keepout
			(tracks allowed)
			(vias allowed)
			(pads allowed)
			(copperpour allowed)
			(footprints not_allowed)
		)
		(placement
			(enabled no)
			(sheetname "")
		)
		(fill
			(thermal_gap 0.5)
			(thermal_bridge_width 0.5)
			(island_removal_mode 0)
		)
		(polygon
			(pts
				(arc
					(start 79.749904 -134.999984)
					(mid 75.000104 -139.749784)
					(end 70.25005 -134.999984)
				)
				(arc
					(start 70.25005 -134.999984)
					(mid 75.000104 -130.24993)
					(end 79.749904 -134.999984)
				)
			)
		)
	)
	(zone
		(layer "F.Cu")
		(hatch none 0.5)
		(connect_pads
			(clearance 0)
		)
		(min_thickness 0.25)
		(keepout
			(tracks not_allowed)
			(vias allowed)
			(pads allowed)
			(copperpour not_allowed)
			(footprints allowed)
		)
		(placement
			(enabled no)
			(sheetname "")
		)
		(fill
			(thermal_gap 0.5)
			(thermal_bridge_width 0.5)
			(island_removal_mode 0)
		)
		(polygon
			(pts
				(arc
					(start 126.000256 -68.641976)
					(mid 125.893882 -68.658059)
					(end 125.797056 -68.704968)
				)
				(arc
					(start 125.881892 -68.789804)
					(mid 126.170562 -69.170676)
					(end 125.78969 -68.882006)
				)
				(arc
					(start 125.704854 -68.79717)
					(mid 125.682991 -69.166859)
					(end 126.000002 -69.358256)
				)
				(arc
					(start 127 -69.358256)
					(mid 127.35814 -69.000116)
					(end 127 -68.641976)
				)
				(xy 126.734062 -68.641976)
				(arc
					(start 126.88189 -68.789804)
					(mid 127.17056 -69.170676)
					(end 126.789688 -68.882006)
				)
				(xy 126.549658 -68.641976)
			)
		)
	)
	(zone
		(layer "F.Cu")
		(hatch none 0.5)
		(connect_pads
			(clearance 0)
		)
		(min_thickness 0.25)
		(keepout
			(tracks allowed)
			(vias allowed)
			(pads allowed)
			(copperpour allowed)
			(footprints not_allowed)
		)
		(placement
			(enabled no)
			(sheetname "")
		)
		(fill
			(thermal_gap 0.5)
			(thermal_bridge_width 0.5)
			(island_removal_mode 0)
		)
		(polygon
			(pts
				(arc
					(start 208.000092 0)
					(mid 209.414303 -0.585785)
					(end 210.000088 -1.999996)
				)
				(arc
					(start 210.000088 -142.999968)
					(mid 209.414303 -144.414179)
					(end 208.000092 -144.999964)
				)
				(xy 205.000098 -144.999964) (xy 205.000098 0)
			)
		)
	)
	(zone
		(layer "F.Cu")
		(hatch none 0.5)
		(connect_pads
			(clearance 0)
		)
		(min_thickness 0.25)
		(keepout
			(tracks not_allowed)
			(vias allowed)
			(pads allowed)
			(copperpour not_allowed)
			(footprints allowed)
		)
		(placement
			(enabled no)
			(sheetname "")
		)
		(fill
			(thermal_gap 0.5)
			(thermal_bridge_width 0.5)
			(island_removal_mode 0)
		)
		(polygon
			(pts
				(arc
					(start 99.358196 -54.000146)
					(mid 99.000056 -53.642006)
					(end 98.641916 -54.000146)
				)
				(arc
					(start 98.641916 -54.99989)
					(mid 98.833224 -55.317053)
					(end 99.203002 -55.295292)
				)
				(arc
					(start 99.118166 -55.210456)
					(mid 98.829496 -54.829584)
					(end 99.210368 -55.118254)
				)
				(arc
					(start 99.295204 -55.20309)
					(mid 99.342089 -55.106393)
					(end 99.358196 -55.000144)
				)
				(xy 99.358196 -54.450488)
				(arc
					(start 99.118166 -54.210458)
					(mid 98.829496 -53.829586)
					(end 99.210368 -54.118256)
				)
				(xy 99.358196 -54.266084)
			)
		)
	)
	(zone
		(layer "F.Cu")
		(hatch none 0.5)
		(connect_pads
			(clearance 0)
		)
		(min_thickness 0.25)
		(keepout
			(tracks not_allowed)
			(vias allowed)
			(pads allowed)
			(copperpour not_allowed)
			(footprints allowed)
		)
		(placement
			(enabled no)
			(sheetname "")
		)
		(fill
			(thermal_gap 0.5)
			(thermal_bridge_width 0.5)
			(island_removal_mode 0)
		)
		(polygon
			(pts
				(arc
					(start 130.105658 -45.829474)
					(mid 129.648458 -45.372274)
					(end 129.191258 -45.829474)
				)
				(arc
					(start 129.191258 -46.97222)
					(mid 129.648331 -47.429674)
					(end 130.105658 -46.972474)
				)
				(xy 130.105658 -46.679104)
				(arc
					(start 129.759456 -46.679104)
					(mid 129.745707 -46.681932)
					(end 129.734056 -46.689772)
				)
				(arc
					(start 129.734056 -46.689772)
					(mid 129.726187 -46.701411)
					(end 129.723388 -46.715172)
				)
				(arc
					(start 129.723388 -46.716442)
					(mid 129.648458 -47.239245)
					(end 129.573528 -46.716442)
				)
				(xy 129.573528 -46.684184)
				(arc
					(start 129.576576 -46.680882)
					(mid 129.59488 -46.628365)
					(end 129.627884 -46.5836)
				)
				(arc
					(start 129.627884 -46.5836)
					(mid 129.672647 -46.550592)
					(end 129.725166 -46.532292)
				)
				(xy 129.728468 -46.529244) (xy 130.105658 -46.529244) (xy 130.105658 -46.272704) (xy 129.728468 -46.272704)
				(arc
					(start 129.725166 -46.269656)
					(mid 129.672649 -46.251352)
					(end 129.627884 -46.218348)
				)
				(arc
					(start 129.627884 -46.218348)
					(mid 129.594876 -46.173585)
					(end 129.576576 -46.121066)
				)
				(xy 129.573528 -46.117764)
				(arc
					(start 129.573528 -46.085506)
					(mid 129.648458 -45.562703)
					(end 129.723388 -46.085506)
				)
				(arc
					(start 129.723388 -46.086776)
					(mid 129.726216 -46.100525)
					(end 129.734056 -46.112176)
				)
				(arc
					(start 129.734056 -46.112176)
					(mid 129.745695 -46.120045)
					(end 129.759456 -46.122844)
				)
				(xy 130.105658 -46.122844)
			)
		)
	)
	(zone
		(layer "F.Cu")
		(hatch none 0.5)
		(connect_pads
			(clearance 0)
		)
		(min_thickness 0.25)
		(keepout
			(tracks not_allowed)
			(vias allowed)
			(pads allowed)
			(copperpour not_allowed)
			(footprints allowed)
		)
		(placement
			(enabled no)
			(sheetname "")
		)
		(fill
			(thermal_gap 0.5)
			(thermal_bridge_width 0.5)
			(island_removal_mode 0)
		)
		(polygon
			(pts
				(arc
					(start 170.557952 -30.39999)
					(mid 170.199685 -30.04185)
					(end 169.841672 -30.400244)
				)
				(xy 169.841672 -30.649672) (xy 169.9514 -30.7594) (xy 169.9514 -30.853126) (xy 169.841926 -30.9626)
				(arc
					(start 169.841926 -31.199836)
					(mid 170.025399 -31.512749)
					(end 170.388026 -31.50489)
				)
				(arc
					(start 170.30192 -31.418784)
					(mid 170.029477 -31.029501)
					(end 170.41876 -31.301944)
				)
				(arc
					(start 170.504866 -31.38805)
					(mid 170.544614 -31.297653)
					(end 170.558206 -31.199836)
				)
				(xy 170.558206 -30.95879) (xy 170.558206 -30.879542)
				(arc
					(start 170.298618 -30.620208)
					(mid 170.029139 -30.229317)
					(end 170.42003 -30.498796)
				)
				(xy 170.557952 -30.636972) (xy 170.557952 -30.498796)
			)
		)
	)
	(zone
		(layer "F.Cu")
		(hatch none 0.5)
		(connect_pads
			(clearance 0)
		)
		(min_thickness 0.25)
		(keepout
			(tracks not_allowed)
			(vias allowed)
			(pads allowed)
			(copperpour not_allowed)
			(footprints allowed)
		)
		(placement
			(enabled no)
			(sheetname "")
		)
		(fill
			(thermal_gap 0.5)
			(thermal_bridge_width 0.5)
			(island_removal_mode 0)
		)
		(polygon
			(pts
				(xy 138.479276 -76.14158) (xy 138.479022 -76.141834)
				(arc
					(start 138.479022 -76.142342)
					(mid 138.096244 -76.52512)
					(end 138.479022 -76.907898)
				)
				(xy 138.479022 -76.90866) (xy 139.622022 -76.90866)
				(arc
					(start 139.622022 -76.907898)
					(mid 140.0048 -76.52512)
					(end 139.622022 -76.142342)
				)
				(xy 139.622022 -76.14158) (xy 139.328652 -76.14158)
				(arc
					(start 139.328652 -76.399898)
					(mid 139.332544 -76.418993)
					(end 139.343384 -76.435204)
				)
				(arc
					(start 139.343384 -76.435204)
					(mid 139.354047 -76.443462)
					(end 139.366498 -76.448666)
				)
				(arc
					(start 139.366498 -76.448666)
					(mid 139.888737 -76.525923)
					(end 139.36599 -76.60005)
				)
				(xy 139.34821 -76.60005)
				(arc
					(start 139.345162 -76.597256)
					(mid 139.286865 -76.577671)
					(end 139.237212 -76.541376)
				)
				(arc
					(start 139.237212 -76.541122)
					(mid 139.201111 -76.491828)
					(end 139.181586 -76.433934)
				)
				(xy 139.178792 -76.430886) (xy 139.178792 -76.14158) (xy 138.922252 -76.14158) (xy 138.922252 -76.42987)
				(arc
					(start 138.919204 -76.432918)
					(mid 138.906788 -76.47585)
					(end 138.885168 -76.51496)
				)
				(xy 138.885168 -76.519024) (xy 138.863578 -76.540868) (xy 138.86307 -76.541122) (xy 138.862054 -76.542138)
				(xy 138.840972 -76.56322)
				(arc
					(start 138.837162 -76.56322)
					(mid 138.798307 -76.584825)
					(end 138.755628 -76.597256)
				)
				(xy 138.75258 -76.60005)
				(arc
					(start 138.735054 -76.60005)
					(mid 138.212252 -76.526044)
					(end 138.734546 -76.448412)
				)
				(arc
					(start 138.734546 -76.448412)
					(mid 138.746278 -76.443609)
					(end 138.75639 -76.435966)
				)
				(arc
					(start 138.757406 -76.43495)
					(mid 138.768492 -76.418403)
					(end 138.772392 -76.398882)
				)
				(xy 138.772392 -76.14158)
			)
		)
	)
	(zone
		(net "GND")
		(layer "F.Cu")
		(hatch none 0.5)
		(connect_pads
			(clearance 0.5)
		)
		(min_thickness 0.25)
		(fill yes
			(thermal_gap 0.5)
			(thermal_bridge_width 0.5)
			(island_removal_mode 0)
		)
		(polygon
			(pts
				(xy 56.007 -91.186) (xy 55.88 -91.313) (xy 55.88 -98.171) (xy 56.261 -98.552) (xy 57.987438 -98.552)
				(xy 58.914538 -99.4791) (xy 58.914538 -101.968046) (xy 59.054492 -102.108) (xy 67.945 -102.108)
				(xy 68.453 -101.6) (xy 68.453 -99.314) (xy 68.05422 -98.91522) (xy 59.4487 -98.91522) (xy 58.928 -98.39452)
				(xy 58.928 -91.313) (xy 58.801 -91.186)
			)
		)
		(polygon
			(pts
				(xy 58.0136 -97.917) (xy 57.8104 -97.917) (xy 57.8104 -98.1202) (xy 58.0136 -98.1202)
			)
		)
		(polygon
			(pts
				(xy 58.0136 -97.0534) (xy 57.8104 -97.0534) (xy 57.8104 -97.2566) (xy 58.0136 -97.2566)
			)
		)
	)
	(zone
		(net "GND")
		(layer "F.Cu")
		(hatch none 0.5)
		(connect_pads
			(clearance 0.5)
		)
		(min_thickness 0.25)
		(fill yes
			(thermal_gap 0.5)
			(thermal_bridge_width 0.5)
			(island_removal_mode 0)
		)
		(polygon
			(pts
				(xy 160.311338 -10.714228) (xy 160.200594 -10.824972) (xy 160.200594 -13.299948) (xy 160.361376 -13.46073)
				(xy 160.856168 -13.46073) (xy 161.537396 -12.779502) (xy 161.537396 -10.879328) (xy 161.372296 -10.714228)
			)
		)
	)
	(zone
		(layer "F.Cu")
		(hatch none 0.5)
		(connect_pads
			(clearance 0)
		)
		(min_thickness 0.25)
		(keepout
			(tracks not_allowed)
			(vias allowed)
			(pads allowed)
			(copperpour not_allowed)
			(footprints allowed)
		)
		(placement
			(enabled no)
			(sheetname "")
		)
		(fill
			(thermal_gap 0.5)
			(thermal_bridge_width 0.5)
			(island_removal_mode 0)
		)
		(polygon
			(pts
				(arc
					(start 126.000256 -71.64197)
					(mid 125.893882 -71.658053)
					(end 125.797056 -71.704962)
				)
				(arc
					(start 125.881892 -71.789798)
					(mid 126.170562 -72.17067)
					(end 125.78969 -71.882)
				)
				(arc
					(start 125.704854 -71.797164)
					(mid 125.682991 -72.166853)
					(end 126.000002 -72.35825)
				)
				(arc
					(start 127 -72.35825)
					(mid 127.35814 -72.00011)
					(end 127 -71.64197)
				)
				(xy 126.734062 -71.64197)
				(arc
					(start 126.88189 -71.789798)
					(mid 127.17056 -72.17067)
					(end 126.789688 -71.882)
				)
				(xy 126.549658 -71.64197)
			)
		)
	)
	(zone
		(layer "F.Cu")
		(hatch none 0.5)
		(connect_pads
			(clearance 0)
		)
		(min_thickness 0.25)
		(keepout
			(tracks allowed)
			(vias allowed)
			(pads allowed)
			(copperpour allowed)
			(footprints allowed)
		)
		(placement
			(enabled no)
			(sheetname "")
		)
		(fill
			(thermal_gap 0.5)
			(thermal_bridge_width 0.5)
			(island_removal_mode 0)
		)
		(polygon
			(pts
				(xy 44.5008 -36.322) (xy 44.5008 -34.5186) (xy 45.5168 -34.5186) (xy 45.5168 -36.322)
			)
		)
	)
	(zone
		(layer "F.Cu")
		(hatch none 0.5)
		(connect_pads
			(clearance 0)
		)
		(min_thickness 0.25)
		(keepout
			(tracks allowed)
			(vias allowed)
			(pads allowed)
			(copperpour allowed)
			(footprints allowed)
		)
		(placement
			(enabled no)
			(sheetname "")
		)
		(fill
			(thermal_gap 0.5)
			(thermal_bridge_width 0.5)
			(island_removal_mode 0)
		)
		(polygon
			(pts
				(xy 23.290784 -87.926164) (xy 23.290784 -86.520782) (xy 24.26335 -86.520782) (xy 24.26335 -87.926164)
			)
		)
	)
	(zone
		(net "P1V5_E")
		(layer "F.Cu")
		(hatch none 0.5)
		(connect_pads
			(clearance 0.5)
		)
		(min_thickness 0.25)
		(fill yes
			(thermal_gap 0.5)
			(thermal_bridge_width 0.5)
			(island_removal_mode 0)
		)
		(polygon
			(pts
				(xy 137.287 -100.711) (xy 136.958578 -101.039422) (xy 136.958578 -104.589072) (xy 137.266934 -104.897428)
				(xy 144.149572 -104.897428) (xy 144.399 -104.648) (xy 144.399 -100.838) (xy 144.272 -100.711)
			)
		)
		(polygon
			(pts
				(xy 143.5608 -101.4984) (xy 143.3576 -101.4984) (xy 143.3576 -101.7016) (xy 143.5608 -101.7016)
			)
		)
	)
	(zone
		(layer "F.Cu")
		(hatch none 0.5)
		(connect_pads
			(clearance 0)
		)
		(min_thickness 0.25)
		(keepout
			(tracks not_allowed)
			(vias allowed)
			(pads allowed)
			(copperpour not_allowed)
			(footprints allowed)
		)
		(placement
			(enabled no)
			(sheetname "")
		)
		(fill
			(thermal_gap 0.5)
			(thermal_bridge_width 0.5)
			(island_removal_mode 0)
		)
		(polygon
			(pts
				(arc
					(start 130.000248 -63.641986)
					(mid 129.683085 -63.833294)
					(end 129.704846 -64.203072)
				)
				(arc
					(start 129.789682 -64.118236)
					(mid 130.170554 -63.829566)
					(end 129.881884 -64.210438)
				)
				(arc
					(start 129.797048 -64.295274)
					(mid 129.893745 -64.342159)
					(end 129.999994 -64.358266)
				)
				(xy 130.54965 -64.358266)
				(arc
					(start 130.78968 -64.118236)
					(mid 131.170552 -63.829566)
					(end 130.881882 -64.210438)
				)
				(xy 130.734054 -64.358266)
				(arc
					(start 130.999992 -64.358266)
					(mid 131.358132 -64.000126)
					(end 130.999992 -63.641986)
				)
				(xy 130.699002 -63.641986) (xy 130.607054 -63.733934) (xy 130.406648 -63.733934) (xy 130.3147 -63.641986)
			)
		)
	)
	(zone
		(layer "F.Cu")
		(hatch none 0.5)
		(connect_pads
			(clearance 0)
		)
		(min_thickness 0.25)
		(keepout
			(tracks not_allowed)
			(vias allowed)
			(pads allowed)
			(copperpour not_allowed)
			(footprints allowed)
		)
		(placement
			(enabled no)
			(sheetname "")
		)
		(fill
			(thermal_gap 0.5)
			(thermal_bridge_width 0.5)
			(island_removal_mode 0)
		)
		(polygon
			(pts
				(arc
					(start 126.000256 -76.64196)
					(mid 125.893882 -76.658043)
					(end 125.797056 -76.704952)
				)
				(arc
					(start 125.881892 -76.789788)
					(mid 126.170562 -77.17066)
					(end 125.78969 -76.88199)
				)
				(arc
					(start 125.704854 -76.797154)
					(mid 125.682991 -77.166843)
					(end 126.000002 -77.35824)
				)
				(xy 126.299976 -77.35824) (xy 126.391416 -77.2668) (xy 126.598426 -77.2668) (xy 126.689866 -77.35824)
				(arc
					(start 127 -77.35824)
					(mid 127.35814 -77.0001)
					(end 127 -76.64196)
				)
				(xy 126.734062 -76.64196)
				(arc
					(start 126.88189 -76.789788)
					(mid 127.17056 -77.17066)
					(end 126.789688 -76.88199)
				)
				(xy 126.549658 -76.64196)
			)
		)
	)
	(zone
		(layer "F.Cu")
		(hatch none 0.5)
		(connect_pads
			(clearance 0)
		)
		(min_thickness 0.25)
		(keepout
			(tracks not_allowed)
			(vias allowed)
			(pads allowed)
			(copperpour not_allowed)
			(footprints allowed)
		)
		(placement
			(enabled no)
			(sheetname "")
		)
		(fill
			(thermal_gap 0.5)
			(thermal_bridge_width 0.5)
			(island_removal_mode 0)
		)
		(polygon
			(pts
				(xy 147.037806 -46.632114)
				(arc
					(start 147.3327 -46.69282)
					(mid 147.372637 -46.692533)
					(end 147.4089 -46.675802)
				)
				(arc
					(start 147.4089 -46.675802)
					(mid 147.605353 -46.186529)
					(end 147.564094 -46.712124)
				)
				(xy 147.55749 -46.743874)
				(arc
					(start 147.542504 -46.753526)
					(mid 147.450209 -46.824124)
					(end 147.335748 -46.844204)
				)
				(xy 147.332954 -46.845982) (xy 147.302728 -46.839632) (xy 147.006564 -46.778672) (xy 146.953224 -47.029878)
				(xy 147.286726 -47.098458) (xy 147.290028 -47.098966) (xy 147.320508 -47.104808)
				(arc
					(start 147.323556 -47.108872)
					(mid 147.413038 -47.18366)
					(end 147.441158 -47.296832)
				)
				(xy 147.442428 -47.298864) (xy 147.438618 -47.317152)
				(arc
					(start 147.43557 -47.330614)
					(mid 147.248834 -47.824738)
					(end 147.289266 -47.298102)
				)
				(arc
					(start 147.291298 -47.28845)
					(mid 147.285307 -47.262313)
					(end 147.263612 -47.24654)
				)
				(xy 147.25777 -47.24527) (xy 147.228052 -47.239682) (xy 147.227544 -47.239174) (xy 146.921982 -47.176436)
				(arc
					(start 146.859752 -47.469298)
					(mid 147.21205 -48.011588)
					(end 147.75434 -47.65929)
				)
				(xy 147.873466 -47.098966)
				(arc
					(start 147.989544 -46.551596)
					(mid 147.64498 -46.000227)
					(end 147.097496 -46.35119)
				)
			)
		)
	)
	(zone
		(net "P12V_STBY_VIN_U11")
		(layer "F.Cu")
		(hatch none 0.5)
		(connect_pads
			(clearance 0.5)
		)
		(min_thickness 0.25)
		(fill yes
			(thermal_gap 0.5)
			(thermal_bridge_width 0.5)
			(island_removal_mode 0)
		)
		(polygon
			(pts
				(xy 155.829 -111.125) (xy 155.448 -111.506) (xy 155.448 -115.697) (xy 155.702 -115.951) (xy 156.591 -115.951)
				(xy 157.988 -114.554) (xy 161.671 -114.554) (xy 162.187636 -114.037364) (xy 162.187636 -111.54791)
				(xy 161.764726 -111.125)
			)
		)
		(polygon
			(pts
				(xy 160.6931 -112.5601) (xy 160.4899 -112.5601) (xy 160.4899 -112.7633) (xy 160.6931 -112.7633)
			)
		)
		(polygon
			(pts
				(xy 156.96438 -111.97082) (xy 156.76118 -111.97082) (xy 156.76118 -112.17402) (xy 156.96438 -112.17402)
			)
		)
		(polygon
			(pts
				(xy 156.10078 -111.97082) (xy 155.89758 -111.97082) (xy 155.89758 -112.17402) (xy 156.10078 -112.17402)
			)
		)
		(polygon
			(pts
				(xy 158.1658 -111.9632) (xy 157.9626 -111.9632) (xy 157.9626 -112.1664) (xy 158.1658 -112.1664)
			)
		)
		(polygon
			(pts
				(xy 157.3022 -111.9632) (xy 157.099 -111.9632) (xy 157.099 -112.1664) (xy 157.3022 -112.1664)
			)
		)
		(polygon
			(pts
				(xy 160.6931 -111.4171) (xy 160.4899 -111.4171) (xy 160.4899 -111.6203) (xy 160.6931 -111.6203)
			)
		)
	)
	(zone
		(layer "F.Cu")
		(hatch none 0.5)
		(connect_pads
			(clearance 0)
		)
		(min_thickness 0.25)
		(keepout
			(tracks not_allowed)
			(vias allowed)
			(pads allowed)
			(copperpour not_allowed)
			(footprints allowed)
		)
		(placement
			(enabled no)
			(sheetname "")
		)
		(fill
			(thermal_gap 0.5)
			(thermal_bridge_width 0.5)
			(island_removal_mode 0)
		)
		(polygon
			(pts
				(arc
					(start 168.958006 -30.39999)
					(mid 168.599866 -30.04185)
					(end 168.241726 -30.39999)
				)
				(xy 168.241726 -30.7086) (xy 168.275 -30.741874) (xy 168.275 -30.8356) (xy 168.241726 -30.868874)
				(arc
					(start 168.241726 -31.199582)
					(mid 168.423755 -31.511684)
					(end 168.785032 -31.506414)
				)
				(arc
					(start 168.698672 -31.420054)
					(mid 168.429193 -31.029163)
					(end 168.820084 -31.298642)
				)
				(arc
					(start 168.906444 -31.385002)
					(mid 168.944887 -31.295944)
					(end 168.958006 -31.199836)
				)
				(xy 168.958006 -30.879288)
				(arc
					(start 168.698672 -30.620208)
					(mid 168.429193 -30.229317)
					(end 168.820084 -30.498796)
				)
				(xy 168.958006 -30.636972)
			)
		)
	)
	(zone
		(layer "F.Cu")
		(hatch none 0.5)
		(connect_pads
			(clearance 0)
		)
		(min_thickness 0.25)
		(keepout
			(tracks not_allowed)
			(vias allowed)
			(pads allowed)
			(copperpour not_allowed)
			(footprints allowed)
		)
		(placement
			(enabled no)
			(sheetname "")
		)
		(fill
			(thermal_gap 0.5)
			(thermal_bridge_width 0.5)
			(island_removal_mode 0)
		)
		(polygon
			(pts
				(arc
					(start 166.58336 -30.400244)
					(mid 166.199947 -30.01645)
					(end 165.81628 -30.39999)
				)
				(xy 165.81628 -30.72511) (xy 165.831012 -30.72511)
				(arc
					(start 166.071804 -30.965902)
					(mid 166.388385 -31.388401)
					(end 165.965886 -31.07182)
				)
				(xy 165.81628 -30.922214)
				(arc
					(start 165.81628 -31.199836)
					(mid 166.19982 -31.583376)
					(end 166.58336 -31.199836)
				)
				(xy 166.58336 -30.87497) (xy 166.568882 -30.87497)
				(arc
					(start 166.327836 -30.633924)
					(mid 166.011255 -30.211425)
					(end 166.433754 -30.528006)
				)
				(xy 166.58336 -30.677612)
			)
		)
	)
	(zone
		(layer "F.Cu")
		(hatch none 0.5)
		(connect_pads
			(clearance 0)
		)
		(min_thickness 0.25)
		(keepout
			(tracks not_allowed)
			(vias allowed)
			(pads allowed)
			(copperpour not_allowed)
			(footprints allowed)
		)
		(placement
			(enabled no)
			(sheetname "")
		)
		(fill
			(thermal_gap 0.5)
			(thermal_bridge_width 0.5)
			(island_removal_mode 0)
		)
		(polygon
			(pts
				(arc
					(start 130.000248 -65.641982)
					(mid 129.683085 -65.83329)
					(end 129.704846 -66.203068)
				)
				(arc
					(start 129.789682 -66.118232)
					(mid 130.170554 -65.829562)
					(end 129.881884 -66.210434)
				)
				(arc
					(start 129.797048 -66.29527)
					(mid 129.893745 -66.342155)
					(end 129.999994 -66.358262)
				)
				(xy 130.54965 -66.358262)
				(arc
					(start 130.78968 -66.118232)
					(mid 131.170552 -65.829562)
					(end 130.881882 -66.210434)
				)
				(xy 130.734054 -66.358262)
				(arc
					(start 130.999992 -66.358262)
					(mid 131.358132 -66.000122)
					(end 130.999992 -65.641982)
				)
				(xy 130.69062 -65.641982) (xy 130.598672 -65.73393) (xy 130.403346 -65.73393) (xy 130.311398 -65.641982)
			)
		)
	)
	(zone
		(layer "F.Cu")
		(hatch none 0.5)
		(connect_pads
			(clearance 0)
		)
		(min_thickness 0.25)
		(keepout
			(tracks not_allowed)
			(vias allowed)
			(pads allowed)
			(copperpour not_allowed)
			(footprints allowed)
		)
		(placement
			(enabled no)
			(sheetname "")
		)
		(fill
			(thermal_gap 0.5)
			(thermal_bridge_width 0.5)
			(island_removal_mode 0)
		)
		(polygon
			(pts
				(arc
					(start 126.000256 -75.641962)
					(mid 125.893882 -75.658045)
					(end 125.797056 -75.704954)
				)
				(arc
					(start 125.881892 -75.78979)
					(mid 126.170562 -76.170662)
					(end 125.78969 -75.881992)
				)
				(arc
					(start 125.704854 -75.797156)
					(mid 125.682991 -76.166845)
					(end 126.000002 -76.358242)
				)
				(arc
					(start 127 -76.358242)
					(mid 127.35814 -76.000102)
					(end 127 -75.641962)
				)
				(xy 126.734062 -75.641962)
				(arc
					(start 126.88189 -75.78979)
					(mid 127.17056 -76.170662)
					(end 126.789688 -75.881992)
				)
				(xy 126.549658 -75.641962)
			)
		)
	)
	(zone
		(layer "F.Cu")
		(hatch none 0.5)
		(connect_pads
			(clearance 0)
		)
		(min_thickness 0.25)
		(keepout
			(tracks not_allowed)
			(vias allowed)
			(pads allowed)
			(copperpour not_allowed)
			(footprints allowed)
		)
		(placement
			(enabled no)
			(sheetname "")
		)
		(fill
			(thermal_gap 0.5)
			(thermal_bridge_width 0.5)
			(island_removal_mode 0)
		)
		(polygon
			(pts
				(arc
					(start 103.358188 -55.000144)
					(mid 103.000048 -54.642004)
					(end 102.641908 -55.000144)
				)
				(arc
					(start 102.641908 -55.999888)
					(mid 102.833216 -56.317051)
					(end 103.202994 -56.29529)
				)
				(arc
					(start 103.118158 -56.210454)
					(mid 102.829488 -55.829582)
					(end 103.21036 -56.118252)
				)
				(arc
					(start 103.295196 -56.203088)
					(mid 103.342081 -56.106391)
					(end 103.358188 -56.000142)
				)
				(xy 103.358188 -55.450486)
				(arc
					(start 103.118158 -55.210456)
					(mid 102.829488 -54.829584)
					(end 103.21036 -55.118254)
				)
				(xy 103.358188 -55.266082)
			)
		)
	)
	(zone
		(layer "F.Cu")
		(hatch none 0.5)
		(connect_pads
			(clearance 0)
		)
		(min_thickness 0.25)
		(keepout
			(tracks not_allowed)
			(vias allowed)
			(pads allowed)
			(copperpour not_allowed)
			(footprints allowed)
		)
		(placement
			(enabled no)
			(sheetname "")
		)
		(fill
			(thermal_gap 0.5)
			(thermal_bridge_width 0.5)
			(island_removal_mode 0)
		)
		(polygon
			(pts
				(arc
					(start 102.35819 -55.000144)
					(mid 102.00005 -54.642004)
					(end 101.64191 -55.000144)
				)
				(arc
					(start 101.64191 -55.999888)
					(mid 101.833218 -56.317051)
					(end 102.202996 -56.29529)
				)
				(arc
					(start 102.11816 -56.210454)
					(mid 101.82949 -55.829582)
					(end 102.210362 -56.118252)
				)
				(arc
					(start 102.295198 -56.203088)
					(mid 102.342083 -56.106391)
					(end 102.35819 -56.000142)
				)
				(xy 102.35819 -55.450486)
				(arc
					(start 102.11816 -55.210456)
					(mid 101.82949 -54.829584)
					(end 102.210362 -55.118254)
				)
				(xy 102.35819 -55.266082)
			)
		)
	)
	(zone
		(net "GND")
		(layer "F.Cu")
		(hatch none 0.5)
		(connect_pads
			(clearance 0.5)
		)
		(min_thickness 0.25)
		(fill yes
			(thermal_gap 0.5)
			(thermal_bridge_width 0.5)
			(island_removal_mode 0)
		)
		(polygon
			(pts
				(xy 80.809592 -65.570608) (xy 80.7339 -65.6463) (xy 80.7339 -66.6623) (xy 80.899 -66.8274) (xy 82.6262 -66.8274)
				(xy 82.65922 -66.79438) (xy 82.65922 -65.767712) (xy 82.462116 -65.570608)
			)
		)
	)
	(zone
		(layer "F.Cu")
		(hatch none 0.5)
		(connect_pads
			(clearance 0)
		)
		(min_thickness 0.25)
		(keepout
			(tracks allowed)
			(vias allowed)
			(pads allowed)
			(copperpour allowed)
			(footprints allowed)
		)
		(placement
			(enabled no)
			(sheetname "")
		)
		(fill
			(thermal_gap 0.5)
			(thermal_bridge_width 0.5)
			(island_removal_mode 0)
		)
		(polygon
			(pts
				(xy 167.0812 -95.0214) (xy 167.0812 -93.1164) (xy 172.9486 -93.1164) (xy 172.9486 -95.0214) (xy 172.9486 -95.9612)
				(xy 172.466 -96.4438) (xy 171.4246 -96.4438) (xy 171.323 -96.3422) (xy 171.323 -95.123) (xy 171.2214 -95.0214)
			)
		)
	)
	(zone
		(layer "F.Cu")
		(hatch none 0.5)
		(connect_pads
			(clearance 0)
		)
		(min_thickness 0.25)
		(keepout
			(tracks not_allowed)
			(vias allowed)
			(pads allowed)
			(copperpour not_allowed)
			(footprints allowed)
		)
		(placement
			(enabled no)
			(sheetname "")
		)
		(fill
			(thermal_gap 0.5)
			(thermal_bridge_width 0.5)
			(island_removal_mode 0)
		)
		(polygon
			(pts
				(arc
					(start 112.35817 -55.000144)
					(mid 112.00003 -54.642004)
					(end 111.64189 -55.000144)
				)
				(arc
					(start 111.64189 -55.999888)
					(mid 111.833198 -56.317051)
					(end 112.202976 -56.29529)
				)
				(arc
					(start 112.11814 -56.210454)
					(mid 111.82947 -55.829582)
					(end 112.210342 -56.118252)
				)
				(arc
					(start 112.295178 -56.203088)
					(mid 112.342063 -56.106391)
					(end 112.35817 -56.000142)
				)
				(xy 112.35817 -55.450486)
				(arc
					(start 112.11814 -55.210456)
					(mid 111.82947 -54.829584)
					(end 112.210342 -55.118254)
				)
				(xy 112.35817 -55.266082)
			)
		)
	)
	(zone
		(layer "F.Cu")
		(hatch none 0.5)
		(connect_pads
			(clearance 0)
		)
		(min_thickness 0.25)
		(keepout
			(tracks not_allowed)
			(vias allowed)
			(pads allowed)
			(copperpour not_allowed)
			(footprints allowed)
		)
		(placement
			(enabled no)
			(sheetname "")
		)
		(fill
			(thermal_gap 0.5)
			(thermal_bridge_width 0.5)
			(island_removal_mode 0)
		)
		(polygon
			(pts
				(arc
					(start 109.358176 -52.00015)
					(mid 109.000036 -51.64201)
					(end 108.641896 -52.00015)
				)
				(arc
					(start 108.641896 -52.999894)
					(mid 108.833204 -53.317057)
					(end 109.202982 -53.295296)
				)
				(arc
					(start 109.118146 -53.21046)
					(mid 108.829476 -52.829588)
					(end 109.210348 -53.118258)
				)
				(arc
					(start 109.295184 -53.203094)
					(mid 109.342069 -53.106397)
					(end 109.358176 -53.000148)
				)
				(xy 109.358176 -52.450492)
				(arc
					(start 109.118146 -52.210462)
					(mid 108.829476 -51.82959)
					(end 109.210348 -52.11826)
				)
				(xy 109.358176 -52.266088)
			)
		)
	)
	(zone
		(layer "F.Cu")
		(hatch none 0.5)
		(connect_pads
			(clearance 0)
		)
		(min_thickness 0.25)
		(keepout
			(tracks not_allowed)
			(vias allowed)
			(pads allowed)
			(copperpour not_allowed)
			(footprints allowed)
		)
		(placement
			(enabled no)
			(sheetname "")
		)
		(fill
			(thermal_gap 0.5)
			(thermal_bridge_width 0.5)
			(island_removal_mode 0)
		)
		(polygon
			(pts
				(arc
					(start 126.000256 -55.642002)
					(mid 125.683093 -55.83331)
					(end 125.704854 -56.203088)
				)
				(arc
					(start 125.78969 -56.118252)
					(mid 126.170562 -55.829582)
					(end 125.881892 -56.210454)
				)
				(arc
					(start 125.797056 -56.29529)
					(mid 125.893753 -56.342175)
					(end 126.000002 -56.358282)
				)
				(xy 126.549658 -56.358282)
				(arc
					(start 126.789688 -56.118252)
					(mid 127.17056 -55.829582)
					(end 126.88189 -56.210454)
				)
				(xy 126.734062 -56.358282)
				(arc
					(start 127 -56.358282)
					(mid 127.35814 -56.000142)
					(end 127 -55.642002)
				)
			)
		)
	)
	(zone
		(layer "F.Cu")
		(hatch none 0.5)
		(connect_pads
			(clearance 0)
		)
		(min_thickness 0.25)
		(keepout
			(tracks not_allowed)
			(vias allowed)
			(pads allowed)
			(copperpour not_allowed)
			(footprints allowed)
		)
		(placement
			(enabled no)
			(sheetname "")
		)
		(fill
			(thermal_gap 0.5)
			(thermal_bridge_width 0.5)
			(island_removal_mode 0)
		)
		(polygon
			(pts
				(arc
					(start 104.358186 -51.000152)
					(mid 104.000046 -50.642012)
					(end 103.641906 -51.000152)
				)
				(xy 103.641906 -51.308) (xy 103.7336 -51.399694) (xy 103.7336 -51.6128) (xy 103.641906 -51.704494)
				(arc
					(start 103.641906 -51.999896)
					(mid 103.833214 -52.317059)
					(end 104.202992 -52.295298)
				)
				(arc
					(start 104.118156 -52.210462)
					(mid 103.829486 -51.82959)
					(end 104.210358 -52.11826)
				)
				(arc
					(start 104.295194 -52.203096)
					(mid 104.342079 -52.106399)
					(end 104.358186 -52.00015)
				)
				(xy 104.358186 -51.450494)
				(arc
					(start 104.118156 -51.210464)
					(mid 103.829486 -50.829592)
					(end 104.210358 -51.118262)
				)
				(xy 104.358186 -51.26609)
			)
		)
	)
	(zone
		(net "P1V8_E")
		(layer "F.Cu")
		(hatch none 0.5)
		(connect_pads
			(clearance 0.5)
		)
		(min_thickness 0.25)
		(fill yes
			(thermal_gap 0.5)
			(thermal_bridge_width 0.5)
			(island_removal_mode 0)
		)
		(polygon
			(pts
				(xy 86.868 -70.358) (xy 86.741 -70.485) (xy 86.741 -71.628) (xy 86.995 -71.882) (xy 88.493092 -71.882)
				(xy 88.700864 -71.674228) (xy 88.700864 -70.509638) (xy 88.549226 -70.358)
			)
		)
	)
	(zone
		(layer "F.Cu")
		(hatch none 0.5)
		(connect_pads
			(clearance 0)
		)
		(min_thickness 0.25)
		(keepout
			(tracks allowed)
			(vias allowed)
			(pads allowed)
			(copperpour allowed)
			(footprints not_allowed)
		)
		(placement
			(enabled no)
			(sheetname "")
		)
		(fill
			(thermal_gap 0.5)
			(thermal_bridge_width 0.5)
			(island_removal_mode 0)
		)
		(polygon
			(pts
				(xy 4.99999 -144.999964) (xy 4.99999 0)
				(arc
					(start 1.999996 0)
					(mid 0.585785 -0.585785)
					(end 0 -1.999996)
				)
				(arc
					(start 0 -142.999968)
					(mid 0.585785 -144.414179)
					(end 1.999996 -144.999964)
				)
			)
		)
	)
	(zone
		(net "AGND_CURRENT_MON")
		(layer "F.Cu")
		(hatch none 0.5)
		(connect_pads
			(clearance 0.5)
		)
		(min_thickness 0.25)
		(fill yes
			(thermal_gap 0.5)
			(thermal_bridge_width 0.5)
			(island_removal_mode 0)
		)
		(polygon
			(pts
				(xy 5.9182 -53.1622) (xy 5.73024 -53.35016) (xy 5.73024 -53.90896) (xy 6.01218 -54.1909) (xy 8.1407 -54.1909)
				(xy 8.255 -54.0766) (xy 8.255 -53.34) (xy 8.0772 -53.1622)
			)
		)
		(polygon
			(pts
				(xy 7.747 -53.4162) (xy 7.5438 -53.4162) (xy 7.5438 -53.6194) (xy 7.747 -53.6194)
			)
		)
	)
	(zone
		(net "GND")
		(layer "F.Cu")
		(hatch none 0.5)
		(connect_pads
			(clearance 0.5)
		)
		(min_thickness 0.25)
		(fill yes
			(thermal_gap 0.5)
			(thermal_bridge_width 0.5)
			(island_removal_mode 0)
		)
		(polygon
			(pts
				(xy 182.3466 -115.9256) (xy 182.0037 -116.2685) (xy 182.0037 -124.7648) (xy 182.1815 -124.9426)
				(xy 185.0136 -124.9426) (xy 185.22315 -124.73305) (xy 185.22315 -116.13515) (xy 185.0136 -115.9256)
			)
		)
		(polygon
			(pts
				(xy 182.7022 -124.5108) (xy 182.499 -124.5108) (xy 182.499 -124.714) (xy 182.7022 -124.714)
			)
		)
		(polygon
			(pts
				(xy 182.7022 -123.9012) (xy 182.499 -123.9012) (xy 182.499 -124.1044) (xy 182.7022 -124.1044)
			)
		)
		(polygon
			(pts
				(xy 184.785 -120.9294) (xy 184.5818 -120.9294) (xy 184.5818 -121.1326) (xy 184.785 -121.1326)
			)
		)
		(polygon
			(pts
				(xy 184.785 -120.3706) (xy 184.5818 -120.3706) (xy 184.5818 -120.5738) (xy 184.785 -120.5738)
			)
		)
		(polygon
			(pts
				(xy 184.7342 -118.0338) (xy 184.531 -118.0338) (xy 184.531 -118.237) (xy 184.7342 -118.237)
			)
		)
		(polygon
			(pts
				(xy 184.7342 -117.4242) (xy 184.531 -117.4242) (xy 184.531 -117.6274) (xy 184.7342 -117.6274)
			)
		)
	)
	(zone
		(layer "F.Cu")
		(hatch none 0.5)
		(connect_pads
			(clearance 0)
		)
		(min_thickness 0.25)
		(keepout
			(tracks not_allowed)
			(vias allowed)
			(pads allowed)
			(copperpour not_allowed)
			(footprints allowed)
		)
		(placement
			(enabled no)
			(sheetname "")
		)
		(fill
			(thermal_gap 0.5)
			(thermal_bridge_width 0.5)
			(island_removal_mode 0)
		)
		(polygon
			(pts
				(arc
					(start 123.358148 -51.000152)
					(mid 123.000008 -50.642012)
					(end 122.641868 -51.000152)
				)
				(xy 122.641868 -51.26609)
				(arc
					(start 122.789696 -51.118262)
					(mid 123.170568 -50.829592)
					(end 122.881898 -51.210464)
				)
				(xy 122.641868 -51.450494)
				(arc
					(start 122.641868 -51.999896)
					(mid 122.657951 -52.10627)
					(end 122.70486 -52.203096)
				)
				(arc
					(start 122.789696 -52.11826)
					(mid 123.170568 -51.82959)
					(end 122.881898 -52.210462)
				)
				(arc
					(start 122.797062 -52.295298)
					(mid 123.166751 -52.317161)
					(end 123.358148 -52.00015)
				)
				(xy 123.358148 -51.689) (xy 123.2662 -51.597052) (xy 123.2662 -51.3842) (xy 123.358148 -51.292252)
			)
		)
	)
	(zone
		(layer "F.Cu")
		(hatch none 0.5)
		(connect_pads
			(clearance 0)
		)
		(min_thickness 0.25)
		(keepout
			(tracks not_allowed)
			(vias allowed)
			(pads allowed)
			(copperpour not_allowed)
			(footprints allowed)
		)
		(placement
			(enabled no)
			(sheetname "")
		)
		(fill
			(thermal_gap 0.5)
			(thermal_bridge_width 0.5)
			(island_removal_mode 0)
		)
		(polygon
			(pts
				(arc
					(start 114.358166 -51.000152)
					(mid 114.000026 -50.642012)
					(end 113.641886 -51.000152)
				)
				(xy 113.641886 -51.308) (xy 113.7412 -51.407314) (xy 113.7412 -51.5874) (xy 113.641886 -51.686714)
				(arc
					(start 113.641886 -51.999896)
					(mid 113.833194 -52.317059)
					(end 114.202972 -52.295298)
				)
				(arc
					(start 114.118136 -52.210462)
					(mid 113.829466 -51.82959)
					(end 114.210338 -52.11826)
				)
				(arc
					(start 114.295174 -52.203096)
					(mid 114.342059 -52.106399)
					(end 114.358166 -52.00015)
				)
				(xy 114.358166 -51.450494)
				(arc
					(start 114.118136 -51.210464)
					(mid 113.829466 -50.829592)
					(end 114.210338 -51.118262)
				)
				(xy 114.358166 -51.26609)
			)
		)
	)
	(zone
		(net "GND")
		(layer "F.Cu")
		(hatch none 0.5)
		(connect_pads
			(clearance 0.5)
		)
		(min_thickness 0.25)
		(fill yes
			(thermal_gap 0.5)
			(thermal_bridge_width 0.5)
			(island_removal_mode 0)
		)
		(polygon
			(pts
				(xy 114.2746 -87.1474) (xy 114.1984 -87.2236) (xy 114.1984 -88.011) (xy 113.852706 -88.356694) (xy 113.852706 -89.834974)
				(xy 116.194332 -92.1766) (xy 119.6467 -92.1766) (xy 119.8753 -91.948) (xy 119.8753 -89.874852) (xy 119.7483 -89.747852)
				(xy 119.058436 -89.747852) (xy 118.866158 -89.94013) (xy 117.823996 -89.94013) (xy 117.506496 -89.62263)
				(xy 117.506496 -88.986106) (xy 118.152164 -88.340438) (xy 118.152164 -87.187024) (xy 118.11254 -87.1474)
			)
		)
		(polygon
			(pts
				(xy 119.303038 -91.271852) (xy 119.099838 -91.271852) (xy 119.099838 -91.475052) (xy 119.303038 -91.475052)
			)
		)
		(polygon
			(pts
				(xy 119.303038 -90.713052) (xy 119.099838 -90.713052) (xy 119.099838 -90.916252) (xy 119.303038 -90.916252)
			)
		)
		(polygon
			(pts
				(xy 119.759984 -90.198448) (xy 119.556784 -90.198448) (xy 119.556784 -90.401648) (xy 119.759984 -90.401648)
			)
		)
		(polygon
			(pts
				(xy 119.201184 -90.198448) (xy 118.997984 -90.198448) (xy 118.997984 -90.401648) (xy 119.201184 -90.401648)
			)
		)
		(polygon
			(pts
				(xy 117.761258 -87.604854) (xy 117.558058 -87.604854) (xy 117.558058 -87.808054) (xy 117.761258 -87.808054)
			)
		)
		(polygon
			(pts
				(xy 117.304058 -87.604854) (xy 117.100858 -87.604854) (xy 117.100858 -87.808054) (xy 117.304058 -87.808054)
			)
		)
		(polygon
			(pts
				(xy 116.745258 -87.604854) (xy 116.542058 -87.604854) (xy 116.542058 -87.808054) (xy 116.745258 -87.808054)
			)
		)
		(polygon
			(pts
				(xy 115.0366 -87.6046) (xy 114.8334 -87.6046) (xy 114.8334 -87.8078) (xy 115.0366 -87.8078)
			)
		)
	)
	(zone
		(layer "F.Cu")
		(hatch none 0.5)
		(connect_pads
			(clearance 0)
		)
		(min_thickness 0.25)
		(keepout
			(tracks not_allowed)
			(vias allowed)
			(pads allowed)
			(copperpour not_allowed)
			(footprints allowed)
		)
		(placement
			(enabled no)
			(sheetname "")
		)
		(fill
			(thermal_gap 0.5)
			(thermal_bridge_width 0.5)
			(island_removal_mode 0)
		)
		(polygon
			(pts
				(arc
					(start 124.358146 -55.000144)
					(mid 124.000006 -54.642004)
					(end 123.641866 -55.000144)
				)
				(xy 123.641866 -55.266082)
				(arc
					(start 123.789694 -55.118254)
					(mid 124.170566 -54.829584)
					(end 123.881896 -55.210456)
				)
				(xy 123.641866 -55.450486)
				(arc
					(start 123.641866 -55.999888)
					(mid 123.657949 -56.106262)
					(end 123.704858 -56.203088)
				)
				(arc
					(start 123.789694 -56.118252)
					(mid 124.170566 -55.829582)
					(end 123.881896 -56.210454)
				)
				(arc
					(start 123.79706 -56.29529)
					(mid 124.166749 -56.317153)
					(end 124.358146 -56.000142)
				)
				(xy 124.358146 -55.70728) (xy 124.264166 -55.6133) (xy 124.264166 -55.39486) (xy 124.358146 -55.30088)
			)
		)
	)
	(zone
		(layer "F.Cu")
		(hatch none 0.5)
		(connect_pads
			(clearance 0)
		)
		(min_thickness 0.25)
		(keepout
			(tracks allowed)
			(vias allowed)
			(pads allowed)
			(copperpour allowed)
			(footprints not_allowed)
		)
		(placement
			(enabled no)
			(sheetname "")
		)
		(fill
			(thermal_gap 0.5)
			(thermal_bridge_width 0.5)
			(island_removal_mode 0)
		)
		(polygon
			(pts
				(arc
					(start 137.999978 -94.309946)
					(mid 134.999984 -97.30994)
					(end 131.99999 -94.309946)
				)
				(arc
					(start 131.99999 -94.309946)
					(mid 134.999984 -91.309952)
					(end 137.999978 -94.309946)
				)
			)
		)
	)
	(zone
		(layer "F.Cu")
		(hatch none 0.5)
		(connect_pads
			(clearance 0)
		)
		(min_thickness 0.25)
		(keepout
			(tracks not_allowed)
			(vias allowed)
			(pads allowed)
			(copperpour not_allowed)
			(footprints allowed)
		)
		(placement
			(enabled no)
			(sheetname "")
		)
		(fill
			(thermal_gap 0.5)
			(thermal_bridge_width 0.5)
			(island_removal_mode 0)
		)
		(polygon
			(pts
				(arc
					(start 92.00007 -39.67988)
					(mid 95.000064 -36.679886)
					(end 98.000058 -39.67988)
				)
				(arc
					(start 98.000058 -39.67988)
					(mid 95.000064 -42.679874)
					(end 92.00007 -39.67988)
				)
			)
		)
	)
	(zone
		(layer "F.Cu")
		(hatch none 0.5)
		(connect_pads
			(clearance 0)
		)
		(min_thickness 0.25)
		(keepout
			(tracks allowed)
			(vias allowed)
			(pads allowed)
			(copperpour allowed)
			(footprints not_allowed)
		)
		(placement
			(enabled no)
			(sheetname "")
		)
		(fill
			(thermal_gap 0.5)
			(thermal_bridge_width 0.5)
			(island_removal_mode 0)
		)
		(polygon
			(pts
				(xy 203.000102 -71.000112) (xy 203.000102 -18.999962) (xy 146.99996 -18.999962) (xy 146.99996 -71.000112)
			)
		)
	)
	(zone
		(net "P3V3")
		(layer "F.Cu")
		(hatch none 0.5)
		(connect_pads
			(clearance 0.5)
		)
		(min_thickness 0.25)
		(fill yes
			(thermal_gap 0.5)
			(thermal_bridge_width 0.5)
			(island_removal_mode 0)
		)
		(polygon
			(pts
				(xy 67.7545 -71.2851) (xy 67.6402 -71.3994) (xy 67.6402 -72.4154) (xy 67.7418 -72.517) (xy 69.1642 -72.517)
				(xy 69.3928 -72.2884) (xy 69.3928 -71.3486) (xy 69.3293 -71.2851)
			)
		)
		(polygon
			(pts
				(xy 68.8086 -71.882) (xy 68.6054 -71.882) (xy 68.6054 -72.0852) (xy 68.8086 -72.0852)
			)
		)
		(polygon
			(pts
				(xy 68.3514 -71.882) (xy 68.1482 -71.882) (xy 68.1482 -72.0852) (xy 68.3514 -72.0852)
			)
		)
	)
	(zone
		(layer "F.Cu")
		(hatch none 0.5)
		(connect_pads
			(clearance 0)
		)
		(min_thickness 0.25)
		(keepout
			(tracks not_allowed)
			(vias allowed)
			(pads allowed)
			(copperpour not_allowed)
			(footprints allowed)
		)
		(placement
			(enabled no)
			(sheetname "")
		)
		(fill
			(thermal_gap 0.5)
			(thermal_bridge_width 0.5)
			(island_removal_mode 0)
		)
		(polygon
			(pts
				(arc
					(start 149.419056 -55.045864)
					(mid 149.508538 -55.120652)
					(end 149.536658 -55.233824)
				)
				(xy 149.537928 -55.235856) (xy 149.534118 -55.254144)
				(arc
					(start 149.53107 -55.267606)
					(mid 149.344334 -55.76173)
					(end 149.384766 -55.235094)
				)
				(arc
					(start 149.386798 -55.225442)
					(mid 149.380807 -55.199305)
					(end 149.359112 -55.183532)
				)
				(xy 149.35327 -55.182262) (xy 149.323552 -55.176674) (xy 149.323044 -55.176166) (xy 149.017736 -55.113428)
				(arc
					(start 148.957792 -55.395876)
					(mid 149.302356 -55.947245)
					(end 149.84984 -55.596282)
				)
				(xy 149.968966 -55.035958)
				(arc
					(start 150.087584 -54.478174)
					(mid 149.735286 -53.935884)
					(end 149.192996 -54.288182)
				)
				(xy 149.133306 -54.569106)
				(arc
					(start 149.4282 -54.629812)
					(mid 149.468137 -54.629525)
					(end 149.5044 -54.612794)
				)
				(arc
					(start 149.5044 -54.612794)
					(mid 149.700853 -54.123521)
					(end 149.659594 -54.649116)
				)
				(xy 149.65299 -54.680866)
				(arc
					(start 149.638004 -54.690518)
					(mid 149.545709 -54.761116)
					(end 149.431248 -54.781196)
				)
				(xy 149.428454 -54.782974) (xy 149.398228 -54.776624) (xy 149.102064 -54.715664) (xy 149.048724 -54.96687)
				(xy 149.382226 -55.03545) (xy 149.385528 -55.035958) (xy 149.416008 -55.0418)
			)
		)
	)
	(zone
		(layer "F.Cu")
		(hatch none 0.5)
		(connect_pads
			(clearance 0)
		)
		(min_thickness 0.25)
		(keepout
			(tracks not_allowed)
			(vias allowed)
			(pads allowed)
			(copperpour not_allowed)
			(footprints allowed)
		)
		(placement
			(enabled no)
			(sheetname "")
		)
		(fill
			(thermal_gap 0.5)
			(thermal_bridge_width 0.5)
			(island_removal_mode 0)
		)
		(polygon
			(pts
				(arc
					(start 129.00025 -69.641974)
					(mid 128.893876 -69.658057)
					(end 128.79705 -69.704966)
				)
				(arc
					(start 128.881886 -69.789802)
					(mid 129.170556 -70.170674)
					(end 128.789684 -69.882004)
				)
				(arc
					(start 128.704848 -69.797168)
					(mid 128.682985 -70.166857)
					(end 128.999996 -70.358254)
				)
				(arc
					(start 129.999994 -70.358254)
					(mid 130.358134 -70.000114)
					(end 129.999994 -69.641974)
				)
				(xy 129.734056 -69.641974)
				(arc
					(start 129.881884 -69.789802)
					(mid 130.170554 -70.170674)
					(end 129.789682 -69.882004)
				)
				(xy 129.549652 -69.641974)
			)
		)
	)
	(zone
		(layer "F.Cu")
		(hatch none 0.5)
		(connect_pads
			(clearance 0)
		)
		(min_thickness 0.25)
		(keepout
			(tracks not_allowed)
			(vias allowed)
			(pads allowed)
			(copperpour not_allowed)
			(footprints allowed)
		)
		(placement
			(enabled no)
			(sheetname "")
		)
		(fill
			(thermal_gap 0.5)
			(thermal_bridge_width 0.5)
			(island_removal_mode 0)
		)
		(polygon
			(pts
				(arc
					(start 111.358172 -52.00015)
					(mid 111.000032 -51.64201)
					(end 110.641892 -52.00015)
				)
				(arc
					(start 110.641892 -52.999894)
					(mid 110.8332 -53.317057)
					(end 111.202978 -53.295296)
				)
				(arc
					(start 111.118142 -53.21046)
					(mid 110.829472 -52.829588)
					(end 111.210344 -53.118258)
				)
				(arc
					(start 111.29518 -53.203094)
					(mid 111.342065 -53.106397)
					(end 111.358172 -53.000148)
				)
				(xy 111.358172 -52.450492)
				(arc
					(start 111.118142 -52.210462)
					(mid 110.829472 -51.82959)
					(end 111.210344 -52.11826)
				)
				(xy 111.358172 -52.266088)
			)
		)
	)
	(zone
		(net "GND")
		(layer "F.Cu")
		(hatch none 0.5)
		(connect_pads
			(clearance 0.5)
		)
		(min_thickness 0.25)
		(fill yes
			(thermal_gap 0.5)
			(thermal_bridge_width 0.5)
			(island_removal_mode 0)
		)
		(polygon
			(pts
				(xy 144.8562 -100.711) (xy 144.7038 -100.8634) (xy 144.7038 -105.664) (xy 144.907 -105.8672) (xy 147.7518 -105.8672)
				(xy 148.1836 -105.4354) (xy 148.1836 -100.8888) (xy 148.0058 -100.711)
			)
		)
		(polygon
			(pts
				(xy 147.2438 -101.4984) (xy 147.0406 -101.4984) (xy 147.0406 -101.7016) (xy 147.2438 -101.7016)
			)
		)
	)
	(zone
		(layer "F.Cu")
		(hatch none 0.5)
		(connect_pads
			(clearance 0)
		)
		(min_thickness 0.25)
		(keepout
			(tracks allowed)
			(vias allowed)
			(pads allowed)
			(copperpour allowed)
			(footprints allowed)
		)
		(placement
			(enabled no)
			(sheetname "")
		)
		(fill
			(thermal_gap 0.5)
			(thermal_bridge_width 0.5)
			(island_removal_mode 0)
		)
		(polygon
			(pts
				(xy 195.838318 -70.51167) (xy 197.24624 -70.51167) (xy 197.24624 -72.30364) (xy 195.838318 -72.30364)
			)
		)
	)
	(zone
		(layer "F.Cu")
		(hatch none 0.5)
		(connect_pads
			(clearance 0)
		)
		(min_thickness 0.25)
		(keepout
			(tracks allowed)
			(vias allowed)
			(pads allowed)
			(copperpour allowed)
			(footprints allowed)
		)
		(placement
			(enabled no)
			(sheetname "")
		)
		(fill
			(thermal_gap 0.5)
			(thermal_bridge_width 0.5)
			(island_removal_mode 0)
		)
		(polygon
			(pts
				(xy 151.638 -118.5164) (xy 151.638 -115.6716) (xy 151.5872 -115.6208) (xy 148.971 -115.6208) (xy 148.971 -116.8654)
				(xy 149.225 -117.1194) (xy 149.352 -117.1194) (xy 149.86 -117.1194) (xy 149.987 -117.2464) (xy 149.987 -118.5164)
			)
		)
	)
	(zone
		(layer "F.Cu")
		(hatch none 0.5)
		(connect_pads
			(clearance 0)
		)
		(min_thickness 0.25)
		(keepout
			(tracks not_allowed)
			(vias allowed)
			(pads allowed)
			(copperpour not_allowed)
			(footprints allowed)
		)
		(placement
			(enabled no)
			(sheetname "")
		)
		(fill
			(thermal_gap 0.5)
			(thermal_bridge_width 0.5)
			(island_removal_mode 0)
		)
		(polygon
			(pts
				(arc
					(start 111.358172 -55.000144)
					(mid 111.000032 -54.642004)
					(end 110.641892 -55.000144)
				)
				(arc
					(start 110.641892 -55.999888)
					(mid 110.8332 -56.317051)
					(end 111.202978 -56.29529)
				)
				(arc
					(start 111.118142 -56.210454)
					(mid 110.829472 -55.829582)
					(end 111.210344 -56.118252)
				)
				(arc
					(start 111.29518 -56.203088)
					(mid 111.342065 -56.106391)
					(end 111.358172 -56.000142)
				)
				(xy 111.358172 -55.450486)
				(arc
					(start 111.118142 -55.210456)
					(mid 110.829472 -54.829584)
					(end 111.210344 -55.118254)
				)
				(xy 111.358172 -55.266082)
			)
		)
	)
	(zone
		(layer "F.Cu")
		(hatch none 0.5)
		(connect_pads
			(clearance 0)
		)
		(min_thickness 0.25)
		(keepout
			(tracks allowed)
			(vias allowed)
			(pads allowed)
			(copperpour allowed)
			(footprints allowed)
		)
		(placement
			(enabled no)
			(sheetname "")
		)
		(fill
			(thermal_gap 0.5)
			(thermal_bridge_width 0.5)
			(island_removal_mode 0)
		)
		(polygon
			(pts
				(xy 12.1666 -56.9722) (xy 10.7696 -56.9722) (xy 10.7696 -53.3146) (xy 9.9568 -53.3146) (xy 9.5504 -53.3146)
				(xy 9.5504 -49.53) (xy 10.4394 -49.53) (xy 10.4394 -49.5046) (xy 11.3284 -49.5046) (xy 11.3284 -49.4792)
				(xy 15.6972 -49.4792) (xy 15.6972 -51.054) (xy 12.1666 -51.054) (xy 12.1666 -51.2572) (xy 12.1666 -51.6128)
				(xy 12.1666 -55.5752) (xy 12.9286 -55.5752) (xy 12.9286 -56.9722)
			)
		)
	)
	(zone
		(layer "F.Cu")
		(hatch none 0.5)
		(connect_pads
			(clearance 0)
		)
		(min_thickness 0.25)
		(keepout
			(tracks not_allowed)
			(vias allowed)
			(pads allowed)
			(copperpour not_allowed)
			(footprints allowed)
		)
		(placement
			(enabled no)
			(sheetname "")
		)
		(fill
			(thermal_gap 0.5)
			(thermal_bridge_width 0.5)
			(island_removal_mode 0)
		)
		(polygon
			(pts
				(arc
					(start 132.677408 -45.814742)
					(mid 132.220208 -45.357542)
					(end 131.763008 -45.814742)
				)
				(arc
					(start 131.763008 -46.957488)
					(mid 132.220081 -47.414942)
					(end 132.677408 -46.957742)
				)
				(xy 132.677408 -46.664372)
				(arc
					(start 132.331206 -46.664372)
					(mid 132.317457 -46.6672)
					(end 132.305806 -46.67504)
				)
				(arc
					(start 132.305806 -46.67504)
					(mid 132.297937 -46.686679)
					(end 132.295138 -46.70044)
				)
				(arc
					(start 132.295138 -46.70171)
					(mid 132.220208 -47.224513)
					(end 132.145278 -46.70171)
				)
				(xy 132.145278 -46.669452)
				(arc
					(start 132.148326 -46.66615)
					(mid 132.16663 -46.613633)
					(end 132.199634 -46.568868)
				)
				(arc
					(start 132.199634 -46.568868)
					(mid 132.244397 -46.53586)
					(end 132.296916 -46.51756)
				)
				(xy 132.300218 -46.514512) (xy 132.677408 -46.514512) (xy 132.677408 -46.257972) (xy 132.300218 -46.257972)
				(arc
					(start 132.296916 -46.254924)
					(mid 132.244399 -46.23662)
					(end 132.199634 -46.203616)
				)
				(arc
					(start 132.199634 -46.203616)
					(mid 132.166626 -46.158853)
					(end 132.148326 -46.106334)
				)
				(xy 132.145278 -46.103032)
				(arc
					(start 132.145278 -46.070774)
					(mid 132.220208 -45.547971)
					(end 132.295138 -46.070774)
				)
				(arc
					(start 132.295138 -46.072044)
					(mid 132.297966 -46.085793)
					(end 132.305806 -46.097444)
				)
				(arc
					(start 132.305806 -46.097444)
					(mid 132.317445 -46.105313)
					(end 132.331206 -46.108112)
				)
				(xy 132.677408 -46.108112)
			)
		)
	)
	(zone
		(layer "F.Cu")
		(hatch none 0.5)
		(connect_pads
			(clearance 0)
		)
		(min_thickness 0.25)
		(keepout
			(tracks allowed)
			(vias allowed)
			(pads allowed)
			(copperpour allowed)
			(footprints allowed)
		)
		(placement
			(enabled no)
			(sheetname "")
		)
		(fill
			(thermal_gap 0.5)
			(thermal_bridge_width 0.5)
			(island_removal_mode 0)
		)
		(polygon
			(pts
				(xy 80.137 -66.675) (xy 82.7278 -66.675) (xy 82.7278 -70.4088) (xy 83.3374 -70.4088) (xy 83.3374 -71.628)
				(xy 80.137 -71.628)
			)
		)
	)
	(zone
		(layer "F.Cu")
		(hatch none 0.5)
		(connect_pads
			(clearance 0)
		)
		(min_thickness 0.25)
		(keepout
			(tracks not_allowed)
			(vias allowed)
			(pads allowed)
			(copperpour not_allowed)
			(footprints allowed)
		)
		(placement
			(enabled no)
			(sheetname "")
		)
		(fill
			(thermal_gap 0.5)
			(thermal_bridge_width 0.5)
			(island_removal_mode 0)
		)
		(polygon
			(pts
				(arc
					(start 170.600624 -23.11527)
					(mid 170.217084 -22.73173)
					(end 169.833544 -23.11527)
				)
				(xy 169.833544 -23.318724) (xy 169.92346 -23.318724)
				(arc
					(start 169.928032 -23.31847)
					(mid 169.975857 -23.3127)
					(end 170.020996 -23.295864)
				)
				(arc
					(start 170.020996 -23.295864)
					(mid 170.335741 -22.876666)
					(end 170.1927 -23.380954)
				)
				(arc
					(start 170.1927 -23.380954)
					(mid 170.088312 -23.454309)
					(end 169.96537 -23.488396)
				)
				(xy 169.963592 -23.48992) (xy 169.937684 -23.48992) (xy 169.928032 -23.490174) (xy 169.92346 -23.48992)
				(xy 169.833544 -23.48992) (xy 169.833544 -23.62962) (xy 169.923714 -23.62962) (xy 169.928286 -23.62962)
				(xy 169.937938 -23.62962) (xy 169.963846 -23.62962)
				(arc
					(start 169.965624 -23.631398)
					(mid 170.088295 -23.665412)
					(end 170.192446 -23.738586)
				)
				(arc
					(start 170.192446 -23.738586)
					(mid 170.335495 -24.243381)
					(end 170.020742 -23.823676)
				)
				(arc
					(start 170.020742 -23.823676)
					(mid 169.975839 -23.807036)
					(end 169.928286 -23.801324)
				)
				(xy 169.923714 -23.801324) (xy 169.833544 -23.801324)
				(arc
					(start 169.833544 -24.004016)
					(mid 170.216957 -24.38781)
					(end 170.600624 -24.00427)
				)
			)
		)
	)
	(zone
		(layer "F.Cu")
		(hatch none 0.5)
		(connect_pads
			(clearance 0)
		)
		(min_thickness 0.25)
		(keepout
			(tracks not_allowed)
			(vias allowed)
			(pads allowed)
			(copperpour not_allowed)
			(footprints allowed)
		)
		(placement
			(enabled no)
			(sheetname "")
		)
		(fill
			(thermal_gap 0.5)
			(thermal_bridge_width 0.5)
			(island_removal_mode 0)
		)
		(polygon
			(pts
				(arc
					(start 126.000256 -61.64199)
					(mid 125.683093 -61.833298)
					(end 125.704854 -62.203076)
				)
				(arc
					(start 125.78969 -62.11824)
					(mid 126.170562 -61.82957)
					(end 125.881892 -62.210442)
				)
				(arc
					(start 125.797056 -62.295278)
					(mid 125.893753 -62.342163)
					(end 126.000002 -62.35827)
				)
				(xy 126.549658 -62.35827)
				(arc
					(start 126.789688 -62.11824)
					(mid 127.17056 -61.82957)
					(end 126.88189 -62.210442)
				)
				(xy 126.734062 -62.35827)
				(arc
					(start 127 -62.35827)
					(mid 127.35814 -62.00013)
					(end 127 -61.64199)
				)
			)
		)
	)
	(zone
		(net "GND")
		(layer "F.Cu")
		(hatch none 0.5)
		(connect_pads
			(clearance 0.5)
		)
		(min_thickness 0.25)
		(fill yes
			(thermal_gap 0.5)
			(thermal_bridge_width 0.5)
			(island_removal_mode 0)
		)
		(polygon
			(pts
				(xy 185.6994 -21.59) (xy 185.039 -22.2504) (xy 183.9976 -22.2504) (xy 183.8706 -22.3774) (xy 183.8706 -22.8346)
				(xy 183.9595 -22.9235) (xy 185.1787 -22.9235) (xy 185.3184 -22.7838) (xy 186.3852 -22.7838) (xy 186.563 -22.9616)
				(xy 186.563 -23.1394) (xy 186.6646 -23.241) (xy 187.1726 -23.241) (xy 187.2234 -23.1902) (xy 187.2234 -21.717)
				(xy 187.0964 -21.59)
			)
		)
		(polygon
			(pts
				(xy 186.7662 -22.5552) (xy 186.563 -22.5552) (xy 186.563 -22.7584) (xy 186.7662 -22.7584)
			)
		)
		(polygon
			(pts
				(xy 186.2836 -22.1234) (xy 186.0804 -22.1234) (xy 186.0804 -22.3266) (xy 186.2836 -22.3266)
			)
		)
		(polygon
			(pts
				(xy 185.7248 -22.1234) (xy 185.5216 -22.1234) (xy 185.5216 -22.3266) (xy 185.7248 -22.3266)
			)
		)
		(polygon
			(pts
				(xy 186.7662 -22.0726) (xy 186.563 -22.0726) (xy 186.563 -22.2758) (xy 186.7662 -22.2758)
			)
		)
	)
	(zone
		(layer "F.Cu")
		(hatch none 0.5)
		(connect_pads
			(clearance 0)
		)
		(min_thickness 0.25)
		(keepout
			(tracks allowed)
			(vias allowed)
			(pads allowed)
			(copperpour allowed)
			(footprints allowed)
		)
		(placement
			(enabled no)
			(sheetname "")
		)
		(fill
			(thermal_gap 0.5)
			(thermal_bridge_width 0.5)
			(island_removal_mode 0)
		)
		(polygon
			(pts
				(xy 17.927066 -87.982552) (xy 17.927066 -86.57717) (xy 18.899632 -86.57717) (xy 18.899632 -87.982552)
			)
		)
	)
	(zone
		(net "P1V5_E_SNB")
		(layer "F.Cu")
		(hatch none 0.5)
		(connect_pads
			(clearance 0.5)
		)
		(min_thickness 0.25)
		(fill yes
			(thermal_gap 0.5)
			(thermal_bridge_width 0.5)
			(island_removal_mode 0)
		)
		(polygon
			(pts
				(xy 152.16378 -108.64342) (xy 151.896064 -108.911136) (xy 151.896064 -110.595664) (xy 151.979376 -110.678976)
				(xy 152.665684 -110.678976) (xy 152.89022 -110.45444) (xy 154.55646 -110.45444) (xy 154.7622 -110.2487)
				(xy 154.7622 -108.84916) (xy 154.55646 -108.64342)
			)
		)
		(polygon
			(pts
				(xy 152.6286 -109.9566) (xy 152.4254 -109.9566) (xy 152.4254 -110.1598) (xy 152.6286 -110.1598)
			)
		)
	)
	(zone
		(layer "F.Cu")
		(hatch none 0.5)
		(connect_pads
			(clearance 0)
		)
		(min_thickness 0.25)
		(keepout
			(tracks allowed)
			(vias allowed)
			(pads allowed)
			(copperpour allowed)
			(footprints allowed)
		)
		(placement
			(enabled no)
			(sheetname "")
		)
		(fill
			(thermal_gap 0.5)
			(thermal_bridge_width 0.5)
			(island_removal_mode 0)
		)
		(polygon
			(pts
				(xy 68.45808 -80.086708) (xy 68.45808 -78.681326) (xy 69.430646 -78.681326) (xy 69.430646 -80.086708)
			)
		)
	)
	(zone
		(layer "F.Cu")
		(hatch none 0.5)
		(connect_pads
			(clearance 0)
		)
		(min_thickness 0.25)
		(keepout
			(tracks not_allowed)
			(vias allowed)
			(pads allowed)
			(copperpour not_allowed)
			(footprints allowed)
		)
		(placement
			(enabled no)
			(sheetname "")
		)
		(fill
			(thermal_gap 0.5)
			(thermal_bridge_width 0.5)
			(island_removal_mode 0)
		)
		(polygon
			(pts
				(xy 138.486134 -78.044294)
				(arc
					(start 138.486134 -78.045056)
					(mid 138.103356 -78.427834)
					(end 138.486134 -78.810612)
				)
				(xy 138.486134 -78.811374) (xy 139.62888 -78.811374) (xy 139.629134 -78.81112)
				(arc
					(start 139.629134 -78.810612)
					(mid 140.011912 -78.427834)
					(end 139.629134 -78.045056)
				)
				(xy 139.629134 -78.044294) (xy 139.335764 -78.044294)
				(arc
					(start 139.335764 -78.302612)
					(mid 139.339656 -78.321707)
					(end 139.350496 -78.337918)
				)
				(arc
					(start 139.350496 -78.337918)
					(mid 139.361159 -78.346176)
					(end 139.37361 -78.35138)
				)
				(arc
					(start 139.37361 -78.35138)
					(mid 139.895849 -78.428637)
					(end 139.373102 -78.502764)
				)
				(xy 139.355322 -78.502764)
				(arc
					(start 139.352274 -78.49997)
					(mid 139.293977 -78.480385)
					(end 139.244324 -78.44409)
				)
				(arc
					(start 139.244324 -78.443836)
					(mid 139.208223 -78.394542)
					(end 139.188698 -78.336648)
				)
				(xy 139.185904 -78.3336) (xy 139.185904 -78.044294) (xy 138.929364 -78.044294) (xy 138.929364 -78.332584)
				(arc
					(start 138.926316 -78.335632)
					(mid 138.9139 -78.378564)
					(end 138.89228 -78.417674)
				)
				(xy 138.89228 -78.421738) (xy 138.87069 -78.443582) (xy 138.870182 -78.443836) (xy 138.869166 -78.444852)
				(xy 138.848084 -78.465934)
				(arc
					(start 138.844274 -78.465934)
					(mid 138.805419 -78.487539)
					(end 138.76274 -78.49997)
				)
				(xy 138.759692 -78.502764)
				(arc
					(start 138.742166 -78.502764)
					(mid 138.219364 -78.428758)
					(end 138.741658 -78.351126)
				)
				(arc
					(start 138.741658 -78.351126)
					(mid 138.75339 -78.346323)
					(end 138.763502 -78.33868)
				)
				(arc
					(start 138.764518 -78.337664)
					(mid 138.775604 -78.321117)
					(end 138.779504 -78.301596)
				)
				(xy 138.779504 -78.044294)
			)
		)
	)
	(zone
		(layer "F.Cu")
		(hatch none 0.5)
		(connect_pads
			(clearance 0)
		)
		(min_thickness 0.25)
		(keepout
			(tracks not_allowed)
			(vias allowed)
			(pads allowed)
			(copperpour not_allowed)
			(footprints allowed)
		)
		(placement
			(enabled no)
			(sheetname "")
		)
		(fill
			(thermal_gap 0.5)
			(thermal_bridge_width 0.5)
			(island_removal_mode 0)
		)
		(polygon
			(pts
				(arc
					(start 130.000248 -72.641968)
					(mid 129.893874 -72.658051)
					(end 129.797048 -72.70496)
				)
				(arc
					(start 129.881884 -72.789796)
					(mid 130.170554 -73.170668)
					(end 129.789682 -72.881998)
				)
				(arc
					(start 129.704846 -72.797162)
					(mid 129.682983 -73.166851)
					(end 129.999994 -73.358248)
				)
				(arc
					(start 130.999992 -73.358248)
					(mid 131.358132 -73.000108)
					(end 130.999992 -72.641968)
				)
				(xy 130.734054 -72.641968)
				(arc
					(start 130.881882 -72.789796)
					(mid 131.170552 -73.170668)
					(end 130.78968 -72.881998)
				)
				(xy 130.54965 -72.641968)
			)
		)
	)
	(zone
		(net "MB0_CM_GATE")
		(layer "F.Cu")
		(hatch none 0.5)
		(connect_pads
			(clearance 0.5)
		)
		(min_thickness 0.25)
		(fill yes
			(thermal_gap 0.5)
			(thermal_bridge_width 0.5)
			(island_removal_mode 0)
		)
		(polygon
			(pts
				(xy 5.157724 -42.822622) (xy 5.034026 -42.94632) (xy 5.034026 -50.176176) (xy 5.711952 -50.853848)
				(xy 10.036048 -50.853848) (xy 10.83945 -51.65725) (xy 11.84275 -51.65725) (xy 11.886692 -51.613308)
				(xy 11.886692 -51.241452) (xy 11.7348 -51.08956) (xy 11.7348 -50.6222) (xy 10.374376 -49.261776)
				(xy 7.053326 -49.261776) (xy 6.626098 -48.834548) (xy 6.626098 -45.356272) (xy 7.278116 -44.704254)
				(xy 7.278116 -42.947082) (xy 7.153656 -42.822622)
			)
		)
	)
	(zone
		(layer "F.Cu")
		(hatch none 0.5)
		(connect_pads
			(clearance 0)
		)
		(min_thickness 0.25)
		(keepout
			(tracks allowed)
			(vias allowed)
			(pads allowed)
			(copperpour allowed)
			(footprints not_allowed)
		)
		(placement
			(enabled no)
			(sheetname "")
		)
		(fill
			(thermal_gap 0.5)
			(thermal_bridge_width 0.5)
			(island_removal_mode 0)
		)
		(polygon
			(pts
				(arc
					(start 131.99999 -94.309946)
					(mid 134.999984 -91.309952)
					(end 137.999978 -94.309946)
				)
				(arc
					(start 137.999978 -94.309946)
					(mid 134.999984 -97.30994)
					(end 131.99999 -94.309946)
				)
			)
		)
	)
	(zone
		(layer "F.Cu")
		(hatch none 0.5)
		(connect_pads
			(clearance 0)
		)
		(min_thickness 0.25)
		(keepout
			(tracks allowed)
			(vias allowed)
			(pads allowed)
			(copperpour allowed)
			(footprints allowed)
		)
		(placement
			(enabled no)
			(sheetname "")
		)
		(fill
			(thermal_gap 0.5)
			(thermal_bridge_width 0.5)
			(island_removal_mode 0)
		)
		(polygon
			(pts
				(xy 147.679918 -40.038528) (xy 147.47367 -40.903398) (xy 147.103084 -40.815006) (xy 147.309332 -39.950136)
			)
		)
	)
	(zone
		(layer "F.Cu")
		(hatch none 0.5)
		(connect_pads
			(clearance 0)
		)
		(min_thickness 0.25)
		(keepout
			(tracks allowed)
			(vias allowed)
			(pads allowed)
			(copperpour allowed)
			(footprints allowed)
		)
		(placement
			(enabled no)
			(sheetname "")
		)
		(fill
			(thermal_gap 0.5)
			(thermal_bridge_width 0.5)
			(island_removal_mode 0)
		)
		(polygon
			(pts
				(xy 44.5516 -32.0802) (xy 44.5516 -30.2768) (xy 45.5676 -30.2768) (xy 45.5676 -32.0802)
			)
		)
	)
	(zone
		(net "GND")
		(layer "F.Cu")
		(hatch none 0.5)
		(connect_pads
			(clearance 0.5)
		)
		(min_thickness 0.25)
		(fill yes
			(thermal_gap 0.5)
			(thermal_bridge_width 0.5)
			(island_removal_mode 0)
		)
		(polygon
			(pts
				(xy 71.198994 -18.63471) (xy 71.173594 -18.66011) (xy 71.173594 -20.04441) (xy 71.275194 -20.14601)
				(xy 72.710294 -20.14601) (xy 72.811894 -20.04441) (xy 72.811894 -18.66011) (xy 72.786494 -18.63471)
			)
		)
	)
	(zone
		(layer "F.Cu")
		(hatch none 0.5)
		(connect_pads
			(clearance 0)
		)
		(min_thickness 0.25)
		(keepout
			(tracks allowed)
			(vias allowed)
			(pads allowed)
			(copperpour allowed)
			(footprints not_allowed)
		)
		(placement
			(enabled no)
			(sheetname "")
		)
		(fill
			(thermal_gap 0.5)
			(thermal_bridge_width 0.5)
			(island_removal_mode 0)
		)
		(polygon
			(pts
				(xy 140.999972 -33.684972) (xy 89.000076 -33.684972) (xy 89.000076 -100.315014) (xy 140.999972 -100.315014)
			)
		)
	)
	(zone
		(layer "F.Cu")
		(hatch none 0.5)
		(connect_pads
			(clearance 0)
		)
		(min_thickness 0.25)
		(keepout
			(tracks not_allowed)
			(vias allowed)
			(pads allowed)
			(copperpour not_allowed)
			(footprints allowed)
		)
		(placement
			(enabled no)
			(sheetname "")
		)
		(fill
			(thermal_gap 0.5)
			(thermal_bridge_width 0.5)
			(island_removal_mode 0)
		)
		(polygon
			(pts
				(arc
					(start 178.790854 -23.11654)
					(mid 178.407314 -22.733)
					(end 178.023774 -23.11654)
				)
				(xy 178.023774 -23.31974) (xy 178.11369 -23.31974)
				(arc
					(start 178.118262 -23.31974)
					(mid 178.166087 -23.31397)
					(end 178.211226 -23.297134)
				)
				(arc
					(start 178.211226 -23.297134)
					(mid 178.525971 -22.877936)
					(end 178.38293 -23.382224)
				)
				(arc
					(start 178.38293 -23.382224)
					(mid 178.278542 -23.455579)
					(end 178.1556 -23.489666)
				)
				(xy 178.153822 -23.491444) (xy 178.127914 -23.491444) (xy 178.118262 -23.491444) (xy 178.11369 -23.491444)
				(xy 178.023774 -23.491444) (xy 178.023774 -23.631144) (xy 178.113944 -23.631144) (xy 178.118516 -23.63089)
				(xy 178.128168 -23.631144) (xy 178.154076 -23.631144)
				(arc
					(start 178.155854 -23.632668)
					(mid 178.278525 -23.666682)
					(end 178.382676 -23.739856)
				)
				(arc
					(start 178.382676 -23.739856)
					(mid 178.525725 -24.244651)
					(end 178.210972 -23.824946)
				)
				(arc
					(start 178.210972 -23.824946)
					(mid 178.166069 -23.808306)
					(end 178.118516 -23.802594)
				)
				(xy 178.113944 -23.80234) (xy 178.023774 -23.80234)
				(arc
					(start 178.023774 -24.005286)
					(mid 178.407187 -24.38908)
					(end 178.790854 -24.00554)
				)
			)
		)
	)
	(zone
		(layer "F.Cu")
		(hatch none 0.5)
		(connect_pads
			(clearance 0)
		)
		(min_thickness 0.25)
		(keepout
			(tracks not_allowed)
			(vias allowed)
			(pads allowed)
			(copperpour not_allowed)
			(footprints allowed)
		)
		(placement
			(enabled no)
			(sheetname "")
		)
		(fill
			(thermal_gap 0.5)
			(thermal_bridge_width 0.5)
			(island_removal_mode 0)
		)
		(polygon
			(pts
				(arc
					(start 126.000256 -65.641982)
					(mid 125.683093 -65.83329)
					(end 125.704854 -66.203068)
				)
				(arc
					(start 125.78969 -66.118232)
					(mid 126.170562 -65.829562)
					(end 125.881892 -66.210434)
				)
				(arc
					(start 125.797056 -66.29527)
					(mid 125.893753 -66.342155)
					(end 126.000002 -66.358262)
				)
				(xy 126.549658 -66.358262)
				(arc
					(start 126.789688 -66.118232)
					(mid 127.17056 -65.829562)
					(end 126.88189 -66.210434)
				)
				(xy 126.734062 -66.358262)
				(arc
					(start 127 -66.358262)
					(mid 127.35814 -66.000122)
					(end 127 -65.641982)
				)
			)
		)
	)
	(zone
		(layer "F.Cu")
		(hatch none 0.5)
		(connect_pads
			(clearance 0)
		)
		(min_thickness 0.25)
		(keepout
			(tracks not_allowed)
			(vias allowed)
			(pads allowed)
			(copperpour not_allowed)
			(footprints allowed)
		)
		(placement
			(enabled no)
			(sheetname "")
		)
		(fill
			(thermal_gap 0.5)
			(thermal_bridge_width 0.5)
			(island_removal_mode 0)
		)
		(polygon
			(pts
				(arc
					(start 139.03071 -60.667392)
					(mid 138.57605 -61.122052)
					(end 139.03071 -61.576712)
				)
				(arc
					(start 140.173456 -61.576712)
					(mid 140.62837 -61.122179)
					(end 140.17371 -60.667392)
				)
				(xy 139.88034 -60.667392)
				(arc
					(start 139.88034 -60.995814)
					(mid 139.884294 -61.015312)
					(end 139.895326 -61.031882)
				)
				(arc
					(start 139.896342 -61.032898)
					(mid 139.906462 -61.040526)
					(end 139.918186 -61.045344)
				)
				(arc
					(start 139.918186 -61.045344)
					(mid 140.440498 -61.122977)
					(end 139.917678 -61.196982)
				)
				(xy 139.900152 -61.196982)
				(arc
					(start 139.897104 -61.194188)
					(mid 139.854439 -61.181722)
					(end 139.81557 -61.160152)
				)
				(xy 139.81176 -61.160152) (xy 139.790678 -61.13907) (xy 139.789662 -61.138054) (xy 139.789154 -61.1378)
				(xy 139.767564 -61.115956)
				(arc
					(start 139.767564 -61.111892)
					(mid 139.745972 -61.07277)
					(end 139.733528 -61.02985)
				)
				(xy 139.73048 -61.026802) (xy 139.73048 -60.667392) (xy 139.47394 -60.667392) (xy 139.47394 -61.027818)
				(arc
					(start 139.471146 -61.030866)
					(mid 139.451607 -61.088752)
					(end 139.41552 -61.138054)
				)
				(arc
					(start 139.41552 -61.138308)
					(mid 139.36588 -61.174626)
					(end 139.30757 -61.194188)
				)
				(xy 139.304522 -61.196982)
				(arc
					(start 139.286742 -61.196982)
					(mid 138.76394 -61.122855)
					(end 139.286234 -61.045598)
				)
				(arc
					(start 139.286234 -61.045598)
					(mid 139.298712 -61.040441)
					(end 139.309348 -61.032136)
				)
				(arc
					(start 139.309348 -61.032136)
					(mid 139.320254 -61.015953)
					(end 139.32408 -60.99683)
				)
				(xy 139.32408 -60.667392)
			)
		)
	)
	(zone
		(layer "F.Cu")
		(hatch none 0.5)
		(connect_pads
			(clearance 0)
		)
		(min_thickness 0.25)
		(keepout
			(tracks not_allowed)
			(vias allowed)
			(pads allowed)
			(copperpour not_allowed)
			(footprints allowed)
		)
		(placement
			(enabled no)
			(sheetname "")
		)
		(fill
			(thermal_gap 0.5)
			(thermal_bridge_width 0.5)
			(island_removal_mode 0)
		)
		(polygon
			(pts
				(arc
					(start 148.500084 -29.500068)
					(mid 151.500078 -26.500074)
					(end 154.500072 -29.500068)
				)
				(arc
					(start 154.500072 -29.500068)
					(mid 151.500078 -32.500062)
					(end 148.500084 -29.500068)
				)
			)
		)
	)
	(zone
		(layer "F.Cu")
		(hatch none 0.5)
		(connect_pads
			(clearance 0)
		)
		(min_thickness 0.25)
		(keepout
			(tracks not_allowed)
			(vias allowed)
			(pads allowed)
			(copperpour not_allowed)
			(footprints allowed)
		)
		(placement
			(enabled no)
			(sheetname "")
		)
		(fill
			(thermal_gap 0.5)
			(thermal_bridge_width 0.5)
			(island_removal_mode 0)
		)
		(polygon
			(pts
				(arc
					(start 127.533908 -45.844206)
					(mid 127.076708 -45.387006)
					(end 126.619508 -45.844206)
				)
				(arc
					(start 126.619508 -46.986952)
					(mid 127.076581 -47.444406)
					(end 127.533908 -46.987206)
				)
				(xy 127.533908 -46.693836)
				(arc
					(start 127.187706 -46.693836)
					(mid 127.173957 -46.696664)
					(end 127.162306 -46.704504)
				)
				(arc
					(start 127.162306 -46.704504)
					(mid 127.154437 -46.716143)
					(end 127.151638 -46.729904)
				)
				(arc
					(start 127.151638 -46.731174)
					(mid 127.076708 -47.253977)
					(end 127.001778 -46.731174)
				)
				(xy 127.001778 -46.698916)
				(arc
					(start 127.004826 -46.695614)
					(mid 127.02313 -46.643097)
					(end 127.056134 -46.598332)
				)
				(arc
					(start 127.056134 -46.598332)
					(mid 127.100897 -46.565324)
					(end 127.153416 -46.547024)
				)
				(xy 127.156718 -46.543976) (xy 127.533908 -46.543976) (xy 127.533908 -46.287436) (xy 127.156718 -46.287436)
				(arc
					(start 127.153416 -46.284388)
					(mid 127.100899 -46.266084)
					(end 127.056134 -46.23308)
				)
				(arc
					(start 127.056134 -46.23308)
					(mid 127.023126 -46.188317)
					(end 127.004826 -46.135798)
				)
				(xy 127.001778 -46.132496)
				(arc
					(start 127.001778 -46.100238)
					(mid 127.076708 -45.577435)
					(end 127.151638 -46.100238)
				)
				(arc
					(start 127.151638 -46.101508)
					(mid 127.154466 -46.115257)
					(end 127.162306 -46.126908)
				)
				(arc
					(start 127.162306 -46.126908)
					(mid 127.173945 -46.134777)
					(end 127.187706 -46.137576)
				)
				(xy 127.533908 -46.137576)
			)
		)
	)
	(zone
		(net "MB0_12V_CTRL_GATE1_R")
		(layer "F.Cu")
		(hatch none 0.5)
		(connect_pads
			(clearance 0.5)
		)
		(min_thickness 0.25)
		(fill yes
			(thermal_gap 0.5)
			(thermal_bridge_width 0.5)
			(island_removal_mode 0)
		)
		(polygon
			(pts
				(xy 5.62991 -40.409114) (xy 5.466334 -40.57269) (xy 5.466334 -42.188384) (xy 5.595366 -42.317416)
				(xy 7.230618 -42.317416) (xy 7.290562 -42.257472) (xy 7.290562 -40.496744) (xy 7.202932 -40.409114)
			)
		)
		(polygon
			(pts
				(xy 6.8326 -41.656) (xy 6.6294 -41.656) (xy 6.6294 -41.8592) (xy 6.8326 -41.8592)
			)
		)
		(polygon
			(pts
				(xy 7.1374 -40.9194) (xy 6.9342 -40.9194) (xy 6.9342 -41.1226) (xy 7.1374 -41.1226)
			)
		)
		(polygon
			(pts
				(xy 6.5278 -40.9194) (xy 6.3246 -40.9194) (xy 6.3246 -41.1226) (xy 6.5278 -41.1226)
			)
		)
	)
	(zone
		(layer "F.Cu")
		(hatch none 0.5)
		(connect_pads
			(clearance 0)
		)
		(min_thickness 0.25)
		(keepout
			(tracks allowed)
			(vias allowed)
			(pads allowed)
			(copperpour allowed)
			(footprints allowed)
		)
		(placement
			(enabled no)
			(sheetname "")
		)
		(fill
			(thermal_gap 0.5)
			(thermal_bridge_width 0.5)
			(island_removal_mode 0)
		)
		(polygon
			(pts
				(xy 156.718 -86.9696) (xy 156.718 -84.6328) (xy 159.0294 -84.6328) (xy 159.0294 -86.9696)
			)
		)
	)
	(zone
		(layer "F.Cu")
		(hatch none 0.5)
		(connect_pads
			(clearance 0)
		)
		(min_thickness 0.25)
		(keepout
			(tracks not_allowed)
			(vias allowed)
			(pads allowed)
			(copperpour not_allowed)
			(footprints allowed)
		)
		(placement
			(enabled no)
			(sheetname "")
		)
		(fill
			(thermal_gap 0.5)
			(thermal_bridge_width 0.5)
			(island_removal_mode 0)
		)
		(polygon
			(pts
				(arc
					(start 126.000256 -69.641974)
					(mid 125.893882 -69.658057)
					(end 125.797056 -69.704966)
				)
				(arc
					(start 125.881892 -69.789802)
					(mid 126.170562 -70.170674)
					(end 125.78969 -69.882004)
				)
				(arc
					(start 125.704854 -69.797168)
					(mid 125.682991 -70.166857)
					(end 126.000002 -70.358254)
				)
				(arc
					(start 127 -70.358254)
					(mid 127.35814 -70.000114)
					(end 127 -69.641974)
				)
				(xy 126.734062 -69.641974)
				(arc
					(start 126.88189 -69.789802)
					(mid 127.17056 -70.170674)
					(end 126.789688 -69.882004)
				)
				(xy 126.549658 -69.641974)
			)
		)
	)
	(zone
		(layer "F.Cu")
		(hatch none 0.5)
		(connect_pads
			(clearance 0)
		)
		(min_thickness 0.25)
		(keepout
			(tracks not_allowed)
			(vias allowed)
			(pads allowed)
			(copperpour not_allowed)
			(footprints allowed)
		)
		(placement
			(enabled no)
			(sheetname "")
		)
		(fill
			(thermal_gap 0.5)
			(thermal_bridge_width 0.5)
			(island_removal_mode 0)
		)
		(polygon
			(pts
				(arc
					(start 118.358158 -52.00015)
					(mid 118.000018 -51.64201)
					(end 117.641878 -52.00015)
				)
				(xy 117.641878 -52.266088)
				(arc
					(start 117.789706 -52.11826)
					(mid 118.170578 -51.82959)
					(end 117.881908 -52.210462)
				)
				(xy 117.641878 -52.450492)
				(arc
					(start 117.641878 -52.999894)
					(mid 117.657961 -53.106268)
					(end 117.70487 -53.203094)
				)
				(arc
					(start 117.789706 -53.118258)
					(mid 118.170578 -52.829588)
					(end 117.881908 -53.21046)
				)
				(arc
					(start 117.797072 -53.295296)
					(mid 118.166761 -53.317159)
					(end 118.358158 -53.000148)
				)
			)
		)
	)
	(zone
		(layer "F.Cu")
		(hatch none 0.5)
		(connect_pads
			(clearance 0)
		)
		(min_thickness 0.25)
		(keepout
			(tracks allowed)
			(vias allowed)
			(pads allowed)
			(copperpour allowed)
			(footprints allowed)
		)
		(placement
			(enabled no)
			(sheetname "")
		)
		(fill
			(thermal_gap 0.5)
			(thermal_bridge_width 0.5)
			(island_removal_mode 0)
		)
		(polygon
			(pts
				(xy 142.494 -58.42) (xy 142.494 -57.531) (xy 142.875 -57.531) (xy 142.875 -58.42)
			)
		)
	)
	(zone
		(net "P0V975")
		(layer "F.Cu")
		(hatch none 0.5)
		(connect_pads
			(clearance 0.5)
		)
		(min_thickness 0.25)
		(fill yes
			(thermal_gap 0.5)
			(thermal_bridge_width 0.5)
			(island_removal_mode 0)
		)
		(polygon
			(pts
				(xy 180.3654 -82.3722) (xy 180.0606 -82.677) (xy 172.8216 -82.677) (xy 172.5168 -82.9818) (xy 172.5168 -85.5726)
				(xy 172.8216 -85.8774) (xy 175.1838 -85.8774) (xy 176.6062 -87.2998) (xy 176.6062 -90.1446) (xy 176.6189 -90.1573)
				(xy 176.6189 -91.5543) (xy 176.6443 -91.5797) (xy 176.6443 -93.2688) (xy 178.3969 -95.0214) (xy 180.086 -95.0214)
				(xy 181.229 -96.1644) (xy 181.229 -97.282) (xy 181.356 -97.409) (xy 188.722 -97.409) (xy 189.038484 -97.092516)
				(xy 189.038484 -93.968316) (xy 188.263022 -93.1926) (xy 187.7568 -93.1926) (xy 184.5183 -89.9541)
				(xy 184.5183 -82.8675) (xy 184.023 -82.3722)
			)
		)
		(polygon
			(pts
				(xy 182.3466 -96.4438) (xy 182.1434 -96.4438) (xy 182.1434 -96.647) (xy 182.3466 -96.647)
			)
		)
		(polygon
			(pts
				(xy 173.736 -83.4898) (xy 173.5328 -83.4898) (xy 173.5328 -83.693) (xy 173.736 -83.693)
			)
		)
		(polygon
			(pts
				(xy 172.8724 -83.4898) (xy 172.6692 -83.4898) (xy 172.6692 -83.693) (xy 172.8724 -83.693)
			)
		)
	)
	(zone
		(layer "F.Cu")
		(hatch none 0.5)
		(connect_pads
			(clearance 0)
		)
		(min_thickness 0.25)
		(keepout
			(tracks allowed)
			(vias allowed)
			(pads allowed)
			(copperpour allowed)
			(footprints not_allowed)
		)
		(placement
			(enabled no)
			(sheetname "")
		)
		(fill
			(thermal_gap 0.5)
			(thermal_bridge_width 0.5)
			(island_removal_mode 0)
		)
		(polygon
			(pts
				(arc
					(start 195.49999 -50.500026)
					(mid 198.499984 -47.500032)
					(end 201.499978 -50.500026)
				)
				(arc
					(start 201.499978 -50.500026)
					(mid 198.499984 -53.50002)
					(end 195.49999 -50.500026)
				)
			)
		)
	)
	(zone
		(layer "F.Cu")
		(hatch none 0.5)
		(connect_pads
			(clearance 0)
		)
		(min_thickness 0.25)
		(keepout
			(tracks not_allowed)
			(vias allowed)
			(pads allowed)
			(copperpour not_allowed)
			(footprints allowed)
		)
		(placement
			(enabled no)
			(sheetname "")
		)
		(fill
			(thermal_gap 0.5)
			(thermal_bridge_width 0.5)
			(island_removal_mode 0)
		)
		(polygon
			(pts
				(arc
					(start 120.358154 -52.00015)
					(mid 120.000014 -51.64201)
					(end 119.641874 -52.00015)
				)
				(xy 119.641874 -52.266088)
				(arc
					(start 119.789702 -52.11826)
					(mid 120.170574 -51.82959)
					(end 119.881904 -52.210462)
				)
				(xy 119.641874 -52.450492)
				(arc
					(start 119.641874 -52.999894)
					(mid 119.657957 -53.106268)
					(end 119.704866 -53.203094)
				)
				(arc
					(start 119.789702 -53.118258)
					(mid 120.170574 -52.829588)
					(end 119.881904 -53.21046)
				)
				(arc
					(start 119.797068 -53.295296)
					(mid 120.166757 -53.317159)
					(end 120.358154 -53.000148)
				)
			)
		)
	)
	(zone
		(layer "F.Cu")
		(hatch none 0.5)
		(connect_pads
			(clearance 0)
		)
		(min_thickness 0.25)
		(keepout
			(tracks not_allowed)
			(vias allowed)
			(pads allowed)
			(copperpour not_allowed)
			(footprints allowed)
		)
		(placement
			(enabled no)
			(sheetname "")
		)
		(fill
			(thermal_gap 0.5)
			(thermal_bridge_width 0.5)
			(island_removal_mode 0)
		)
		(polygon
			(pts
				(xy 150.726394 -38.17239) (xy 150.988268 -38.227762) (xy 150.988522 -38.227762) (xy 151.018748 -38.234366)
				(xy 151.048974 -38.240716)
				(arc
					(start 151.060912 -38.243256)
					(mid 151.084673 -38.2413)
					(end 151.10333 -38.226492)
				)
				(arc
					(start 151.10333 -38.226492)
					(mid 151.289203 -37.732659)
					(end 151.251412 -38.259004)
				)
				(xy 151.244808 -38.290754)
				(arc
					(start 151.236426 -38.296088)
					(mid 151.163785 -38.369286)
					(end 151.063706 -38.394132)
				)
				(xy 151.059896 -38.396418) (xy 151.02967 -38.389814) (xy 150.987252 -38.38067) (xy 150.695406 -38.318948)
				(xy 150.641812 -38.570154) (xy 150.987252 -38.643306) (xy 151.010366 -38.643306) (xy 151.016716 -38.649656)
				(xy 151.025352 -38.651434)
				(arc
					(start 151.028146 -38.655752)
					(mid 151.120161 -38.747855)
					(end 151.12365 -38.878002)
				)
				(arc
					(start 151.12365 -38.878002)
					(mid 150.935723 -39.371445)
					(end 150.976584 -38.844982)
				)
				(xy 150.983442 -38.813486)
				(arc
					(start 150.984204 -38.812978)
					(mid 150.979052 -38.801282)
					(end 150.968964 -38.79342)
				)
				(xy 150.94839 -38.79342) (xy 150.941786 -38.786816) (xy 150.610824 -38.716712)
				(arc
					(start 150.54707 -39.016178)
					(mid 150.899368 -39.558468)
					(end 151.441658 -39.20617)
				)
				(arc
					(start 151.676862 -38.098476)
					(mid 151.332298 -37.547107)
					(end 150.784814 -37.89807)
				)
			)
		)
	)
	(zone
		(layer "F.Cu")
		(hatch none 0.5)
		(connect_pads
			(clearance 0)
		)
		(min_thickness 0.25)
		(keepout
			(tracks not_allowed)
			(vias allowed)
			(pads allowed)
			(copperpour not_allowed)
			(footprints allowed)
		)
		(placement
			(enabled no)
			(sheetname "")
		)
		(fill
			(thermal_gap 0.5)
			(thermal_bridge_width 0.5)
			(island_removal_mode 0)
		)
		(polygon
			(pts
				(arc
					(start 107.35818 -55.000144)
					(mid 107.00004 -54.642004)
					(end 106.6419 -55.000144)
				)
				(arc
					(start 106.6419 -55.999888)
					(mid 106.833208 -56.317051)
					(end 107.202986 -56.29529)
				)
				(arc
					(start 107.11815 -56.210454)
					(mid 106.82948 -55.829582)
					(end 107.210352 -56.118252)
				)
				(arc
					(start 107.295188 -56.203088)
					(mid 107.342073 -56.106391)
					(end 107.35818 -56.000142)
				)
				(xy 107.35818 -55.450486)
				(arc
					(start 107.11815 -55.210456)
					(mid 106.82948 -54.829584)
					(end 107.210352 -55.118254)
				)
				(xy 107.35818 -55.266082)
			)
		)
	)
	(zone
		(net "GND")
		(layer "F.Cu")
		(hatch none 0.5)
		(connect_pads
			(clearance 0.5)
		)
		(min_thickness 0.25)
		(fill yes
			(thermal_gap 0.5)
			(thermal_bridge_width 0.5)
			(island_removal_mode 0)
		)
		(polygon
			(pts
				(xy 44.5008 -32.6136) (xy 44.3865 -32.7279) (xy 44.3865 -34.1122) (xy 44.4881 -34.2138) (xy 45.847 -34.2138)
				(xy 45.9359 -34.1249) (xy 45.9359 -32.7025) (xy 45.847 -32.6136)
			)
		)
	)
	(zone
		(layer "F.Cu")
		(hatch none 0.5)
		(connect_pads
			(clearance 0)
		)
		(min_thickness 0.25)
		(keepout
			(tracks not_allowed)
			(vias allowed)
			(pads allowed)
			(copperpour not_allowed)
			(footprints allowed)
		)
		(placement
			(enabled no)
			(sheetname "")
		)
		(fill
			(thermal_gap 0.5)
			(thermal_bridge_width 0.5)
			(island_removal_mode 0)
		)
		(polygon
			(pts
				(arc
					(start 127.000254 -52.642008)
					(mid 126.683091 -52.833316)
					(end 126.704852 -53.203094)
				)
				(arc
					(start 126.789688 -53.118258)
					(mid 127.17056 -52.829588)
					(end 126.88189 -53.21046)
				)
				(arc
					(start 126.797054 -53.295296)
					(mid 126.893751 -53.342181)
					(end 127 -53.358288)
				)
				(xy 127.549656 -53.358288)
				(arc
					(start 127.789686 -53.118258)
					(mid 128.170558 -52.829588)
					(end 127.881888 -53.21046)
				)
				(xy 127.73406 -53.358288)
				(arc
					(start 127.999998 -53.358288)
					(mid 128.358138 -53.000148)
					(end 127.999998 -52.642008)
				)
				(xy 127.704596 -52.642008) (xy 127.605282 -52.741322) (xy 127.40513 -52.741322) (xy 127.305816 -52.642008)
			)
		)
	)
	(zone
		(net "MB0_P12V_MAIN_R")
		(layer "F.Cu")
		(hatch none 0.5)
		(connect_pads
			(clearance 0.5)
		)
		(min_thickness 0.25)
		(fill yes
			(thermal_gap 0.5)
			(thermal_bridge_width 0.5)
			(island_removal_mode 0)
		)
		(polygon
			(pts
				(xy 6.756146 -27.20086) (xy 6.455918 -27.501088) (xy 6.455918 -34.878518) (xy 6.615684 -35.038284)
				(xy 6.616446 -35.038284) (xy 6.690106 -35.111944) (xy 15.738856 -35.111944) (xy 15.9258 -34.925)
				(xy 15.9258 -27.54376) (xy 15.5829 -27.20086)
			)
		)
	)
	(zone
		(net "GND")
		(layer "F.Cu")
		(hatch none 0.5)
		(connect_pads
			(clearance 0.5)
		)
		(min_thickness 0.25)
		(fill yes
			(thermal_gap 0.5)
			(thermal_bridge_width 0.5)
			(island_removal_mode 0)
		)
		(polygon
			(pts
				(xy 84.225638 -52.00396) (xy 83.641438 -52.58816) (xy 83.641438 -56.34736) (xy 84.450936 -57.156858)
				(xy 90.666062 -57.156858) (xy 92.081604 -58.5724) (xy 100.598986 -58.5724) (xy 100.700586 -58.4708)
				(xy 100.700586 -58.34507) (xy 100.129086 -57.77357) (xy 92.06357 -57.77357) (xy 90.05316 -55.76316)
				(xy 87.883238 -55.76316) (xy 87.705438 -55.94096) (xy 87.705438 -56.39816) (xy 87.680038 -56.42356)
				(xy 84.581238 -56.42356) (xy 84.352638 -56.19496) (xy 84.352638 -53.37556) (xy 85.063838 -52.66436)
				(xy 88.8238 -52.66436) (xy 92.603828 -56.444388) (xy 99.048316 -56.444388) (xy 99.3394 -56.735472)
				(xy 100.599494 -56.735472) (xy 100.700586 -56.63438) (xy 100.700586 -56.363362) (xy 100.103686 -55.766462)
				(xy 93.752924 -55.766462) (xy 89.990422 -52.00396)
			)
		)
		(polygon
			(pts
				(xy 88.950038 -56.24576) (xy 88.746838 -56.24576) (xy 88.746838 -56.44896) (xy 88.950038 -56.44896)
			)
		)
		(polygon
			(pts
				(xy 88.340438 -56.24576) (xy 88.137238 -56.24576) (xy 88.137238 -56.44896) (xy 88.340438 -56.44896)
			)
		)
	)
	(zone
		(net "GND")
		(layer "F.Cu")
		(hatch none 0.5)
		(connect_pads
			(clearance 0.5)
		)
		(min_thickness 0.25)
		(fill yes
			(thermal_gap 0.5)
			(thermal_bridge_width 0.5)
			(island_removal_mode 0)
		)
		(polygon
			(pts
				(xy 56.4769 -50.9016) (xy 55.6641 -51.7144) (xy 55.6641 -62.407038) (xy 56.4007 -63.143638) (xy 61.4172 -63.143638)
				(xy 61.976 -62.584838) (xy 61.976 -51.5112) (xy 61.3664 -50.9016)
			)
		)
	)
	(zone
		(layer "F.Cu")
		(hatch none 0.5)
		(connect_pads
			(clearance 0)
		)
		(min_thickness 0.25)
		(keepout
			(tracks allowed)
			(vias allowed)
			(pads allowed)
			(copperpour allowed)
			(footprints allowed)
		)
		(placement
			(enabled no)
			(sheetname "")
		)
		(fill
			(thermal_gap 0.5)
			(thermal_bridge_width 0.5)
			(island_removal_mode 0)
		)
		(polygon
			(pts
				(xy 202.565 -86.83117) (xy 201.331322 -86.83117) (xy 201.331322 -85.8012) (xy 202.565 -85.8012)
			)
		)
	)
	(zone
		(layer "F.Cu")
		(hatch none 0.5)
		(connect_pads
			(clearance 0)
		)
		(min_thickness 0.25)
		(keepout
			(tracks not_allowed)
			(vias allowed)
			(pads allowed)
			(copperpour not_allowed)
			(footprints allowed)
		)
		(placement
			(enabled no)
			(sheetname "")
		)
		(fill
			(thermal_gap 0.5)
			(thermal_bridge_width 0.5)
			(island_removal_mode 0)
		)
		(polygon
			(pts
				(arc
					(start 119.358156 -55.000144)
					(mid 119.000016 -54.642004)
					(end 118.641876 -55.000144)
				)
				(xy 118.641876 -55.266082)
				(arc
					(start 118.789704 -55.118254)
					(mid 119.170576 -54.829584)
					(end 118.881906 -55.210456)
				)
				(xy 118.641876 -55.450486)
				(arc
					(start 118.641876 -55.999888)
					(mid 118.657959 -56.106262)
					(end 118.704868 -56.203088)
				)
				(arc
					(start 118.789704 -56.118252)
					(mid 119.170576 -55.829582)
					(end 118.881906 -56.210454)
				)
				(arc
					(start 118.79707 -56.29529)
					(mid 119.166759 -56.317153)
					(end 119.358156 -56.000142)
				)
			)
		)
	)
	(zone
		(net "P1V8_C")
		(layer "F.Cu")
		(hatch none 0.5)
		(connect_pads
			(clearance 0.5)
		)
		(min_thickness 0.25)
		(fill yes
			(thermal_gap 0.5)
			(thermal_bridge_width 0.5)
			(island_removal_mode 0)
		)
		(polygon
			(pts
				(xy 192.089532 -45.1866) (xy 192.013332 -45.2628) (xy 192.013332 -50.348388) (xy 192.171574 -50.50663)
				(xy 193.636138 -50.50663) (xy 193.878708 -50.7492) (xy 193.878708 -51.685952) (xy 193.463926 -52.100734)
				(xy 192.091564 -52.100734) (xy 192.029842 -52.162456) (xy 192.029842 -52.581556) (xy 192.120266 -52.67198)
				(xy 194.741292 -52.67198) (xy 195.226178 -52.187094) (xy 195.226178 -45.582078) (xy 194.8307 -45.1866)
			)
		)
		(polygon
			(pts
				(xy 192.66662 -49.7078) (xy 192.46342 -49.7078) (xy 192.46342 -49.911) (xy 192.66662 -49.911)
			)
		)
		(polygon
			(pts
				(xy 192.663572 -47.740062) (xy 192.460372 -47.740062) (xy 192.460372 -47.943262) (xy 192.663572 -47.943262)
			)
		)
		(polygon
			(pts
				(xy 192.663572 -47.181262) (xy 192.460372 -47.181262) (xy 192.460372 -47.384462) (xy 192.663572 -47.384462)
			)
		)
		(polygon
			(pts
				(xy 192.663572 -46.698662) (xy 192.460372 -46.698662) (xy 192.460372 -46.901862) (xy 192.663572 -46.901862)
			)
		)
		(polygon
			(pts
				(xy 192.663572 -46.139862) (xy 192.460372 -46.139862) (xy 192.460372 -46.343062) (xy 192.663572 -46.343062)
			)
		)
		(polygon
			(pts
				(xy 192.663572 -45.657262) (xy 192.460372 -45.657262) (xy 192.460372 -45.860462) (xy 192.663572 -45.860462)
			)
		)
	)
	(zone
		(layer "F.Cu")
		(hatch none 0.5)
		(connect_pads
			(clearance 0)
		)
		(min_thickness 0.25)
		(keepout
			(tracks allowed)
			(vias allowed)
			(pads allowed)
			(copperpour allowed)
			(footprints allowed)
		)
		(placement
			(enabled no)
			(sheetname "")
		)
		(fill
			(thermal_gap 0.5)
			(thermal_bridge_width 0.5)
			(island_removal_mode 0)
		)
		(polygon
			(pts
				(xy 148.142452 -34.99485) (xy 147.936204 -35.85972) (xy 147.565618 -35.771328) (xy 147.771866 -34.906458)
			)
		)
	)
	(zone
		(layer "F.Cu")
		(hatch none 0.5)
		(connect_pads
			(clearance 0)
		)
		(min_thickness 0.25)
		(keepout
			(tracks not_allowed)
			(vias allowed)
			(pads allowed)
			(copperpour not_allowed)
			(footprints allowed)
		)
		(placement
			(enabled no)
			(sheetname "")
		)
		(fill
			(thermal_gap 0.5)
			(thermal_bridge_width 0.5)
			(island_removal_mode 0)
		)
		(polygon
			(pts
				(arc
					(start 126.000256 -67.641978)
					(mid 125.893882 -67.658061)
					(end 125.797056 -67.70497)
				)
				(arc
					(start 125.881892 -67.789806)
					(mid 126.170562 -68.170678)
					(end 125.78969 -67.882008)
				)
				(arc
					(start 125.704854 -67.797172)
					(mid 125.682991 -68.166861)
					(end 126.000002 -68.358258)
				)
				(arc
					(start 127 -68.358258)
					(mid 127.35814 -68.000118)
					(end 127 -67.641978)
				)
				(xy 126.734062 -67.641978)
				(arc
					(start 126.88189 -67.789806)
					(mid 127.17056 -68.170678)
					(end 126.789688 -67.882008)
				)
				(xy 126.549658 -67.641978)
			)
		)
	)
	(zone
		(layer "F.Cu")
		(hatch none 0.5)
		(connect_pads
			(clearance 0)
		)
		(min_thickness 0.25)
		(keepout
			(tracks allowed)
			(vias allowed)
			(pads allowed)
			(copperpour allowed)
			(footprints allowed)
		)
		(placement
			(enabled no)
			(sheetname "")
		)
		(fill
			(thermal_gap 0.5)
			(thermal_bridge_width 0.5)
			(island_removal_mode 0)
		)
		(polygon
			(pts
				(xy 197.876922 -88.40597) (xy 196.759322 -88.40597) (xy 196.759322 -85.8012) (xy 197.876922 -85.8012)
			)
		)
	)
	(zone
		(layer "F.Cu")
		(hatch none 0.5)
		(connect_pads
			(clearance 0)
		)
		(min_thickness 0.25)
		(keepout
			(tracks not_allowed)
			(vias allowed)
			(pads allowed)
			(copperpour not_allowed)
			(footprints allowed)
		)
		(placement
			(enabled no)
			(sheetname "")
		)
		(fill
			(thermal_gap 0.5)
			(thermal_bridge_width 0.5)
			(island_removal_mode 0)
		)
		(polygon
			(pts
				(arc
					(start 180.561234 -7.400036)
					(mid 179.999894 -6.838696)
					(end 179.438554 -7.400036)
				)
				(xy 179.438554 -7.85876) (xy 179.8193 -7.85876)
				(arc
					(start 179.823872 -7.858506)
					(mid 179.881901 -7.837353)
					(end 179.912772 -7.78383)
				)
				(arc
					(start 179.912772 -7.78383)
					(mid 180.001195 -7.006423)
					(end 180.085492 -7.784338)
				)
				(xy 180.085492 -7.803896)
				(arc
					(start 180.082952 -7.806436)
					(mid 180.00904 -7.953504)
					(end 179.861972 -8.027416)
				)
				(xy 179.859432 -8.029956) (xy 179.832 -8.029956) (xy 179.823872 -8.03021) (xy 179.8193 -8.029956)
				(xy 179.438554 -8.029956) (xy 179.438554 -8.169656) (xy 179.819046 -8.169656) (xy 179.823618 -8.169656)
				(xy 179.831746 -8.169656) (xy 179.859178 -8.169656)
				(arc
					(start 179.861718 -8.17245)
					(mid 180.008963 -8.246439)
					(end 180.082952 -8.393684)
				)
				(xy 180.085492 -8.396224)
				(arc
					(start 180.085492 -8.415782)
					(mid 180.001195 -9.193747)
					(end 179.912772 -8.41629)
				)
				(arc
					(start 179.912772 -8.41629)
					(mid 179.881869 -8.362536)
					(end 179.823618 -8.34136)
				)
				(xy 179.819046 -8.34136) (xy 179.438554 -8.34136)
				(arc
					(start 179.438554 -8.79983)
					(mid 179.999767 -9.361424)
					(end 180.561234 -8.800084)
				)
			)
		)
	)
	(zone
		(layer "F.Cu")
		(hatch none 0.5)
		(connect_pads
			(clearance 0)
		)
		(min_thickness 0.25)
		(keepout
			(tracks not_allowed)
			(vias allowed)
			(pads allowed)
			(copperpour not_allowed)
			(footprints allowed)
		)
		(placement
			(enabled no)
			(sheetname "")
		)
		(fill
			(thermal_gap 0.5)
			(thermal_bridge_width 0.5)
			(island_removal_mode 0)
		)
		(polygon
			(pts
				(arc
					(start 166.58336 -37.600128)
					(mid 166.199947 -37.216334)
					(end 165.81628 -37.599874)
				)
				(xy 165.81628 -37.924994) (xy 165.831012 -37.924994) (xy 165.874954 -37.968936) (xy 165.874954 -37.96919)
				(arc
					(start 166.071804 -38.16604)
					(mid 166.388385 -38.588539)
					(end 165.965886 -38.271958)
				)
				(xy 165.81628 -38.122352)
				(arc
					(start 165.81628 -38.399974)
					(mid 166.19982 -38.783514)
					(end 166.58336 -38.399974)
				)
				(xy 166.58336 -38.074854) (xy 166.568882 -38.074854)
				(arc
					(start 166.327836 -37.833808)
					(mid 166.011255 -37.411309)
					(end 166.433754 -37.72789)
				)
				(xy 166.58336 -37.877496)
			)
		)
	)
	(zone
		(net "GB_VDDH")
		(layer "F.Cu")
		(hatch none 0.5)
		(connect_pads
			(clearance 0.5)
		)
		(min_thickness 0.25)
		(fill yes
			(thermal_gap 0.5)
			(thermal_bridge_width 0.5)
			(island_removal_mode 0)
		)
		(polygon
			(pts
				(xy 143.355314 -95.81007) (xy 140.847826 -98.317558) (xy 140.847826 -100.25761) (xy 140.979398 -100.389182)
				(xy 147.782026 -100.389182) (xy 147.99691 -100.174298) (xy 147.99691 -96.391984) (xy 147.414996 -95.81007)
			)
		)
		(polygon
			(pts
				(xy 147.2438 -100.076) (xy 147.0406 -100.076) (xy 147.0406 -100.2792) (xy 147.2438 -100.2792)
			)
		)
		(polygon
			(pts
				(xy 144.4244 -100.076) (xy 144.2212 -100.076) (xy 144.2212 -100.2792) (xy 144.4244 -100.2792)
			)
		)
		(polygon
			(pts
				(xy 143.5608 -100.076) (xy 143.3576 -100.076) (xy 143.3576 -100.2792) (xy 143.5608 -100.2792)
			)
		)
		(polygon
			(pts
				(xy 147.2438 -99.2124) (xy 147.0406 -99.2124) (xy 147.0406 -99.4156) (xy 147.2438 -99.4156)
			)
		)
		(polygon
			(pts
				(xy 144.4244 -99.2124) (xy 144.2212 -99.2124) (xy 144.2212 -99.4156) (xy 144.4244 -99.4156)
			)
		)
		(polygon
			(pts
				(xy 143.5608 -99.2124) (xy 143.3576 -99.2124) (xy 143.3576 -99.4156) (xy 143.5608 -99.4156)
			)
		)
	)
	(zone
		(layer "F.Cu")
		(hatch none 0.5)
		(connect_pads
			(clearance 0)
		)
		(min_thickness 0.25)
		(keepout
			(tracks allowed)
			(vias allowed)
			(pads allowed)
			(copperpour allowed)
			(footprints allowed)
		)
		(placement
			(enabled no)
			(sheetname "")
		)
		(fill
			(thermal_gap 0.5)
			(thermal_bridge_width 0.5)
			(island_removal_mode 0)
		)
		(polygon
			(pts
				(xy 201.676 -98.28657) (xy 200.442322 -98.28657) (xy 200.442322 -97.2566) (xy 201.676 -97.2566)
			)
		)
	)
	(zone
		(net "AGND_P3V3")
		(layer "F.Cu")
		(hatch none 0.5)
		(connect_pads
			(clearance 0.5)
		)
		(min_thickness 0.25)
		(fill yes
			(thermal_gap 0.5)
			(thermal_bridge_width 0.5)
			(island_removal_mode 0)
		)
		(polygon
			(pts
				(xy 70.46468 -94.488) (xy 70.380606 -94.572074) (xy 70.380606 -95.33636) (xy 70.204584 -95.512382)
				(xy 69.593206 -95.512382) (xy 69.34327 -95.762318) (xy 69.34327 -98.297238) (xy 69.215 -98.425508)
				(xy 69.215 -101.346) (xy 69.342 -101.473) (xy 71.628 -101.473) (xy 71.755 -101.346) (xy 71.755 -94.615)
				(xy 71.628 -94.488)
			)
		)
		(polygon
			(pts
				(xy 71.247 -100.7872) (xy 71.0438 -100.7872) (xy 71.0438 -100.9904) (xy 71.247 -100.9904)
			)
		)
		(polygon
			(pts
				(xy 70.6882 -100.7872) (xy 70.485 -100.7872) (xy 70.485 -100.9904) (xy 70.6882 -100.9904)
			)
		)
		(polygon
			(pts
				(xy 69.994272 -97.2566) (xy 69.791072 -97.2566) (xy 69.791072 -97.4598) (xy 69.994272 -97.4598)
			)
		)
		(polygon
			(pts
				(xy 69.994272 -96.6978) (xy 69.791072 -96.6978) (xy 69.791072 -96.901) (xy 69.994272 -96.901)
			)
		)
		(polygon
			(pts
				(xy 69.994272 -96.2406) (xy 69.791072 -96.2406) (xy 69.791072 -96.4438) (xy 69.994272 -96.4438)
			)
		)
		(polygon
			(pts
				(xy 69.994272 -95.6818) (xy 69.791072 -95.6818) (xy 69.791072 -95.885) (xy 69.994272 -95.885)
			)
		)
		(polygon
			(pts
				(xy 71.035926 -95.02775) (xy 70.832726 -95.02775) (xy 70.832726 -95.23095) (xy 71.035926 -95.23095)
			)
		)
	)
	(zone
		(net "GND")
		(layer "F.Cu")
		(hatch none 0.5)
		(connect_pads
			(clearance 0.5)
		)
		(min_thickness 0.25)
		(fill yes
			(thermal_gap 0.5)
			(thermal_bridge_width 0.5)
			(island_removal_mode 0)
		)
		(polygon
			(pts
				(xy 57.15 -32.5755) (xy 56.1721 -33.5534) (xy 56.1721 -40.5257) (xy 56.4388 -40.7924) (xy 61.22797 -40.7924)
				(xy 61.70168 -40.31869) (xy 61.70168 -33.680146) (xy 60.597034 -32.5755)
			)
		)
	)
	(zone
		(layer "F.Cu")
		(hatch none 0.5)
		(connect_pads
			(clearance 0)
		)
		(min_thickness 0.25)
		(keepout
			(tracks not_allowed)
			(vias allowed)
			(pads allowed)
			(copperpour not_allowed)
			(footprints allowed)
		)
		(placement
			(enabled no)
			(sheetname "")
		)
		(fill
			(thermal_gap 0.5)
			(thermal_bridge_width 0.5)
			(island_removal_mode 0)
		)
		(polygon
			(pts
				(arc
					(start 116.358162 -52.00015)
					(mid 116.000022 -51.64201)
					(end 115.641882 -52.00015)
				)
				(xy 115.641882 -52.266088)
				(arc
					(start 115.78971 -52.11826)
					(mid 116.170582 -51.82959)
					(end 115.881912 -52.210462)
				)
				(xy 115.641882 -52.450492)
				(arc
					(start 115.641882 -52.999894)
					(mid 115.657965 -53.106268)
					(end 115.704874 -53.203094)
				)
				(arc
					(start 115.78971 -53.118258)
					(mid 116.170582 -52.829588)
					(end 115.881912 -53.21046)
				)
				(arc
					(start 115.797076 -53.295296)
					(mid 116.166765 -53.317159)
					(end 116.358162 -53.000148)
				)
			)
		)
	)
	(zone
		(net "GND")
		(layer "F.Cu")
		(hatch none 0.5)
		(connect_pads
			(clearance 0.5)
		)
		(min_thickness 0.25)
		(fill yes
			(thermal_gap 0.5)
			(thermal_bridge_width 0.5)
			(island_removal_mode 0)
		)
		(polygon
			(pts
				(xy 18.4658 -27.178) (xy 17.8054 -27.8384) (xy 17.8054 -31.4452) (xy 17.9324 -31.5722) (xy 20.5486 -31.5722)
				(xy 21.3868 -30.734) (xy 30.4038 -30.734) (xy 30.41015 -30.72765) (xy 30.4165 -30.734) (xy 30.78734 -30.734)
				(xy 31.1023 -30.41904) (xy 31.1023 -27.48534) (xy 30.79496 -27.178)
			)
		)
	)
	(zone
		(net "P3V3")
		(layer "F.Cu")
		(hatch none 0.5)
		(connect_pads
			(clearance 0.5)
		)
		(min_thickness 0.25)
		(fill yes
			(thermal_gap 0.5)
			(thermal_bridge_width 0.5)
			(island_removal_mode 0)
		)
		(polygon
			(pts
				(xy 157.9118 -93.3704) (xy 157.8991 -93.3831) (xy 157.7721 -93.3831) (xy 157.7086 -93.4466) (xy 157.7086 -94.4118)
				(xy 158.1404 -94.8436) (xy 158.7246 -94.8436) (xy 158.8008 -94.7674) (xy 158.8008 -94.488) (xy 158.4706 -94.1578)
				(xy 158.4706 -93.3958) (xy 158.4452 -93.3704)
			)
		)
	)
	(zone
		(net "P1V5_C")
		(layer "F.Cu")
		(hatch none 0.5)
		(connect_pads
			(clearance 0.5)
		)
		(min_thickness 0.25)
		(fill yes
			(thermal_gap 0.5)
			(thermal_bridge_width 0.5)
			(island_removal_mode 0)
		)
		(polygon
			(pts
				(xy 157.1752 -68.6943) (xy 156.950918 -68.918582) (xy 156.950918 -71.080884) (xy 157.103826 -71.233792)
				(xy 158.069788 -71.233792) (xy 158.218632 -71.084948) (xy 158.218632 -69.218302) (xy 158.212028 -69.211952)
				(xy 158.212028 -68.933568) (xy 157.97276 -68.6943)
			)
		)
		(polygon
			(pts
				(xy 157.7594 -70.42023) (xy 157.5562 -70.42023) (xy 157.5562 -70.62343) (xy 157.7594 -70.62343)
			)
		)
	)
	(zone
		(net "GND")
		(layer "F.Cu")
		(hatch none 0.5)
		(connect_pads
			(clearance 0.5)
		)
		(min_thickness 0.25)
		(fill yes
			(thermal_gap 0.5)
			(thermal_bridge_width 0.5)
			(island_removal_mode 0)
		)
		(polygon
			(pts
				(xy 176.1744 -76.2) (xy 175.9458 -76.4286) (xy 175.9458 -82.1436) (xy 176.1744 -82.3722) (xy 179.9082 -82.3722)
				(xy 180.1368 -82.1436) (xy 180.1368 -77.0382) (xy 179.2986 -76.2)
			)
		)
		(polygon
			(pts
				(xy 177.038 -78.1304) (xy 176.8348 -78.1304) (xy 176.8348 -78.3336) (xy 177.038 -78.3336)
			)
		)
		(polygon
			(pts
				(xy 177.038 -77.2668) (xy 176.8348 -77.2668) (xy 176.8348 -77.47) (xy 177.038 -77.47)
			)
		)
		(polygon
			(pts
				(xy 176.657 -76.9874) (xy 176.4538 -76.9874) (xy 176.4538 -77.1906) (xy 176.657 -77.1906)
			)
		)
	)
	(zone
		(layer "F.Cu")
		(hatch none 0.5)
		(connect_pads
			(clearance 0)
		)
		(min_thickness 0.25)
		(keepout
			(tracks allowed)
			(vias allowed)
			(pads allowed)
			(copperpour allowed)
			(footprints not_allowed)
		)
		(placement
			(enabled no)
			(sheetname "")
		)
		(fill
			(thermal_gap 0.5)
			(thermal_bridge_width 0.5)
			(island_removal_mode 0)
		)
		(polygon
			(pts
				(arc
					(start 92.00007 -39.67988)
					(mid 95.000064 -36.679886)
					(end 98.000058 -39.67988)
				)
				(arc
					(start 98.000058 -39.67988)
					(mid 95.000064 -42.679874)
					(end 92.00007 -39.67988)
				)
			)
		)
	)
	(zone
		(net "P1V8_E_OUT")
		(layer "F.Cu")
		(hatch none 0.5)
		(connect_pads
			(clearance 0.5)
		)
		(min_thickness 0.25)
		(fill yes
			(thermal_gap 0.5)
			(thermal_bridge_width 0.5)
			(island_removal_mode 0)
		)
		(polygon
			(pts
				(xy 180.8353 -114.9985) (xy 180.6448 -115.189) (xy 180.6448 -115.6462) (xy 180.3654 -115.9256) (xy 178.6636 -115.9256)
				(xy 178.4096 -116.1796) (xy 178.4096 -117.9576) (xy 178.2826 -118.0846) (xy 177.6476 -118.0846)
				(xy 177.5206 -118.2116) (xy 177.5206 -124.3076) (xy 178.1556 -124.9426) (xy 181.3306 -124.9426)
				(xy 181.65445 -124.61875) (xy 181.65445 -115.79225) (xy 181.864 -115.5827) (xy 182.3974 -115.5827)
				(xy 182.4863 -115.4938) (xy 182.4863 -115.062) (xy 182.4228 -114.9985)
			)
		)
		(polygon
			(pts
				(xy 181.1782 -124.5108) (xy 180.975 -124.5108) (xy 180.975 -124.714) (xy 181.1782 -124.714)
			)
		)
		(polygon
			(pts
				(xy 181.1782 -123.9012) (xy 180.975 -123.9012) (xy 180.975 -124.1044) (xy 181.1782 -124.1044)
			)
		)
		(polygon
			(pts
				(xy 181.5465 -115.46713) (xy 181.3433 -115.46713) (xy 181.3433 -115.67033) (xy 181.5465 -115.67033)
			)
		)
	)
	(zone
		(net "P12V_SYBY_VDD_U6")
		(layer "F.Cu")
		(hatch none 0.5)
		(connect_pads
			(clearance 0.5)
		)
		(min_thickness 0.25)
		(fill yes
			(thermal_gap 0.5)
			(thermal_bridge_width 0.5)
			(island_removal_mode 0)
		)
		(polygon
			(pts
				(xy 161.790634 -78.74) (xy 161.41954 -79.111094) (xy 161.41954 -87.84971) (xy 160.751012 -88.518492)
				(xy 160.751012 -94.374716) (xy 161.583624 -95.207328) (xy 166.362888 -95.207328) (xy 166.777416 -94.7928)
				(xy 168.630854 -94.7928) (xy 168.783 -94.944946) (xy 170.695874 -94.944946) (xy 170.772074 -94.868746)
				(xy 170.772074 -94.648274) (xy 170.7388 -94.615) (xy 169.629328 -94.615) (xy 169.349674 -94.335346)
				(xy 166.572946 -94.335346) (xy 165.9382 -93.7006) (xy 163.1442 -93.7006) (xy 162.941 -93.4974) (xy 162.941 -91.821)
				(xy 163.195 -91.567) (xy 164.9476 -91.567) (xy 165.184074 -91.330526) (xy 165.184074 -78.976474)
				(xy 164.9476 -78.74)
			)
		)
		(polygon
			(pts
				(xy 166.0652 -94.2086) (xy 165.862 -94.2086) (xy 165.862 -94.4118) (xy 166.0652 -94.4118)
			)
		)
		(polygon
			(pts
				(xy 165.4556 -94.2086) (xy 165.2524 -94.2086) (xy 165.2524 -94.4118) (xy 165.4556 -94.4118)
			)
		)
	)
	(zone
		(layer "F.Cu")
		(hatch none 0.5)
		(connect_pads
			(clearance 0)
		)
		(min_thickness 0.25)
		(keepout
			(tracks allowed)
			(vias allowed)
			(pads allowed)
			(copperpour allowed)
			(footprints not_allowed)
		)
		(placement
			(enabled no)
			(sheetname "")
		)
		(fill
			(thermal_gap 0.5)
			(thermal_bridge_width 0.5)
			(island_removal_mode 0)
		)
		(polygon
			(pts
				(arc
					(start 148.500084 -29.500068)
					(mid 151.500078 -26.500074)
					(end 154.500072 -29.500068)
				)
				(arc
					(start 154.500072 -29.500068)
					(mid 151.500078 -32.500062)
					(end 148.500084 -29.500068)
				)
			)
		)
	)
	(zone
		(net "P0V9_VSW")
		(layer "F.Cu")
		(hatch none 0.5)
		(connect_pads
			(clearance 0.5)
		)
		(min_thickness 0.25)
		(fill yes
			(thermal_gap 0.5)
			(thermal_bridge_width 0.5)
			(island_removal_mode 0)
		)
		(polygon
			(pts
				(xy 55.1688 -43.942) (xy 54.5211 -44.5897) (xy 54.5211 -45.0469) (xy 54.229 -45.339) (xy 52.4256 -45.339)
				(xy 52.1716 -45.593) (xy 52.1716 -50.7492) (xy 52.5653 -51.1429) (xy 54.3941 -51.1429) (xy 55.1942 -50.3428)
				(xy 58.3184 -50.3428) (xy 59.0296 -49.6316) (xy 59.0296 -44.3738) (xy 58.5978 -43.942)
			)
		)
	)
	(zone
		(layer "F.Cu")
		(hatch none 0.5)
		(connect_pads
			(clearance 0)
		)
		(min_thickness 0.25)
		(keepout
			(tracks not_allowed)
			(vias allowed)
			(pads allowed)
			(copperpour not_allowed)
			(footprints allowed)
		)
		(placement
			(enabled no)
			(sheetname "")
		)
		(fill
			(thermal_gap 0.5)
			(thermal_bridge_width 0.5)
			(island_removal_mode 0)
		)
		(polygon
			(pts
				(arc
					(start 129.00025 -71.64197)
					(mid 128.893876 -71.658053)
					(end 128.79705 -71.704962)
				)
				(arc
					(start 128.881886 -71.789798)
					(mid 129.170556 -72.17067)
					(end 128.789684 -71.882)
				)
				(arc
					(start 128.704848 -71.797164)
					(mid 128.682985 -72.166853)
					(end 128.999996 -72.35825)
				)
				(arc
					(start 129.999994 -72.35825)
					(mid 130.358134 -72.00011)
					(end 129.999994 -71.64197)
				)
				(xy 129.734056 -71.64197)
				(arc
					(start 129.881884 -71.789798)
					(mid 130.170554 -72.17067)
					(end 129.789682 -71.882)
				)
				(xy 129.549652 -71.64197)
			)
		)
	)
	(zone
		(layer "F.Cu")
		(hatch none 0.5)
		(connect_pads
			(clearance 0)
		)
		(min_thickness 0.25)
		(keepout
			(tracks not_allowed)
			(vias allowed)
			(pads allowed)
			(copperpour not_allowed)
			(footprints allowed)
		)
		(placement
			(enabled no)
			(sheetname "")
		)
		(fill
			(thermal_gap 0.5)
			(thermal_bridge_width 0.5)
			(island_removal_mode 0)
		)
		(polygon
			(pts
				(arc
					(start 120.358154 -55.000144)
					(mid 120.000014 -54.642004)
					(end 119.641874 -55.000144)
				)
				(xy 119.641874 -55.266082)
				(arc
					(start 119.789702 -55.118254)
					(mid 120.170574 -54.829584)
					(end 119.881904 -55.210456)
				)
				(xy 119.641874 -55.450486)
				(arc
					(start 119.641874 -55.999888)
					(mid 119.657957 -56.106262)
					(end 119.704866 -56.203088)
				)
				(arc
					(start 119.789702 -56.118252)
					(mid 120.170574 -55.829582)
					(end 119.881904 -56.210454)
				)
				(arc
					(start 119.797068 -56.29529)
					(mid 120.166757 -56.317153)
					(end 120.358154 -56.000142)
				)
			)
		)
	)
	(zone
		(layer "F.Cu")
		(hatch none 0.5)
		(connect_pads
			(clearance 0)
		)
		(min_thickness 0.25)
		(keepout
			(tracks not_allowed)
			(vias allowed)
			(pads allowed)
			(copperpour not_allowed)
			(footprints allowed)
		)
		(placement
			(enabled no)
			(sheetname "")
		)
		(fill
			(thermal_gap 0.5)
			(thermal_bridge_width 0.5)
			(island_removal_mode 0)
		)
		(polygon
			(pts
				(arc
					(start 126.000256 -74.641964)
					(mid 125.893882 -74.658047)
					(end 125.797056 -74.704956)
				)
				(arc
					(start 125.881892 -74.789792)
					(mid 126.170562 -75.170664)
					(end 125.78969 -74.881994)
				)
				(arc
					(start 125.704854 -74.797158)
					(mid 125.682991 -75.166847)
					(end 126.000002 -75.358244)
				)
				(arc
					(start 127 -75.358244)
					(mid 127.35814 -75.000104)
					(end 127 -74.641964)
				)
				(xy 126.734062 -74.641964)
				(arc
					(start 126.88189 -74.789792)
					(mid 127.17056 -75.170664)
					(end 126.789688 -74.881994)
				)
				(xy 126.549658 -74.641964)
			)
		)
	)
	(zone
		(layer "F.Cu")
		(hatch none 0.5)
		(connect_pads
			(clearance 0)
		)
		(min_thickness 0.25)
		(keepout
			(tracks allowed)
			(vias allowed)
			(pads allowed)
			(copperpour allowed)
			(footprints allowed)
		)
		(placement
			(enabled no)
			(sheetname "")
		)
		(fill
			(thermal_gap 0.5)
			(thermal_bridge_width 0.5)
			(island_removal_mode 0)
		)
		(polygon
			(pts
				(xy 127.762 -44.6278) (xy 127.762 -44.2468) (xy 128.778 -44.2468) (xy 128.778 -44.6278)
			)
		)
	)
	(zone
		(layer "F.Cu")
		(hatch none 0.5)
		(connect_pads
			(clearance 0)
		)
		(min_thickness 0.25)
		(keepout
			(tracks not_allowed)
			(vias allowed)
			(pads allowed)
			(copperpour not_allowed)
			(footprints allowed)
		)
		(placement
			(enabled no)
			(sheetname "")
		)
		(fill
			(thermal_gap 0.5)
			(thermal_bridge_width 0.5)
			(island_removal_mode 0)
		)
		(polygon
			(pts
				(arc
					(start 165.399974 -34.016442)
					(mid 165.016434 -34.399982)
					(end 165.399974 -34.783522)
				)
				(xy 165.677596 -34.783522)
				(arc
					(start 165.52799 -34.633916)
					(mid 165.211409 -34.211417)
					(end 165.633908 -34.527998)
				)
				(xy 165.874954 -34.769044) (xy 165.874954 -34.783522)
				(arc
					(start 166.199566 -34.783522)
					(mid 166.311042 -34.767119)
					(end 166.412926 -34.719006)
				)
				(arc
					(start 166.327836 -34.633916)
					(mid 166.011255 -34.211417)
					(end 166.433754 -34.527998)
				)
				(arc
					(start 166.518844 -34.613088)
					(mid 166.538161 -34.219107)
					(end 166.19982 -34.016442)
				)
				(xy 166.0144 -34.016442) (xy 165.867842 -34.163) (xy 165.735 -34.163) (xy 165.588442 -34.016442)
			)
		)
	)
	(zone
		(layer "F.Cu")
		(hatch none 0.5)
		(connect_pads
			(clearance 0)
		)
		(min_thickness 0.25)
		(keepout
			(tracks not_allowed)
			(vias allowed)
			(pads allowed)
			(copperpour not_allowed)
			(footprints allowed)
		)
		(placement
			(enabled no)
			(sheetname "")
		)
		(fill
			(thermal_gap 0.5)
			(thermal_bridge_width 0.5)
			(island_removal_mode 0)
		)
		(polygon
			(pts
				(arc
					(start 138.80465 -62.590426)
					(mid 138.34999 -63.045086)
					(end 138.80465 -63.499746)
				)
				(arc
					(start 139.947396 -63.499746)
					(mid 140.40231 -63.045213)
					(end 139.94765 -62.590426)
				)
				(xy 139.65428 -62.590426)
				(arc
					(start 139.65428 -62.918848)
					(mid 139.658234 -62.938346)
					(end 139.669266 -62.954916)
				)
				(arc
					(start 139.670282 -62.955932)
					(mid 139.680402 -62.96356)
					(end 139.692126 -62.968378)
				)
				(arc
					(start 139.692126 -62.968378)
					(mid 140.214438 -63.046011)
					(end 139.691618 -63.120016)
				)
				(xy 139.674092 -63.120016)
				(arc
					(start 139.671044 -63.117222)
					(mid 139.628379 -63.104756)
					(end 139.58951 -63.083186)
				)
				(xy 139.5857 -63.083186) (xy 139.564618 -63.062104) (xy 139.563602 -63.061088) (xy 139.563094 -63.060834)
				(xy 139.541504 -63.03899)
				(arc
					(start 139.541504 -63.034926)
					(mid 139.519912 -62.995804)
					(end 139.507468 -62.952884)
				)
				(xy 139.50442 -62.949836) (xy 139.50442 -62.590426) (xy 139.24788 -62.590426) (xy 139.24788 -62.950852)
				(arc
					(start 139.245086 -62.9539)
					(mid 139.225547 -63.011786)
					(end 139.18946 -63.061088)
				)
				(arc
					(start 139.18946 -63.061342)
					(mid 139.13982 -63.09766)
					(end 139.08151 -63.117222)
				)
				(xy 139.078462 -63.120016)
				(arc
					(start 139.060682 -63.120016)
					(mid 138.53788 -63.045889)
					(end 139.060174 -62.968632)
				)
				(arc
					(start 139.060174 -62.968632)
					(mid 139.072652 -62.963475)
					(end 139.083288 -62.95517)
				)
				(arc
					(start 139.083288 -62.95517)
					(mid 139.094194 -62.938987)
					(end 139.09802 -62.919864)
				)
				(xy 139.09802 -62.590426)
			)
		)
	)
	(zone
		(layer "F.Cu")
		(hatch none 0.5)
		(connect_pads
			(clearance 0)
		)
		(min_thickness 0.25)
		(keepout
			(tracks not_allowed)
			(vias allowed)
			(pads allowed)
			(copperpour not_allowed)
			(footprints allowed)
		)
		(placement
			(enabled no)
			(sheetname "")
		)
		(fill
			(thermal_gap 0.5)
			(thermal_bridge_width 0.5)
			(island_removal_mode 0)
		)
		(polygon
			(pts
				(arc
					(start 130.000248 -68.641976)
					(mid 129.893874 -68.658059)
					(end 129.797048 -68.704968)
				)
				(arc
					(start 129.881884 -68.789804)
					(mid 130.170554 -69.170676)
					(end 129.789682 -68.882006)
				)
				(arc
					(start 129.704846 -68.79717)
					(mid 129.682983 -69.166859)
					(end 129.999994 -69.358256)
				)
				(xy 130.310128 -69.358256) (xy 130.402584 -69.2658) (xy 130.601212 -69.2658) (xy 130.693668 -69.358256)
				(arc
					(start 130.999992 -69.358256)
					(mid 131.358132 -69.000116)
					(end 130.999992 -68.641976)
				)
				(xy 130.734054 -68.641976)
				(arc
					(start 130.881882 -68.789804)
					(mid 131.170552 -69.170676)
					(end 130.78968 -68.882006)
				)
				(xy 130.54965 -68.641976)
			)
		)
	)
	(zone
		(layer "F.Cu")
		(hatch none 0.5)
		(connect_pads
			(clearance 0)
		)
		(min_thickness 0.25)
		(keepout
			(tracks allowed)
			(vias allowed)
			(pads allowed)
			(copperpour allowed)
			(footprints allowed)
		)
		(placement
			(enabled no)
			(sheetname "")
		)
		(fill
			(thermal_gap 0.5)
			(thermal_bridge_width 0.5)
			(island_removal_mode 0)
		)
		(polygon
			(pts
				(xy 63.49619 -80.01762) (xy 63.49619 -78.612238) (xy 64.468756 -78.612238) (xy 64.468756 -80.01762)
			)
		)
	)
	(zone
		(layer "F.Cu")
		(hatch none 0.5)
		(connect_pads
			(clearance 0)
		)
		(min_thickness 0.25)
		(keepout
			(tracks allowed)
			(vias allowed)
			(pads allowed)
			(copperpour allowed)
			(footprints allowed)
		)
		(placement
			(enabled no)
			(sheetname "")
		)
		(fill
			(thermal_gap 0.5)
			(thermal_bridge_width 0.5)
			(island_removal_mode 0)
		)
		(polygon
			(pts
				(xy 155.3718 -118.5164) (xy 155.3718 -116.4844) (xy 157.2768 -116.4844) (xy 157.2768 -118.5164)
			)
		)
	)
	(zone
		(layer "F.Cu")
		(hatch none 0.5)
		(connect_pads
			(clearance 0)
		)
		(min_thickness 0.25)
		(keepout
			(tracks not_allowed)
			(vias allowed)
			(pads allowed)
			(copperpour not_allowed)
			(footprints allowed)
		)
		(placement
			(enabled no)
			(sheetname "")
		)
		(fill
			(thermal_gap 0.5)
			(thermal_bridge_width 0.5)
			(island_removal_mode 0)
		)
		(polygon
			(pts
				(arc
					(start 126.000256 -56.642)
					(mid 125.683093 -56.833308)
					(end 125.704854 -57.203086)
				)
				(arc
					(start 125.78969 -57.11825)
					(mid 126.170562 -56.82958)
					(end 125.881892 -57.210452)
				)
				(arc
					(start 125.797056 -57.295288)
					(mid 125.893753 -57.342173)
					(end 126.000002 -57.35828)
				)
				(xy 126.549658 -57.35828)
				(arc
					(start 126.789688 -57.11825)
					(mid 127.17056 -56.82958)
					(end 126.88189 -57.210452)
				)
				(xy 126.734062 -57.35828)
				(arc
					(start 127 -57.35828)
					(mid 127.35814 -57.00014)
					(end 127 -56.642)
				)
			)
		)
	)
	(zone
		(net "MB0_12V_CTRL_GATE1")
		(layer "F.Cu")
		(hatch none 0.5)
		(connect_pads
			(clearance 0.5)
		)
		(min_thickness 0.25)
		(fill yes
			(thermal_gap 0.5)
			(thermal_bridge_width 0.5)
			(island_removal_mode 0)
		)
		(polygon
			(pts
				(xy 6.667246 -35.379406) (xy 6.41985 -35.626802) (xy 6.41985 -38.927532) (xy 6.62559 -39.133272)
				(xy 8.999728 -39.133272) (xy 9.070848 -39.062152) (xy 9.070848 -35.384232) (xy 9.066022 -35.379406)
			)
		)
	)
	(zone
		(layer "F.Cu")
		(hatch none 0.5)
		(connect_pads
			(clearance 0)
		)
		(min_thickness 0.25)
		(keepout
			(tracks not_allowed)
			(vias allowed)
			(pads allowed)
			(copperpour not_allowed)
			(footprints allowed)
		)
		(placement
			(enabled no)
			(sheetname "")
		)
		(fill
			(thermal_gap 0.5)
			(thermal_bridge_width 0.5)
			(island_removal_mode 0)
		)
		(polygon
			(pts
				(arc
					(start 139.446 -58.44794)
					(mid 138.99134 -58.9026)
					(end 139.446 -59.35726)
				)
				(arc
					(start 140.588746 -59.35726)
					(mid 141.04366 -58.902727)
					(end 140.589 -58.44794)
				)
				(xy 140.29563 -58.44794)
				(arc
					(start 140.29563 -58.776362)
					(mid 140.299584 -58.79586)
					(end 140.310616 -58.81243)
				)
				(arc
					(start 140.311632 -58.813446)
					(mid 140.321752 -58.821074)
					(end 140.333476 -58.825892)
				)
				(arc
					(start 140.333476 -58.825892)
					(mid 140.855788 -58.903525)
					(end 140.332968 -58.97753)
				)
				(xy 140.315442 -58.97753)
				(arc
					(start 140.312394 -58.974736)
					(mid 140.269729 -58.96227)
					(end 140.23086 -58.9407)
				)
				(xy 140.22705 -58.9407) (xy 140.205968 -58.919618) (xy 140.204952 -58.918602) (xy 140.204444 -58.918348)
				(xy 140.182854 -58.896504)
				(arc
					(start 140.182854 -58.89244)
					(mid 140.161262 -58.853318)
					(end 140.148818 -58.810398)
				)
				(xy 140.14577 -58.80735) (xy 140.14577 -58.44794) (xy 139.88923 -58.44794) (xy 139.88923 -58.808366)
				(arc
					(start 139.886436 -58.811414)
					(mid 139.866897 -58.8693)
					(end 139.83081 -58.918602)
				)
				(arc
					(start 139.83081 -58.918856)
					(mid 139.78117 -58.955174)
					(end 139.72286 -58.974736)
				)
				(xy 139.719812 -58.97753)
				(arc
					(start 139.702032 -58.97753)
					(mid 139.17923 -58.903403)
					(end 139.701524 -58.826146)
				)
				(arc
					(start 139.701524 -58.826146)
					(mid 139.714002 -58.820989)
					(end 139.724638 -58.812684)
				)
				(arc
					(start 139.724638 -58.812684)
					(mid 139.735544 -58.796501)
					(end 139.73937 -58.777378)
				)
				(xy 139.73937 -58.44794)
			)
		)
	)
	(zone
		(net "AGND_CURRENT_MON")
		(layer "F.Cu")
		(hatch none 0.5)
		(connect_pads
			(clearance 0.5)
		)
		(min_thickness 0.25)
		(fill yes
			(thermal_gap 0.5)
			(thermal_bridge_width 0.5)
			(island_removal_mode 0)
		)
		(polygon
			(pts
				(xy 12.4714 -51.6509) (xy 12.3444 -51.7779) (xy 12.3444 -54.7624) (xy 12.446 -54.864) (xy 15.3543 -54.864)
				(xy 15.4813 -54.737) (xy 15.4813 -51.8414) (xy 15.2908 -51.6509)
			)
		)
	)
	(zone
		(layer "F.Cu")
		(hatch none 0.5)
		(connect_pads
			(clearance 0)
		)
		(min_thickness 0.25)
		(keepout
			(tracks not_allowed)
			(vias allowed)
			(pads allowed)
			(copperpour not_allowed)
			(footprints allowed)
		)
		(placement
			(enabled no)
			(sheetname "")
		)
		(fill
			(thermal_gap 0.5)
			(thermal_bridge_width 0.5)
			(island_removal_mode 0)
		)
		(polygon
			(pts
				(arc
					(start 126.000256 -59.641994)
					(mid 125.683093 -59.833302)
					(end 125.704854 -60.20308)
				)
				(arc
					(start 125.78969 -60.118244)
					(mid 126.170562 -59.829574)
					(end 125.881892 -60.210446)
				)
				(arc
					(start 125.797056 -60.295282)
					(mid 125.893753 -60.342167)
					(end 126.000002 -60.358274)
				)
				(xy 126.549658 -60.358274)
				(arc
					(start 126.789688 -60.118244)
					(mid 127.17056 -59.829574)
					(end 126.88189 -60.210446)
				)
				(xy 126.734062 -60.358274)
				(arc
					(start 127 -60.358274)
					(mid 127.35814 -60.000134)
					(end 127 -59.641994)
				)
			)
		)
	)
	(zone
		(net "P1V8_E")
		(layer "F.Cu")
		(hatch none 0.5)
		(connect_pads
			(clearance 0.5)
		)
		(min_thickness 0.25)
		(fill yes
			(thermal_gap 0.5)
			(thermal_bridge_width 0.5)
			(island_removal_mode 0)
		)
		(polygon
			(pts
				(xy 174.371 -122.047) (xy 174.117 -122.301) (xy 174.117 -124.2822) (xy 174.3202 -124.4854) (xy 176.9872 -124.4854)
				(xy 177.1904 -124.2822) (xy 177.1904 -122.1232) (xy 177.1142 -122.047)
			)
		)
	)
	(zone
		(layer "F.Cu")
		(hatch none 0.5)
		(connect_pads
			(clearance 0)
		)
		(min_thickness 0.25)
		(keepout
			(tracks allowed)
			(vias allowed)
			(pads allowed)
			(copperpour allowed)
			(footprints allowed)
		)
		(placement
			(enabled no)
			(sheetname "")
		)
		(fill
			(thermal_gap 0.5)
			(thermal_bridge_width 0.5)
			(island_removal_mode 0)
		)
		(polygon
			(pts
				(xy 146.308318 -46.312328) (xy 146.10207 -47.177198) (xy 145.731484 -47.088806) (xy 145.937732 -46.223936)
			)
		)
	)
	(zone
		(net "P3V3")
		(layer "F.Cu")
		(hatch none 0.5)
		(connect_pads
			(clearance 0.5)
		)
		(min_thickness 0.25)
		(fill yes
			(thermal_gap 0.5)
			(thermal_bridge_width 0.5)
			(island_removal_mode 0)
		)
		(polygon
			(pts
				(xy 190.476886 -73.433432) (xy 190.3857 -73.524618) (xy 190.3857 -75.68438) (xy 190.44158 -75.74026)
				(xy 190.54826 -75.74026) (xy 190.63843 -75.83043) (xy 193.15557 -75.83043) (xy 193.54546 -76.22032)
				(xy 193.54546 -76.62418) (xy 193.60134 -76.68006) (xy 195.06438 -76.68006) (xy 195.17868 -76.56576)
				(xy 195.17868 -75.2856) (xy 195.1609 -75.2856) (xy 193.308732 -73.433432)
			)
		)
		(polygon
			(pts
				(xy 192.808352 -75.174094) (xy 192.605152 -75.174094) (xy 192.605152 -75.377294) (xy 192.808352 -75.377294)
			)
		)
		(polygon
			(pts
				(xy 192.198752 -75.174094) (xy 191.995552 -75.174094) (xy 191.995552 -75.377294) (xy 192.198752 -75.377294)
			)
		)
		(polygon
			(pts
				(xy 191.05118 -75.08748) (xy 190.84798 -75.08748) (xy 190.84798 -75.29068) (xy 191.05118 -75.29068)
			)
		)
	)
	(zone
		(net "GND")
		(layer "F.Cu")
		(hatch none 0.5)
		(connect_pads
			(clearance 0.5)
		)
		(min_thickness 0.25)
		(fill yes
			(thermal_gap 0.5)
			(thermal_bridge_width 0.5)
			(island_removal_mode 0)
		)
		(polygon
			(pts
				(xy 72.923654 -62.3316) (xy 72.263 -62.992254) (xy 72.263 -64.982852) (xy 72.558148 -65.278) (xy 75.48245 -65.278)
				(xy 75.87107 -64.88938) (xy 75.87107 -62.63767) (xy 75.565 -62.3316)
			)
		)
		(polygon
			(pts
				(xy 74.9808 -63.3095) (xy 74.7776 -63.3095) (xy 74.7776 -63.5127) (xy 74.9808 -63.5127)
			)
		)
		(polygon
			(pts
				(xy 74.9808 -62.4459) (xy 74.7776 -62.4459) (xy 74.7776 -62.6491) (xy 74.9808 -62.6491)
			)
		)
	)
	(zone
		(net "P1V8_C")
		(layer "F.Cu")
		(hatch none 0.5)
		(connect_pads
			(clearance 0.5)
		)
		(min_thickness 0.25)
		(fill yes
			(thermal_gap 0.5)
			(thermal_bridge_width 0.5)
			(island_removal_mode 0)
		)
		(polygon
			(pts
				(xy 201.422 -73.66) (xy 201.17435 -73.90765) (xy 201.17435 -74.625962) (xy 201.351388 -74.803) (xy 204.187552 -74.803)
				(xy 204.319632 -74.67092) (xy 204.319632 -73.786238) (xy 204.193394 -73.66)
			)
		)
		(polygon
			(pts
				(xy 202.88377 -74.134218) (xy 202.68057 -74.134218) (xy 202.68057 -74.337418) (xy 202.88377 -74.337418)
			)
		)
		(polygon
			(pts
				(xy 202.27417 -74.134218) (xy 202.07097 -74.134218) (xy 202.07097 -74.337418) (xy 202.27417 -74.337418)
			)
		)
		(polygon
			(pts
				(xy 204.072236 -74.128884) (xy 203.869036 -74.128884) (xy 203.869036 -74.332084) (xy 204.072236 -74.332084)
			)
		)
		(polygon
			(pts
				(xy 203.513436 -74.128884) (xy 203.310236 -74.128884) (xy 203.310236 -74.332084) (xy 203.513436 -74.332084)
			)
		)
	)
	(zone
		(net "GND")
		(layer "F.Cu")
		(hatch none 0.5)
		(connect_pads
			(clearance 0.5)
		)
		(min_thickness 0.25)
		(fill yes
			(thermal_gap 0.5)
			(thermal_bridge_width 0.5)
			(island_removal_mode 0)
		)
		(polygon
			(pts
				(xy 202.694032 -68.468748) (xy 202.375262 -68.787518) (xy 202.375262 -71.232268) (xy 202.047856 -71.559674)
				(xy 201.353674 -71.559674) (xy 201.239882 -71.673466) (xy 201.239882 -72.192642) (xy 201.335132 -72.287892)
				(xy 201.588624 -72.287892) (xy 201.591926 -72.28459) (xy 204.62494 -72.28459) (xy 204.915008 -71.994522)
				(xy 204.915008 -68.522596) (xy 204.86116 -68.468748)
			)
		)
		(polygon
			(pts
				(xy 204.343 -68.9864) (xy 204.1398 -68.9864) (xy 204.1398 -69.1896) (xy 204.343 -69.1896)
			)
		)
	)
	(zone
		(layer "F.Cu")
		(hatch none 0.5)
		(connect_pads
			(clearance 0)
		)
		(min_thickness 0.25)
		(keepout
			(tracks not_allowed)
			(vias allowed)
			(pads allowed)
			(copperpour not_allowed)
			(footprints allowed)
		)
		(placement
			(enabled no)
			(sheetname "")
		)
		(fill
			(thermal_gap 0.5)
			(thermal_bridge_width 0.5)
			(island_removal_mode 0)
		)
		(polygon
			(pts
				(arc
					(start 106.358182 -55.000144)
					(mid 106.000042 -54.642004)
					(end 105.641902 -55.000144)
				)
				(arc
					(start 105.641902 -55.999888)
					(mid 105.83321 -56.317051)
					(end 106.202988 -56.29529)
				)
				(arc
					(start 106.118152 -56.210454)
					(mid 105.829482 -55.829582)
					(end 106.210354 -56.118252)
				)
				(arc
					(start 106.29519 -56.203088)
					(mid 106.342075 -56.106391)
					(end 106.358182 -56.000142)
				)
				(xy 106.358182 -55.450486)
				(arc
					(start 106.118152 -55.210456)
					(mid 105.829482 -54.829584)
					(end 106.210354 -55.118254)
				)
				(xy 106.358182 -55.266082)
			)
		)
	)
	(zone
		(net "P3V3")
		(layer "F.Cu")
		(hatch none 0.5)
		(connect_pads
			(clearance 0.5)
		)
		(min_thickness 0.25)
		(fill yes
			(thermal_gap 0.5)
			(thermal_bridge_width 0.5)
			(island_removal_mode 0)
		)
		(polygon
			(pts
				(xy 52.7558 -123.6472) (xy 52.4256 -123.9774) (xy 52.4256 -127.9906) (xy 53.213 -128.778) (xy 62.738 -128.778)
				(xy 63.7032 -127.8128) (xy 63.7032 -123.7742) (xy 63.5762 -123.6472)
			)
		)
	)
	(zone
		(layer "F.Cu")
		(hatch none 0.5)
		(connect_pads
			(clearance 0)
		)
		(min_thickness 0.25)
		(keepout
			(tracks allowed)
			(vias allowed)
			(pads allowed)
			(copperpour allowed)
			(footprints allowed)
		)
		(placement
			(enabled no)
			(sheetname "")
		)
		(fill
			(thermal_gap 0.5)
			(thermal_bridge_width 0.5)
			(island_removal_mode 0)
		)
		(polygon
			(pts
				(xy 142.329916 -64.514984) (xy 142.329916 -63.651384) (xy 142.660116 -63.651384) (xy 142.660116 -64.514984)
			)
		)
	)
	(zone
		(layer "F.Cu")
		(hatch none 0.5)
		(connect_pads
			(clearance 0)
		)
		(min_thickness 0.25)
		(keepout
			(tracks not_allowed)
			(vias allowed)
			(pads allowed)
			(copperpour not_allowed)
			(footprints allowed)
		)
		(placement
			(enabled no)
			(sheetname "")
		)
		(fill
			(thermal_gap 0.5)
			(thermal_bridge_width 0.5)
			(island_removal_mode 0)
		)
		(polygon
			(pts
				(arc
					(start 123.358148 -55.000144)
					(mid 123.000008 -54.642004)
					(end 122.641868 -55.000144)
				)
				(xy 122.641868 -55.266082)
				(arc
					(start 122.789696 -55.118254)
					(mid 123.170568 -54.829584)
					(end 122.881898 -55.210456)
				)
				(xy 122.641868 -55.450486)
				(arc
					(start 122.641868 -55.999888)
					(mid 122.657951 -56.106262)
					(end 122.70486 -56.203088)
				)
				(arc
					(start 122.789696 -56.118252)
					(mid 123.170568 -55.829582)
					(end 122.881898 -56.210454)
				)
				(arc
					(start 122.797062 -56.29529)
					(mid 123.166751 -56.317153)
					(end 123.358148 -56.000142)
				)
			)
		)
	)
	(zone
		(layer "F.Cu")
		(hatch none 0.5)
		(connect_pads
			(clearance 0)
		)
		(min_thickness 0.25)
		(keepout
			(tracks not_allowed)
			(vias allowed)
			(pads allowed)
			(copperpour not_allowed)
			(footprints allowed)
		)
		(placement
			(enabled no)
			(sheetname "")
		)
		(fill
			(thermal_gap 0.5)
			(thermal_bridge_width 0.5)
			(island_removal_mode 0)
		)
		(polygon
			(pts
				(arc
					(start 112.35817 -51.000152)
					(mid 112.00003 -50.642012)
					(end 111.64189 -51.000152)
				)
				(xy 111.64189 -51.31689) (xy 111.7346 -51.4096) (xy 111.7346 -51.59629) (xy 111.64189 -51.689)
				(arc
					(start 111.64189 -51.999896)
					(mid 111.833198 -52.317059)
					(end 112.202976 -52.295298)
				)
				(arc
					(start 112.11814 -52.210462)
					(mid 111.82947 -51.82959)
					(end 112.210342 -52.11826)
				)
				(arc
					(start 112.295178 -52.203096)
					(mid 112.342063 -52.106399)
					(end 112.35817 -52.00015)
				)
				(xy 112.35817 -51.450494)
				(arc
					(start 112.11814 -51.210464)
					(mid 111.82947 -50.829592)
					(end 112.210342 -51.118262)
				)
				(xy 112.35817 -51.26609)
			)
		)
	)
	(zone
		(layer "F.Cu")
		(hatch none 0.5)
		(connect_pads
			(clearance 0)
		)
		(min_thickness 0.25)
		(keepout
			(tracks not_allowed)
			(vias allowed)
			(pads allowed)
			(copperpour not_allowed)
			(footprints allowed)
		)
		(placement
			(enabled no)
			(sheetname "")
		)
		(fill
			(thermal_gap 0.5)
			(thermal_bridge_width 0.5)
			(island_removal_mode 0)
		)
		(polygon
			(pts
				(arc
					(start 126.000256 -53.642006)
					(mid 125.683093 -53.833314)
					(end 125.704854 -54.203092)
				)
				(arc
					(start 125.78969 -54.118256)
					(mid 126.170562 -53.829586)
					(end 125.881892 -54.210458)
				)
				(arc
					(start 125.797056 -54.295294)
					(mid 125.893753 -54.342179)
					(end 126.000002 -54.358286)
				)
				(xy 126.549658 -54.358286)
				(arc
					(start 126.789688 -54.118256)
					(mid 127.17056 -53.829586)
					(end 126.88189 -54.210458)
				)
				(xy 126.734062 -54.358286)
				(arc
					(start 127 -54.358286)
					(mid 127.35814 -54.000146)
					(end 127 -53.642006)
				)
			)
		)
	)
	(zone
		(layer "F.Cu")
		(hatch none 0.5)
		(connect_pads
			(clearance 0)
		)
		(min_thickness 0.25)
		(keepout
			(tracks not_allowed)
			(vias allowed)
			(pads allowed)
			(copperpour not_allowed)
			(footprints allowed)
		)
		(placement
			(enabled no)
			(sheetname "")
		)
		(fill
			(thermal_gap 0.5)
			(thermal_bridge_width 0.5)
			(island_removal_mode 0)
		)
		(polygon
			(pts
				(arc
					(start 100.358194 -51.000152)
					(mid 100.000054 -50.642012)
					(end 99.641914 -51.000152)
				)
				(arc
					(start 99.641914 -51.999896)
					(mid 99.833222 -52.317059)
					(end 100.203 -52.295298)
				)
				(arc
					(start 100.118164 -52.210462)
					(mid 99.829494 -51.82959)
					(end 100.210366 -52.11826)
				)
				(arc
					(start 100.295202 -52.203096)
					(mid 100.342087 -52.106399)
					(end 100.358194 -52.00015)
				)
				(xy 100.358194 -51.450494)
				(arc
					(start 100.118164 -51.210464)
					(mid 99.829494 -50.829592)
					(end 100.210366 -51.118262)
				)
				(xy 100.358194 -51.26609)
			)
		)
	)
	(zone
		(layer "F.Cu")
		(hatch none 0.5)
		(connect_pads
			(clearance 0)
		)
		(min_thickness 0.25)
		(keepout
			(tracks not_allowed)
			(vias allowed)
			(pads allowed)
			(copperpour not_allowed)
			(footprints allowed)
		)
		(placement
			(enabled no)
			(sheetname "")
		)
		(fill
			(thermal_gap 0.5)
			(thermal_bridge_width 0.5)
			(island_removal_mode 0)
		)
		(polygon
			(pts
				(arc
					(start 109.358176 -55.000144)
					(mid 109.000036 -54.642004)
					(end 108.641896 -55.000144)
				)
				(arc
					(start 108.641896 -55.999888)
					(mid 108.833204 -56.317051)
					(end 109.202982 -56.29529)
				)
				(arc
					(start 109.118146 -56.210454)
					(mid 108.829476 -55.829582)
					(end 109.210348 -56.118252)
				)
				(arc
					(start 109.295184 -56.203088)
					(mid 109.342069 -56.106391)
					(end 109.358176 -56.000142)
				)
				(xy 109.358176 -55.450486)
				(arc
					(start 109.118146 -55.210456)
					(mid 108.829476 -54.829584)
					(end 109.210348 -55.118254)
				)
				(xy 109.358176 -55.266082)
			)
		)
	)
	(zone
		(layer "F.Cu")
		(hatch none 0.5)
		(connect_pads
			(clearance 0)
		)
		(min_thickness 0.25)
		(keepout
			(tracks not_allowed)
			(vias allowed)
			(pads allowed)
			(copperpour not_allowed)
			(footprints allowed)
		)
		(placement
			(enabled no)
			(sheetname "")
		)
		(fill
			(thermal_gap 0.5)
			(thermal_bridge_width 0.5)
			(island_removal_mode 0)
		)
		(polygon
			(pts
				(arc
					(start 173.758098 -30.39999)
					(mid 173.399831 -30.04185)
					(end 173.041818 -30.400244)
				)
				(xy 173.042072 -30.725872) (xy 173.0756 -30.7594) (xy 173.0756 -30.852872) (xy 173.042072 -30.8864)
				(arc
					(start 173.042072 -31.199836)
					(mid 173.225545 -31.512749)
					(end 173.588172 -31.50489)
				)
				(arc
					(start 173.502066 -31.418784)
					(mid 173.229623 -31.029501)
					(end 173.618906 -31.301944)
				)
				(arc
					(start 173.705012 -31.38805)
					(mid 173.74476 -31.297653)
					(end 173.758352 -31.199836)
				)
				(xy 173.758352 -30.95879) (xy 173.758352 -30.879542)
				(arc
					(start 173.498764 -30.620208)
					(mid 173.229285 -30.229317)
					(end 173.620176 -30.498796)
				)
				(xy 173.758098 -30.636972) (xy 173.758098 -30.498796)
			)
		)
	)
	(zone
		(layer "F.Cu")
		(hatch none 0.5)
		(connect_pads
			(clearance 0)
		)
		(min_thickness 0.25)
		(keepout
			(tracks not_allowed)
			(vias allowed)
			(pads allowed)
			(copperpour not_allowed)
			(footprints allowed)
		)
		(placement
			(enabled no)
			(sheetname "")
		)
		(fill
			(thermal_gap 0.5)
			(thermal_bridge_width 0.5)
			(island_removal_mode 0)
		)
		(polygon
			(pts
				(arc
					(start 195.49999 -50.500026)
					(mid 198.499984 -47.500032)
					(end 201.499978 -50.500026)
				)
				(arc
					(start 201.499978 -50.500026)
					(mid 198.499984 -53.50002)
					(end 195.49999 -50.500026)
				)
			)
		)
	)
	(zone
		(layer "F.Cu")
		(hatch none 0.5)
		(connect_pads
			(clearance 0)
		)
		(min_thickness 0.25)
		(keepout
			(tracks not_allowed)
			(vias allowed)
			(pads allowed)
			(copperpour not_allowed)
			(footprints allowed)
		)
		(placement
			(enabled no)
			(sheetname "")
		)
		(fill
			(thermal_gap 0.5)
			(thermal_bridge_width 0.5)
			(island_removal_mode 0)
		)
		(polygon
			(pts
				(arc
					(start 110.358174 -55.000144)
					(mid 110.000034 -54.642004)
					(end 109.641894 -55.000144)
				)
				(arc
					(start 109.641894 -55.999888)
					(mid 109.833202 -56.317051)
					(end 110.20298 -56.29529)
				)
				(arc
					(start 110.118144 -56.210454)
					(mid 109.829474 -55.829582)
					(end 110.210346 -56.118252)
				)
				(arc
					(start 110.295182 -56.203088)
					(mid 110.342067 -56.106391)
					(end 110.358174 -56.000142)
				)
				(xy 110.358174 -55.450486)
				(arc
					(start 110.118144 -55.210456)
					(mid 109.829474 -54.829584)
					(end 110.210346 -55.118254)
				)
				(xy 110.358174 -55.266082)
			)
		)
	)
	(zone
		(layer "F.Cu")
		(hatch none 0.5)
		(connect_pads
			(clearance 0)
		)
		(min_thickness 0.25)
		(keepout
			(tracks not_allowed)
			(vias allowed)
			(pads allowed)
			(copperpour not_allowed)
			(footprints allowed)
		)
		(placement
			(enabled no)
			(sheetname "")
		)
		(fill
			(thermal_gap 0.5)
			(thermal_bridge_width 0.5)
			(island_removal_mode 0)
		)
		(polygon
			(pts
				(arc
					(start 146.303238 -33.01746)
					(mid 146.39272 -33.092248)
					(end 146.42084 -33.20542)
				)
				(xy 146.42211 -33.207452) (xy 146.4183 -33.22574)
				(arc
					(start 146.415252 -33.239202)
					(mid 146.228516 -33.733326)
					(end 146.268948 -33.20669)
				)
				(arc
					(start 146.27098 -33.197038)
					(mid 146.264989 -33.170901)
					(end 146.243294 -33.155128)
				)
				(xy 146.237452 -33.153858) (xy 146.207734 -33.14827) (xy 146.207226 -33.147762) (xy 145.901664 -33.085024)
				(arc
					(start 145.839434 -33.377886)
					(mid 146.191732 -33.920176)
					(end 146.734022 -33.567878)
				)
				(xy 146.853148 -33.007554)
				(arc
					(start 146.969226 -32.460184)
					(mid 146.624662 -31.908815)
					(end 146.077178 -32.259778)
				)
				(xy 146.017488 -32.540702)
				(arc
					(start 146.312382 -32.601408)
					(mid 146.352319 -32.601121)
					(end 146.388582 -32.58439)
				)
				(arc
					(start 146.388582 -32.58439)
					(mid 146.585035 -32.095117)
					(end 146.543776 -32.620712)
				)
				(xy 146.537172 -32.652462)
				(arc
					(start 146.522186 -32.662114)
					(mid 146.429891 -32.732712)
					(end 146.31543 -32.752792)
				)
				(xy 146.312636 -32.75457) (xy 146.28241 -32.74822) (xy 145.986246 -32.68726) (xy 145.932906 -32.938466)
				(xy 146.266408 -33.007046) (xy 146.26971 -33.007554) (xy 146.30019 -33.013396)
			)
		)
	)
	(zone
		(layer "F.Cu")
		(hatch none 0.5)
		(connect_pads
			(clearance 0)
		)
		(min_thickness 0.25)
		(keepout
			(tracks not_allowed)
			(vias allowed)
			(pads allowed)
			(copperpour not_allowed)
			(footprints allowed)
		)
		(placement
			(enabled no)
			(sheetname "")
		)
		(fill
			(thermal_gap 0.5)
			(thermal_bridge_width 0.5)
			(island_removal_mode 0)
		)
		(polygon
			(pts
				(arc
					(start 126.000256 -58.641996)
					(mid 125.683093 -58.833304)
					(end 125.704854 -59.203082)
				)
				(arc
					(start 125.78969 -59.118246)
					(mid 126.170562 -58.829576)
					(end 125.881892 -59.210448)
				)
				(arc
					(start 125.797056 -59.295284)
					(mid 125.893753 -59.342169)
					(end 126.000002 -59.358276)
				)
				(xy 126.549658 -59.358276)
				(arc
					(start 126.789688 -59.118246)
					(mid 127.17056 -58.829576)
					(end 126.88189 -59.210448)
				)
				(xy 126.734062 -59.358276)
				(arc
					(start 127 -59.358276)
					(mid 127.35814 -59.000136)
					(end 127 -58.641996)
				)
			)
		)
	)
	(zone
		(layer "F.Cu")
		(hatch none 0.5)
		(connect_pads
			(clearance 0)
		)
		(min_thickness 0.25)
		(keepout
			(tracks not_allowed)
			(vias allowed)
			(pads allowed)
			(copperpour not_allowed)
			(footprints allowed)
		)
		(placement
			(enabled no)
			(sheetname "")
		)
		(fill
			(thermal_gap 0.5)
			(thermal_bridge_width 0.5)
			(island_removal_mode 0)
		)
		(polygon
			(pts
				(arc
					(start 149.814534 -35.21329)
					(mid 149.46997 -34.661921)
					(end 148.922486 -35.012884)
				)
				(xy 148.863558 -35.290506) (xy 149.032976 -35.32886)
				(arc
					(start 149.157944 -35.354514)
					(mid 149.197737 -35.35415)
					(end 149.23389 -35.337496)
				)
				(arc
					(start 149.23389 -35.337496)
					(mid 149.430343 -34.848223)
					(end 149.389084 -35.373818)
				)
				(xy 149.38248 -35.405568)
				(arc
					(start 149.367494 -35.41522)
					(mid 149.275199 -35.485818)
					(end 149.160738 -35.505898)
				)
				(xy 149.157944 -35.507676) (xy 149.031706 -35.481514) (xy 149.030944 -35.482022) (xy 149.00148 -35.475164)
				(xy 148.971762 -35.469068) (xy 148.971254 -35.46856) (xy 148.832316 -35.437318) (xy 148.778722 -35.688524)
				(xy 148.915374 -35.719004) (xy 148.91639 -35.718496) (xy 148.94052 -35.724592) (xy 148.962618 -35.724592)
				(xy 148.968714 -35.730688) (xy 149.111716 -35.760152) (xy 149.115018 -35.76066) (xy 149.145498 -35.766502)
				(arc
					(start 149.148546 -35.770566)
					(mid 149.238028 -35.845354)
					(end 149.266148 -35.958526)
				)
				(xy 149.267418 -35.960558) (xy 149.263608 -35.978846)
				(arc
					(start 149.26056 -35.992308)
					(mid 149.073824 -36.486432)
					(end 149.114256 -35.959796)
				)
				(arc
					(start 149.116288 -35.950144)
					(mid 149.110297 -35.924007)
					(end 149.088602 -35.908234)
				)
				(xy 149.08276 -35.906964) (xy 149.053042 -35.901376) (xy 149.052534 -35.900868) (xy 148.944838 -35.87877)
				(xy 148.943314 -35.879786) (xy 148.922232 -35.874452) (xy 148.900388 -35.874452) (xy 148.894292 -35.868356)
				(xy 148.886164 -35.866578) (xy 148.885656 -35.86607) (xy 148.747734 -35.835082)
				(arc
					(start 148.684742 -36.130992)
					(mid 149.03704 -36.673282)
					(end 149.57933 -36.320984)
				)
				(xy 149.698456 -35.76066)
			)
		)
	)
	(zone
		(layer "F.Cu")
		(hatch none 0.5)
		(connect_pads
			(clearance 0)
		)
		(min_thickness 0.25)
		(keepout
			(tracks not_allowed)
			(vias allowed)
			(pads allowed)
			(copperpour not_allowed)
			(footprints allowed)
		)
		(placement
			(enabled no)
			(sheetname "")
		)
		(fill
			(thermal_gap 0.5)
			(thermal_bridge_width 0.5)
			(island_removal_mode 0)
		)
		(polygon
			(pts
				(arc
					(start 168.157906 -30.39999)
					(mid 167.799639 -30.04185)
					(end 167.441626 -30.400244)
				)
				(xy 167.441626 -30.607) (xy 167.5638 -30.729174) (xy 167.5638 -30.861) (xy 167.44188 -30.98292)
				(arc
					(start 167.44188 -31.199582)
					(mid 167.623909 -31.511684)
					(end 167.985186 -31.506414)
				)
				(arc
					(start 167.898826 -31.420054)
					(mid 167.629347 -31.029163)
					(end 168.020238 -31.298642)
				)
				(arc
					(start 168.106598 -31.385002)
					(mid 168.145076 -31.295821)
					(end 168.15816 -31.199582)
				)
				(xy 168.15816 -30.958536) (xy 168.15816 -30.879542)
				(arc
					(start 167.898572 -30.620208)
					(mid 167.629093 -30.229317)
					(end 168.019984 -30.498796)
				)
				(xy 168.157906 -30.636972) (xy 168.157906 -30.498796)
			)
		)
	)
	(zone
		(layer "F.Cu")
		(hatch none 0.5)
		(connect_pads
			(clearance 0)
		)
		(min_thickness 0.25)
		(keepout
			(tracks not_allowed)
			(vias allowed)
			(pads allowed)
			(copperpour not_allowed)
			(footprints allowed)
		)
		(placement
			(enabled no)
			(sheetname "")
		)
		(fill
			(thermal_gap 0.5)
			(thermal_bridge_width 0.5)
			(island_removal_mode 0)
		)
		(polygon
			(pts
				(arc
					(start 131.99999 -94.309946)
					(mid 134.999984 -91.309952)
					(end 137.999978 -94.309946)
				)
				(arc
					(start 137.999978 -94.309946)
					(mid 134.999984 -97.30994)
					(end 131.99999 -94.309946)
				)
			)
		)
	)
	(zone
		(layer "F.Cu")
		(hatch none 0.5)
		(connect_pads
			(clearance 0)
		)
		(min_thickness 0.25)
		(keepout
			(tracks not_allowed)
			(vias allowed)
			(pads allowed)
			(copperpour not_allowed)
			(footprints allowed)
		)
		(placement
			(enabled no)
			(sheetname "")
		)
		(fill
			(thermal_gap 0.5)
			(thermal_bridge_width 0.5)
			(island_removal_mode 0)
		)
		(polygon
			(pts
				(arc
					(start 105.358184 -55.000144)
					(mid 105.000044 -54.642004)
					(end 104.641904 -55.000144)
				)
				(arc
					(start 104.641904 -55.999888)
					(mid 104.833212 -56.317051)
					(end 105.20299 -56.29529)
				)
				(arc
					(start 105.118154 -56.210454)
					(mid 104.829484 -55.829582)
					(end 105.210356 -56.118252)
				)
				(arc
					(start 105.295192 -56.203088)
					(mid 105.342077 -56.106391)
					(end 105.358184 -56.000142)
				)
				(xy 105.358184 -55.450486)
				(arc
					(start 105.118154 -55.210456)
					(mid 104.829484 -54.829584)
					(end 105.210356 -55.118254)
				)
				(xy 105.358184 -55.266082)
			)
		)
	)
	(zone
		(net "GND")
		(layer "F.Cu")
		(hatch none 0.5)
		(connect_pads
			(clearance 0.5)
		)
		(min_thickness 0.25)
		(fill yes
			(thermal_gap 0.5)
			(thermal_bridge_width 0.5)
			(island_removal_mode 0)
		)
		(polygon
			(pts
				(xy 165.9255 -81.4324) (xy 165.8239 -81.534) (xy 165.8239 -91.6559) (xy 165.5318 -91.948) (xy 163.5506 -91.948)
				(xy 163.449 -92.0496) (xy 163.449 -93.2434) (xy 163.6014 -93.3958) (xy 166.519098 -93.3958) (xy 167.115744 -93.992446)
				(xy 169.400474 -93.992446) (xy 169.444924 -93.947996) (xy 169.444924 -93.287596) (xy 168.4528 -92.295472)
				(xy 168.4528 -88.646) (xy 168.6052 -88.4936) (xy 169.248074 -88.4936) (xy 169.324274 -88.4174) (xy 169.324274 -82.87766)
				(xy 169.32148 -82.87512) (xy 169.32148 -81.61528) (xy 169.1386 -81.4324)
			)
		)
		(polygon
			(pts
				(xy 166.0652 -92.6846) (xy 165.862 -92.6846) (xy 165.862 -92.8878) (xy 166.0652 -92.8878)
			)
		)
		(polygon
			(pts
				(xy 165.4556 -92.6846) (xy 165.2524 -92.6846) (xy 165.2524 -92.8878) (xy 165.4556 -92.8878)
			)
		)
		(polygon
			(pts
				(xy 168.829482 -87.736172) (xy 168.626282 -87.736172) (xy 168.626282 -87.939372) (xy 168.829482 -87.939372)
			)
		)
	)
	(zone
		(net "P1V8_E")
		(layer "F.Cu")
		(hatch none 0.5)
		(connect_pads
			(clearance 0.5)
		)
		(min_thickness 0.25)
		(fill yes
			(thermal_gap 0.5)
			(thermal_bridge_width 0.5)
			(island_removal_mode 0)
		)
		(polygon
			(pts
				(xy 65.382902 -12.8651) (xy 65.125854 -13.122148) (xy 65.125854 -14.984984) (xy 65.35928 -15.21841)
				(xy 67.09918 -15.21841) (xy 67.255644 -15.061946) (xy 67.255644 -13.079984) (xy 67.04076 -12.8651)
			)
		)
	)
	(zone
		(layer "F.Cu")
		(hatch none 0.5)
		(connect_pads
			(clearance 0)
		)
		(min_thickness 0.25)
		(keepout
			(tracks allowed)
			(vias allowed)
			(pads allowed)
			(copperpour allowed)
			(footprints allowed)
		)
		(placement
			(enabled no)
			(sheetname "")
		)
		(fill
			(thermal_gap 0.5)
			(thermal_bridge_width 0.5)
			(island_removal_mode 0)
		)
		(polygon
			(pts
				(xy 152.527 -94.1324) (xy 152.527 -92.8116) (xy 154.4574 -92.8116) (xy 154.4574 -94.1324)
			)
		)
	)
	(zone
		(layer "F.Cu")
		(hatch none 0.5)
		(connect_pads
			(clearance 0)
		)
		(min_thickness 0.25)
		(keepout
			(tracks not_allowed)
			(vias allowed)
			(pads allowed)
			(copperpour not_allowed)
			(footprints allowed)
		)
		(placement
			(enabled no)
			(sheetname "")
		)
		(fill
			(thermal_gap 0.5)
			(thermal_bridge_width 0.5)
			(island_removal_mode 0)
		)
		(polygon
			(pts
				(arc
					(start 104.358186 -55.000144)
					(mid 104.000046 -54.642004)
					(end 103.641906 -55.000144)
				)
				(arc
					(start 103.641906 -55.999888)
					(mid 103.833214 -56.317051)
					(end 104.202992 -56.29529)
				)
				(arc
					(start 104.118156 -56.210454)
					(mid 103.829486 -55.829582)
					(end 104.210358 -56.118252)
				)
				(arc
					(start 104.295194 -56.203088)
					(mid 104.342079 -56.106391)
					(end 104.358186 -56.000142)
				)
				(xy 104.358186 -55.450486)
				(arc
					(start 104.118156 -55.210456)
					(mid 103.829486 -54.829584)
					(end 104.210358 -55.118254)
				)
				(xy 104.358186 -55.266082)
			)
		)
	)
	(zone
		(layer "F.Cu")
		(hatch none 0.5)
		(connect_pads
			(clearance 0)
		)
		(min_thickness 0.25)
		(keepout
			(tracks not_allowed)
			(vias allowed)
			(pads allowed)
			(copperpour not_allowed)
			(footprints allowed)
		)
		(placement
			(enabled no)
			(sheetname "")
		)
		(fill
			(thermal_gap 0.5)
			(thermal_bridge_width 0.5)
			(island_removal_mode 0)
		)
		(polygon
			(pts
				(arc
					(start 129.00025 -60.641992)
					(mid 128.683087 -60.8333)
					(end 128.704848 -61.203078)
				)
				(arc
					(start 128.789684 -61.118242)
					(mid 129.170556 -60.829572)
					(end 128.881886 -61.210444)
				)
				(arc
					(start 128.79705 -61.29528)
					(mid 128.893747 -61.342165)
					(end 128.999996 -61.358272)
				)
				(xy 129.549652 -61.358272)
				(arc
					(start 129.789682 -61.118242)
					(mid 130.170554 -60.829572)
					(end 129.881884 -61.210444)
				)
				(xy 129.734056 -61.358272)
				(arc
					(start 129.999994 -61.358272)
					(mid 130.358134 -61.000132)
					(end 129.999994 -60.641992)
				)
			)
		)
	)
	(zone
		(layer "F.Cu")
		(hatch none 0.5)
		(connect_pads
			(clearance 0)
		)
		(min_thickness 0.25)
		(keepout
			(tracks not_allowed)
			(vias allowed)
			(pads allowed)
			(copperpour not_allowed)
			(footprints allowed)
		)
		(placement
			(enabled no)
			(sheetname "")
		)
		(fill
			(thermal_gap 0.5)
			(thermal_bridge_width 0.5)
			(island_removal_mode 0)
		)
		(polygon
			(pts
				(arc
					(start 174.698406 -23.112476)
					(mid 174.314866 -22.728936)
					(end 173.931326 -23.112476)
				)
				(xy 173.931326 -23.315676) (xy 174.021242 -23.315676)
				(arc
					(start 174.025814 -23.315676)
					(mid 174.073639 -23.309906)
					(end 174.118778 -23.29307)
				)
				(arc
					(start 174.118778 -23.29307)
					(mid 174.433523 -22.873872)
					(end 174.290482 -23.37816)
				)
				(arc
					(start 174.290482 -23.37816)
					(mid 174.186094 -23.451515)
					(end 174.063152 -23.485602)
				)
				(xy 174.061374 -23.48738) (xy 174.035466 -23.48738) (xy 174.025814 -23.48738) (xy 174.021242 -23.48738)
				(xy 173.931326 -23.48738) (xy 173.931326 -23.62708) (xy 174.021496 -23.62708) (xy 174.026068 -23.626826)
				(xy 174.03572 -23.62708) (xy 174.061628 -23.62708)
				(arc
					(start 174.063406 -23.628604)
					(mid 174.186077 -23.662618)
					(end 174.290228 -23.735792)
				)
				(arc
					(start 174.290228 -23.735792)
					(mid 174.433277 -24.240587)
					(end 174.118524 -23.820882)
				)
				(arc
					(start 174.118524 -23.820882)
					(mid 174.073621 -23.804242)
					(end 174.026068 -23.79853)
				)
				(xy 174.021496 -23.798276) (xy 173.931326 -23.798276)
				(arc
					(start 173.931326 -24.001222)
					(mid 174.314739 -24.385016)
					(end 174.698406 -24.001476)
				)
			)
		)
	)
	(zone
		(layer "F.Cu")
		(hatch none 0.5)
		(connect_pads
			(clearance 0)
		)
		(min_thickness 0.25)
		(keepout
			(tracks not_allowed)
			(vias allowed)
			(pads allowed)
			(copperpour not_allowed)
			(footprints allowed)
		)
		(placement
			(enabled no)
			(sheetname "")
		)
		(fill
			(thermal_gap 0.5)
			(thermal_bridge_width 0.5)
			(island_removal_mode 0)
		)
		(polygon
			(pts
				(xy 148.085556 -50.60061)
				(arc
					(start 148.38045 -50.661316)
					(mid 148.420387 -50.661029)
					(end 148.45665 -50.644298)
				)
				(arc
					(start 148.45665 -50.644298)
					(mid 148.653103 -50.155025)
					(end 148.611844 -50.68062)
				)
				(xy 148.60524 -50.71237)
				(arc
					(start 148.590254 -50.722022)
					(mid 148.497959 -50.79262)
					(end 148.383498 -50.8127)
				)
				(xy 148.380704 -50.814478) (xy 148.350478 -50.808128) (xy 148.054314 -50.747168) (xy 148.000974 -50.998374)
				(xy 148.334476 -51.066954) (xy 148.337778 -51.067462) (xy 148.368258 -51.073304)
				(arc
					(start 148.371306 -51.077368)
					(mid 148.460788 -51.152156)
					(end 148.488908 -51.265328)
				)
				(xy 148.490178 -51.26736) (xy 148.486368 -51.285648)
				(arc
					(start 148.48332 -51.29911)
					(mid 148.296584 -51.793234)
					(end 148.337016 -51.266598)
				)
				(arc
					(start 148.339048 -51.256946)
					(mid 148.333057 -51.230809)
					(end 148.311362 -51.215036)
				)
				(xy 148.30552 -51.213766) (xy 148.275802 -51.208178) (xy 148.275294 -51.20767) (xy 147.969732 -51.144932)
				(arc
					(start 147.907502 -51.437794)
					(mid 148.2598 -51.980084)
					(end 148.80209 -51.627786)
				)
				(xy 148.921216 -51.067462)
				(arc
					(start 149.037294 -50.520092)
					(mid 148.69273 -49.968723)
					(end 148.145246 -50.319686)
				)
			)
		)
	)
	(zone
		(layer "F.Cu")
		(hatch none 0.5)
		(connect_pads
			(clearance 0)
		)
		(min_thickness 0.25)
		(keepout
			(tracks allowed)
			(vias allowed)
			(pads allowed)
			(copperpour allowed)
			(footprints allowed)
		)
		(placement
			(enabled no)
			(sheetname "")
		)
		(fill
			(thermal_gap 0.5)
			(thermal_bridge_width 0.5)
			(island_removal_mode 0)
		)
		(polygon
			(pts
				(xy 85.979 -71.0438) (xy 85.979 -66.3702) (xy 88.5698 -66.3702) (xy 88.5698 -71.0438)
			)
		)
	)
	(zone
		(layer "F.Cu")
		(hatch none 0.5)
		(connect_pads
			(clearance 0)
		)
		(min_thickness 0.25)
		(keepout
			(tracks not_allowed)
			(vias allowed)
			(pads allowed)
			(copperpour not_allowed)
			(footprints allowed)
		)
		(placement
			(enabled no)
			(sheetname "")
		)
		(fill
			(thermal_gap 0.5)
			(thermal_bridge_width 0.5)
			(island_removal_mode 0)
		)
		(polygon
			(pts
				(arc
					(start 166.508938 -23.166832)
					(mid 166.125398 -22.783292)
					(end 165.741858 -23.166832)
				)
				(xy 165.741858 -23.370032) (xy 165.831774 -23.370032)
				(arc
					(start 165.836346 -23.370032)
					(mid 165.884171 -23.364262)
					(end 165.92931 -23.347426)
				)
				(arc
					(start 165.92931 -23.347426)
					(mid 166.244055 -22.928228)
					(end 166.101014 -23.432516)
				)
				(arc
					(start 166.101014 -23.432516)
					(mid 165.996626 -23.505871)
					(end 165.873684 -23.539958)
				)
				(xy 165.871906 -23.541736) (xy 165.845998 -23.541736) (xy 165.836346 -23.541736) (xy 165.831774 -23.541736)
				(xy 165.741858 -23.541736) (xy 165.741858 -23.681436) (xy 165.832028 -23.681436) (xy 165.8366 -23.681182)
				(xy 165.846252 -23.681436) (xy 165.87216 -23.681436)
				(arc
					(start 165.873938 -23.68296)
					(mid 165.996609 -23.716974)
					(end 166.10076 -23.790148)
				)
				(arc
					(start 166.10076 -23.790148)
					(mid 166.243809 -24.294943)
					(end 165.929056 -23.875238)
				)
				(arc
					(start 165.929056 -23.875238)
					(mid 165.884153 -23.858598)
					(end 165.8366 -23.852886)
				)
				(xy 165.832028 -23.852632) (xy 165.741858 -23.852632)
				(arc
					(start 165.741858 -24.055578)
					(mid 166.125271 -24.439372)
					(end 166.508938 -24.055832)
				)
			)
		)
	)
	(zone
		(layer "F.Cu")
		(hatch none 0.5)
		(connect_pads
			(clearance 0)
		)
		(min_thickness 0.25)
		(keepout
			(tracks allowed)
			(vias allowed)
			(pads allowed)
			(copperpour allowed)
			(footprints allowed)
		)
		(placement
			(enabled no)
			(sheetname "")
		)
		(fill
			(thermal_gap 0.5)
			(thermal_bridge_width 0.5)
			(island_removal_mode 0)
		)
		(polygon
			(pts
				(xy 201.10577 -84.0994) (xy 201.10577 -85.561678) (xy 198.501 -85.561678) (xy 198.501 -84.0994)
			)
		)
	)
	(zone
		(layer "F.Cu")
		(hatch none 0.5)
		(connect_pads
			(clearance 0)
		)
		(min_thickness 0.25)
		(keepout
			(tracks not_allowed)
			(vias allowed)
			(pads allowed)
			(copperpour not_allowed)
			(footprints allowed)
		)
		(placement
			(enabled no)
			(sheetname "")
		)
		(fill
			(thermal_gap 0.5)
			(thermal_bridge_width 0.5)
			(island_removal_mode 0)
		)
		(polygon
			(pts
				(arc
					(start 126.000256 -54.642004)
					(mid 125.683093 -54.833312)
					(end 125.704854 -55.20309)
				)
				(arc
					(start 125.78969 -55.118254)
					(mid 126.170562 -54.829584)
					(end 125.881892 -55.210456)
				)
				(arc
					(start 125.797056 -55.295292)
					(mid 125.893753 -55.342177)
					(end 126.000002 -55.358284)
				)
				(xy 126.549658 -55.358284)
				(arc
					(start 126.789688 -55.118254)
					(mid 127.17056 -54.829584)
					(end 126.88189 -55.210456)
				)
				(xy 126.734062 -55.358284)
				(arc
					(start 127 -55.358284)
					(mid 127.35814 -55.000144)
					(end 127 -54.642004)
				)
			)
		)
	)
	(zone
		(layer "F.Cu")
		(hatch none 0.5)
		(connect_pads
			(clearance 0)
		)
		(min_thickness 0.25)
		(keepout
			(tracks allowed)
			(vias allowed)
			(pads allowed)
			(copperpour allowed)
			(footprints allowed)
		)
		(placement
			(enabled no)
			(sheetname "")
		)
		(fill
			(thermal_gap 0.5)
			(thermal_bridge_width 0.5)
			(island_removal_mode 0)
		)
		(polygon
			(pts
				(xy 130.302 -44.6278) (xy 130.302 -44.2468) (xy 131.318 -44.2468) (xy 131.318 -44.6278)
			)
		)
	)
	(zone
		(layer "F.Cu")
		(hatch none 0.5)
		(connect_pads
			(clearance 0)
		)
		(min_thickness 0.25)
		(keepout
			(tracks not_allowed)
			(vias allowed)
			(pads allowed)
			(copperpour not_allowed)
			(footprints allowed)
		)
		(placement
			(enabled no)
			(sheetname "")
		)
		(fill
			(thermal_gap 0.5)
			(thermal_bridge_width 0.5)
			(island_removal_mode 0)
		)
		(polygon
			(pts
				(arc
					(start 176.158144 -30.400244)
					(mid 175.800004 -30.042104)
					(end 175.441864 -30.400244)
				)
				(xy 175.441864 -30.734) (xy 175.4886 -30.780736) (xy 175.4886 -30.839664) (xy 175.441864 -30.8864)
				(arc
					(start 175.441864 -31.199836)
					(mid 175.625337 -31.512749)
					(end 175.987964 -31.50489)
				)
				(arc
					(start 175.901858 -31.418784)
					(mid 175.629415 -31.029501)
					(end 176.018698 -31.301944)
				)
				(arc
					(start 176.104804 -31.38805)
					(mid 176.144546 -31.29778)
					(end 176.158144 -31.20009)
				)
				(xy 176.158144 -30.875224)
				(arc
					(start 175.901858 -30.618938)
					(mid 175.629415 -30.229655)
					(end 176.018698 -30.502098)
				)
				(xy 176.158144 -30.641544)
			)
		)
	)
	(zone
		(net "P12V_MAIN")
		(layer "F.Cu")
		(hatch none 0.5)
		(connect_pads
			(clearance 0.5)
		)
		(min_thickness 0.25)
		(fill yes
			(thermal_gap 0.5)
			(thermal_bridge_width 0.5)
			(island_removal_mode 0)
		)
		(polygon
			(pts
				(xy 21.5138 -31.242) (xy 20.7518 -32.004) (xy 16.5608 -32.004) (xy 16.22806 -32.33674) (xy 16.22806 -34.97326)
				(xy 16.300704 -35.045904) (xy 17.697704 -35.045904) (xy 17.8308 -35.179) (xy 20.3708 -35.179) (xy 21.0058 -35.814)
				(xy 21.0058 -37.465) (xy 21.2598 -37.719) (xy 30.5308 -37.719) (xy 30.7848 -37.465) (xy 30.7848 -31.496)
				(xy 30.5308 -31.242)
			)
		)
	)
	(zone
		(layer "F.Cu")
		(hatch none 0.5)
		(connect_pads
			(clearance 0)
		)
		(min_thickness 0.25)
		(keepout
			(tracks not_allowed)
			(vias allowed)
			(pads allowed)
			(copperpour not_allowed)
			(footprints allowed)
		)
		(placement
			(enabled no)
			(sheetname "")
		)
		(fill
			(thermal_gap 0.5)
			(thermal_bridge_width 0.5)
			(island_removal_mode 0)
		)
		(polygon
			(pts
				(arc
					(start 117.35816 -51.000152)
					(mid 117.00002 -50.642012)
					(end 116.64188 -51.000152)
				)
				(xy 116.64188 -51.26609)
				(arc
					(start 116.789708 -51.118262)
					(mid 117.17058 -50.829592)
					(end 116.88191 -51.210464)
				)
				(xy 116.64188 -51.450494)
				(arc
					(start 116.64188 -51.999896)
					(mid 116.657963 -52.10627)
					(end 116.704872 -52.203096)
				)
				(arc
					(start 116.789708 -52.11826)
					(mid 117.17058 -51.82959)
					(end 116.88191 -52.210462)
				)
				(arc
					(start 116.797074 -52.295298)
					(mid 117.166763 -52.317161)
					(end 117.35816 -52.00015)
				)
				(xy 117.35816 -51.69916) (xy 117.2464 -51.5874) (xy 117.2464 -51.41976) (xy 117.35816 -51.308)
			)
		)
	)
	(zone
		(net "GND")
		(layer "F.Cu")
		(hatch none 0.5)
		(connect_pads
			(clearance 0.5)
		)
		(min_thickness 0.25)
		(fill yes
			(thermal_gap 0.5)
			(thermal_bridge_width 0.5)
			(island_removal_mode 0)
		)
		(polygon
			(pts
				(xy 19.430492 -79.413354) (xy 19.318732 -79.525114) (xy 19.318732 -80.12176) (xy 18.851118 -80.589374)
				(xy 18.851118 -82.065368) (xy 18.913094 -82.127344) (xy 20.147534 -82.127344) (xy 20.284186 -81.990692)
				(xy 20.284186 -79.475584) (xy 20.221956 -79.413354)
			)
		)
		(polygon
			(pts
				(xy 19.558 -81.026) (xy 19.3548 -81.026) (xy 19.3548 -81.5086) (xy 19.558 -81.5086)
			)
		)
		(polygon
			(pts
				(xy 19.558 -80.4164) (xy 19.3548 -80.4164) (xy 19.3548 -80.6196) (xy 19.558 -80.6196)
			)
		)
		(polygon
			(pts
				(xy 19.9898 -79.9338) (xy 19.7866 -79.9338) (xy 19.7866 -80.137) (xy 19.9898 -80.137)
			)
		)
	)
	(zone
		(layer "F.Cu")
		(hatch none 0.5)
		(connect_pads
			(clearance 0)
		)
		(min_thickness 0.25)
		(keepout
			(tracks not_allowed)
			(vias allowed)
			(pads allowed)
			(copperpour not_allowed)
			(footprints allowed)
		)
		(placement
			(enabled no)
			(sheetname "")
		)
		(fill
			(thermal_gap 0.5)
			(thermal_bridge_width 0.5)
			(island_removal_mode 0)
		)
		(polygon
			(pts
				(arc
					(start 70.25005 -134.999984)
					(mid 75.000104 -130.24993)
					(end 79.749904 -134.999984)
				)
				(arc
					(start 79.749904 -134.999984)
					(mid 75.000104 -139.749784)
					(end 70.25005 -134.999984)
				)
			)
		)
	)
	(zone
		(layer "F.Cu")
		(hatch none 0.5)
		(connect_pads
			(clearance 0)
		)
		(min_thickness 0.25)
		(keepout
			(tracks not_allowed)
			(vias allowed)
			(pads allowed)
			(copperpour not_allowed)
			(footprints allowed)
		)
		(placement
			(enabled no)
			(sheetname "")
		)
		(fill
			(thermal_gap 0.5)
			(thermal_bridge_width 0.5)
			(island_removal_mode 0)
		)
		(polygon
			(pts
				(arc
					(start 126.000256 -62.641988)
					(mid 125.683093 -62.833296)
					(end 125.704854 -63.203074)
				)
				(arc
					(start 125.78969 -63.118238)
					(mid 126.170562 -62.829568)
					(end 125.881892 -63.21044)
				)
				(arc
					(start 125.797056 -63.295276)
					(mid 125.893753 -63.342161)
					(end 126.000002 -63.358268)
				)
				(xy 126.549658 -63.358268)
				(arc
					(start 126.789688 -63.118238)
					(mid 127.17056 -62.829568)
					(end 126.88189 -63.21044)
				)
				(xy 126.734062 -63.358268)
				(arc
					(start 127 -63.358268)
					(mid 127.35814 -63.000128)
					(end 127 -62.641988)
				)
			)
		)
	)
	(zone
		(net "GND")
		(layer "F.Cu")
		(hatch none 0.5)
		(connect_pads
			(clearance 0.5)
		)
		(min_thickness 0.25)
		(fill yes
			(thermal_gap 0.5)
			(thermal_bridge_width 0.5)
			(island_removal_mode 0)
		)
		(polygon
			(pts
				(xy 155.575 -108.458) (xy 155.448 -108.585) (xy 155.448 -110.617) (xy 155.575 -110.744) (xy 159.916368 -110.744)
				(xy 160.059878 -110.60049) (xy 160.059878 -108.574078) (xy 159.9438 -108.458)
			)
		)
		(polygon
			(pts
				(xy 156.96438 -109.68482) (xy 156.76118 -109.68482) (xy 156.76118 -109.88802) (xy 156.96438 -109.88802)
			)
		)
		(polygon
			(pts
				(xy 156.10078 -109.68482) (xy 155.89758 -109.68482) (xy 155.89758 -109.88802) (xy 156.10078 -109.88802)
			)
		)
		(polygon
			(pts
				(xy 158.1658 -109.6772) (xy 157.9626 -109.6772) (xy 157.9626 -109.8804) (xy 158.1658 -109.8804)
			)
		)
		(polygon
			(pts
				(xy 157.3022 -109.6772) (xy 157.099 -109.6772) (xy 157.099 -109.8804) (xy 157.3022 -109.8804)
			)
		)
	)
	(zone
		(net "P3V3")
		(layer "F.Cu")
		(hatch none 0.5)
		(connect_pads
			(clearance 0.5)
		)
		(min_thickness 0.25)
		(fill yes
			(thermal_gap 0.5)
			(thermal_bridge_width 0.5)
			(island_removal_mode 0)
		)
		(polygon
			(pts
				(xy 170.70705 -115.98275) (xy 170.2562 -116.4336) (xy 170.2562 -120.269) (xy 170.6118 -120.6246)
				(xy 174.5996 -120.6246) (xy 175.2346 -119.9896) (xy 175.2346 -118.2116) (xy 174.5996 -118.2116)
				(xy 174.4726 -118.0846) (xy 174.4726 -116.0526) (xy 174.40275 -115.98275)
			)
		)
		(polygon
			(pts
				(xy 171.92752 -116.47424) (xy 171.72432 -116.47424) (xy 171.72432 -116.67744) (xy 171.92752 -116.67744)
			)
		)
		(polygon
			(pts
				(xy 171.36872 -116.47424) (xy 171.16552 -116.47424) (xy 171.16552 -116.67744) (xy 171.36872 -116.67744)
			)
		)
	)
	(zone
		(layer "F.Cu")
		(hatch none 0.5)
		(connect_pads
			(clearance 0)
		)
		(min_thickness 0.25)
		(keepout
			(tracks allowed)
			(vias allowed)
			(pads allowed)
			(copperpour allowed)
			(footprints allowed)
		)
		(placement
			(enabled no)
			(sheetname "")
		)
		(fill
			(thermal_gap 0.5)
			(thermal_bridge_width 0.5)
			(island_removal_mode 0)
		)
		(polygon
			(pts
				(xy 160.348422 -7.713472) (xy 160.348422 -5.148072) (xy 166.139622 -5.148072) (xy 166.139622 -7.713472)
			)
		)
	)
	(zone
		(layer "F.Cu")
		(hatch none 0.5)
		(connect_pads
			(clearance 0)
		)
		(min_thickness 0.25)
		(keepout
			(tracks allowed)
			(vias allowed)
			(pads allowed)
			(copperpour allowed)
			(footprints allowed)
		)
		(placement
			(enabled no)
			(sheetname "")
		)
		(fill
			(thermal_gap 0.5)
			(thermal_bridge_width 0.5)
			(island_removal_mode 0)
		)
		(polygon
			(pts
				(xy 201.08037 -89.016078) (xy 201.08037 -90.133678) (xy 198.4756 -90.133678) (xy 198.4756 -89.016078)
			)
		)
	)
	(zone
		(layer "F.Cu")
		(hatch none 0.5)
		(connect_pads
			(clearance 0)
		)
		(min_thickness 0.25)
		(keepout
			(tracks allowed)
			(vias allowed)
			(pads allowed)
			(copperpour allowed)
			(footprints allowed)
		)
		(placement
			(enabled no)
			(sheetname "")
		)
		(fill
			(thermal_gap 0.5)
			(thermal_bridge_width 0.5)
			(island_removal_mode 0)
		)
		(polygon
			(pts
				(xy 155.2448 -94.1324) (xy 155.2448 -92.2274) (xy 157.1752 -92.2274) (xy 157.1752 -94.1324)
			)
		)
	)
	(zone
		(layer "F.Cu")
		(hatch none 0.5)
		(connect_pads
			(clearance 0)
		)
		(min_thickness 0.25)
		(keepout
			(tracks not_allowed)
			(vias allowed)
			(pads allowed)
			(copperpour not_allowed)
			(footprints allowed)
		)
		(placement
			(enabled no)
			(sheetname "")
		)
		(fill
			(thermal_gap 0.5)
			(thermal_bridge_width 0.5)
			(island_removal_mode 0)
		)
		(polygon
			(pts
				(arc
					(start 106.358182 -51.000152)
					(mid 106.000042 -50.642012)
					(end 105.641902 -51.000152)
				)
				(xy 105.641902 -51.308) (xy 105.7402 -51.406298) (xy 105.7402 -51.6128) (xy 105.641902 -51.711098)
				(arc
					(start 105.641902 -51.999896)
					(mid 105.83321 -52.317059)
					(end 106.202988 -52.295298)
				)
				(arc
					(start 106.118152 -52.210462)
					(mid 105.829482 -51.82959)
					(end 106.210354 -52.11826)
				)
				(arc
					(start 106.29519 -52.203096)
					(mid 106.342075 -52.106399)
					(end 106.358182 -52.00015)
				)
				(xy 106.358182 -51.450494)
				(arc
					(start 106.118152 -51.210464)
					(mid 105.829482 -50.829592)
					(end 106.210354 -51.118262)
				)
				(xy 106.358182 -51.26609)
			)
		)
	)
	(zone
		(net "GND")
		(layer "F.Cu")
		(hatch none 0.5)
		(connect_pads
			(clearance 0.5)
		)
		(min_thickness 0.25)
		(fill yes
			(thermal_gap 0.5)
			(thermal_bridge_width 0.5)
			(island_removal_mode 0)
		)
		(polygon
			(pts
				(xy 185.4708 -82.4484) (xy 184.9755 -82.9437) (xy 184.9755 -90.0303) (xy 187.2996 -92.3544) (xy 190.119 -92.3544)
				(xy 190.3476 -92.1258) (xy 190.3476 -82.677) (xy 190.119 -82.4484)
			)
		)
	)
	(zone
		(layer "F.Cu")
		(hatch none 0.5)
		(connect_pads
			(clearance 0)
		)
		(min_thickness 0.25)
		(keepout
			(tracks not_allowed)
			(vias allowed)
			(pads allowed)
			(copperpour not_allowed)
			(footprints allowed)
		)
		(placement
			(enabled no)
			(sheetname "")
		)
		(fill
			(thermal_gap 0.5)
			(thermal_bridge_width 0.5)
			(island_removal_mode 0)
		)
		(polygon
			(pts
				(arc
					(start 113.358168 -52.00015)
					(mid 113.000028 -51.64201)
					(end 112.641888 -52.00015)
				)
				(arc
					(start 112.641888 -52.999894)
					(mid 112.833196 -53.317057)
					(end 113.202974 -53.295296)
				)
				(arc
					(start 113.118138 -53.21046)
					(mid 112.829468 -52.829588)
					(end 113.21034 -53.118258)
				)
				(arc
					(start 113.295176 -53.203094)
					(mid 113.342061 -53.106397)
					(end 113.358168 -53.000148)
				)
				(xy 113.358168 -52.450492)
				(arc
					(start 113.118138 -52.210462)
					(mid 112.829468 -51.82959)
					(end 113.21034 -52.11826)
				)
				(xy 113.358168 -52.266088)
			)
		)
	)
	(zone
		(net "P12V_STBY_SCC")
		(layer "F.Cu")
		(hatch none 0.5)
		(connect_pads
			(clearance 0.5)
		)
		(min_thickness 0.25)
		(fill yes
			(thermal_gap 0.5)
			(thermal_bridge_width 0.5)
			(island_removal_mode 0)
		)
		(polygon
			(pts
				(xy 9.562338 -35.383216) (xy 9.455404 -35.49015) (xy 9.336278 -35.614356) (xy 9.336278 -41.177718)
				(xy 9.58596 -41.4274) (xy 12.898374 -41.4274) (xy 13.716 -40.609774) (xy 13.716 -35.687) (xy 13.412216 -35.383216)
			)
		)
		(polygon
			(pts
				(xy 13.3096 -38.7858) (xy 13.1064 -38.7858) (xy 13.1064 -38.989) (xy 13.3096 -38.989)
			)
		)
		(polygon
			(pts
				(xy 13.3096 -38.227) (xy 13.1064 -38.227) (xy 13.1064 -38.4302) (xy 13.3096 -38.4302)
			)
		)
	)
	(zone
		(net "P3V3")
		(layer "F.Cu")
		(hatch none 0.5)
		(connect_pads
			(clearance 0.5)
		)
		(min_thickness 0.25)
		(fill yes
			(thermal_gap 0.5)
			(thermal_bridge_width 0.5)
			(island_removal_mode 0)
		)
		(polygon
			(pts
				(xy 165.104064 -11.121136) (xy 164.9984 -11.2268) (xy 164.9984 -12.752578) (xy 165.098222 -12.8524)
				(xy 165.098222 -13.222478) (xy 165.473888 -13.598144) (xy 166.995856 -13.598144) (xy 167.259 -13.335)
				(xy 167.259 -11.303) (xy 167.077136 -11.121136)
			)
		)
	)
	(zone
		(layer "F.Cu")
		(hatch none 0.5)
		(connect_pads
			(clearance 0)
		)
		(min_thickness 0.25)
		(keepout
			(tracks not_allowed)
			(vias allowed)
			(pads allowed)
			(copperpour not_allowed)
			(footprints allowed)
		)
		(placement
			(enabled no)
			(sheetname "")
		)
		(fill
			(thermal_gap 0.5)
			(thermal_bridge_width 0.5)
			(island_removal_mode 0)
		)
		(polygon
			(pts
				(arc
					(start 102.35819 -51.000152)
					(mid 102.00005 -50.642012)
					(end 101.64191 -51.000152)
				)
				(xy 101.64191 -51.2826) (xy 101.7778 -51.41849) (xy 101.7778 -51.5874) (xy 101.64191 -51.72329)
				(arc
					(start 101.64191 -51.999896)
					(mid 101.833218 -52.317059)
					(end 102.202996 -52.295298)
				)
				(arc
					(start 102.11816 -52.210462)
					(mid 101.82949 -51.82959)
					(end 102.210362 -52.11826)
				)
				(arc
					(start 102.295198 -52.203096)
					(mid 102.342083 -52.106399)
					(end 102.35819 -52.00015)
				)
				(xy 102.35819 -51.450494)
				(arc
					(start 102.11816 -51.210464)
					(mid 101.82949 -50.829592)
					(end 102.210362 -51.118262)
				)
				(xy 102.35819 -51.26609)
			)
		)
	)
	(zone
		(layer "F.Cu")
		(hatch none 0.5)
		(connect_pads
			(clearance 0)
		)
		(min_thickness 0.25)
		(keepout
			(tracks allowed)
			(vias allowed)
			(pads allowed)
			(copperpour allowed)
			(footprints allowed)
		)
		(placement
			(enabled no)
			(sheetname "")
		)
		(fill
			(thermal_gap 0.5)
			(thermal_bridge_width 0.5)
			(island_removal_mode 0)
		)
		(polygon
			(pts
				(xy 7.049262 -87.913718) (xy 7.049262 -86.508336) (xy 8.021828 -86.508336) (xy 8.021828 -87.913718)
			)
		)
	)
	(zone
		(layer "F.Cu")
		(hatch none 0.5)
		(connect_pads
			(clearance 0)
		)
		(min_thickness 0.25)
		(keepout
			(tracks not_allowed)
			(vias allowed)
			(pads allowed)
			(copperpour not_allowed)
			(footprints allowed)
		)
		(placement
			(enabled no)
			(sheetname "")
		)
		(fill
			(thermal_gap 0.5)
			(thermal_bridge_width 0.5)
			(island_removal_mode 0)
		)
		(polygon
			(pts
				(arc
					(start 108.358178 -55.000144)
					(mid 108.000038 -54.642004)
					(end 107.641898 -55.000144)
				)
				(arc
					(start 107.641898 -55.999888)
					(mid 107.833206 -56.317051)
					(end 108.202984 -56.29529)
				)
				(arc
					(start 108.118148 -56.210454)
					(mid 107.829478 -55.829582)
					(end 108.21035 -56.118252)
				)
				(arc
					(start 108.295186 -56.203088)
					(mid 108.342071 -56.106391)
					(end 108.358178 -56.000142)
				)
				(xy 108.358178 -55.450486)
				(arc
					(start 108.118148 -55.210456)
					(mid 107.829478 -54.829584)
					(end 108.21035 -55.118254)
				)
				(xy 108.358178 -55.266082)
			)
		)
	)
	(zone
		(net "P12V_STBY_VIN_Q7")
		(layer "F.Cu")
		(hatch none 0.5)
		(connect_pads
			(clearance 0.5)
		)
		(min_thickness 0.25)
		(fill yes
			(thermal_gap 0.5)
			(thermal_bridge_width 0.5)
			(island_removal_mode 0)
		)
		(polygon
			(pts
				(xy 35.5854 -43.561) (xy 35.0774 -44.069) (xy 35.0774 -49.403) (xy 35.2044 -49.53) (xy 47.3456 -49.53)
				(xy 47.9806 -48.895) (xy 47.9806 -46.609) (xy 47.8536 -46.482) (xy 44.831 -46.482) (xy 44.0436 -45.6946)
				(xy 44.0436 -43.815) (xy 43.7896 -43.561)
			)
		)
		(polygon
			(pts
				(xy 45.8724 -48.5394) (xy 45.6692 -48.5394) (xy 45.6692 -48.7426) (xy 45.8724 -48.7426)
			)
		)
		(polygon
			(pts
				(xy 45.0088 -48.5394) (xy 44.8056 -48.5394) (xy 44.8056 -48.7426) (xy 45.0088 -48.7426)
			)
		)
	)
	(zone
		(layer "F.Cu")
		(hatch none 0.5)
		(connect_pads
			(clearance 0)
		)
		(min_thickness 0.25)
		(keepout
			(tracks allowed)
			(vias allowed)
			(pads allowed)
			(copperpour allowed)
			(footprints allowed)
		)
		(placement
			(enabled no)
			(sheetname "")
		)
		(fill
			(thermal_gap 0.5)
			(thermal_bridge_width 0.5)
			(island_removal_mode 0)
		)
		(polygon
			(pts
				(xy 61.315854 -104.017826) (xy 61.315854 -101.454966) (xy 67.53098 -101.454966) (xy 67.53098 -104.017826)
			)
		)
	)
	(zone
		(net "GND")
		(layer "F.Cu")
		(hatch none 0.5)
		(connect_pads
			(clearance 0.5)
		)
		(min_thickness 0.25)
		(fill yes
			(thermal_gap 0.5)
			(thermal_bridge_width 0.5)
			(island_removal_mode 0)
		)
		(polygon
			(pts
				(xy 46.4312 -34.1122) (xy 46.3804 -34.163) (xy 46.3804 -35.2806) (xy 46.5328 -35.433) (xy 47.0916 -35.433)
				(xy 47.6504 -35.9918) (xy 47.6504 -37.4904) (xy 47.8536 -37.6936) (xy 49.7332 -37.6936) (xy 49.9364 -37.4904)
				(xy 49.9364 -35.3822) (xy 49.8094 -35.2552) (xy 48.5648 -35.2552) (xy 47.4218 -34.1122)
			)
		)
	)
	(zone
		(net "P3V3")
		(layer "F.Cu")
		(hatch none 0.5)
		(connect_pads
			(clearance 0.5)
		)
		(min_thickness 0.25)
		(fill yes
			(thermal_gap 0.5)
			(thermal_bridge_width 0.5)
			(island_removal_mode 0)
		)
		(polygon
			(pts
				(xy 84.3026 -106.4006) (xy 84.2264 -106.4768) (xy 84.2264 -107.9754) (xy 84.276692 -108.025692)
				(xy 86.208108 -108.025692) (xy 86.3346 -107.8992) (xy 86.3346 -106.5276) (xy 86.2076 -106.4006)
			)
		)
		(polygon
			(pts
				(xy 85.6234 -107.3404) (xy 85.4202 -107.3404) (xy 85.4202 -107.5436) (xy 85.6234 -107.5436)
			)
		)
	)
	(zone
		(layer "F.Cu")
		(hatch none 0.5)
		(connect_pads
			(clearance 0)
		)
		(min_thickness 0.25)
		(keepout
			(tracks allowed)
			(vias allowed)
			(pads allowed)
			(copperpour allowed)
			(footprints allowed)
		)
		(placement
			(enabled no)
			(sheetname "")
		)
		(fill
			(thermal_gap 0.5)
			(thermal_bridge_width 0.5)
			(island_removal_mode 0)
		)
		(polygon
			(pts
				(xy 160.4645 -13.326872) (xy 160.4645 -10.761472) (xy 166.2557 -10.761472) (xy 166.2557 -13.326872)
			)
		)
	)
	(zone
		(layer "F.Cu")
		(hatch none 0.5)
		(connect_pads
			(clearance 0)
		)
		(min_thickness 0.25)
		(keepout
			(tracks not_allowed)
			(vias allowed)
			(pads allowed)
			(copperpour not_allowed)
			(footprints allowed)
		)
		(placement
			(enabled no)
			(sheetname "")
		)
		(fill
			(thermal_gap 0.5)
			(thermal_bridge_width 0.5)
			(island_removal_mode 0)
		)
		(polygon
			(pts
				(arc
					(start 149.309328 -40.340788)
					(mid 148.964764 -39.789419)
					(end 148.41728 -40.140382)
				)
				(xy 148.35886 -40.414702) (xy 148.620734 -40.470074) (xy 148.620988 -40.470074) (xy 148.651214 -40.476678)
				(xy 148.68144 -40.483028)
				(arc
					(start 148.693378 -40.485568)
					(mid 148.717139 -40.483612)
					(end 148.735796 -40.468804)
				)
				(arc
					(start 148.735796 -40.468804)
					(mid 148.921669 -39.974971)
					(end 148.883878 -40.501316)
				)
				(xy 148.877274 -40.533066)
				(arc
					(start 148.868892 -40.5384)
					(mid 148.796251 -40.611598)
					(end 148.696172 -40.636444)
				)
				(xy 148.692362 -40.63873) (xy 148.662136 -40.632126) (xy 148.619718 -40.622982) (xy 148.327872 -40.56126)
				(xy 148.274278 -40.812466) (xy 148.578062 -40.876982) (xy 148.57857 -40.876728) (xy 148.608288 -40.883078)
				(xy 148.620734 -40.885618) (xy 148.642832 -40.885618) (xy 148.649182 -40.891968) (xy 148.658072 -40.893746)
				(arc
					(start 148.660866 -40.898064)
					(mid 148.752765 -40.990234)
					(end 148.756116 -41.120314)
				)
				(arc
					(start 148.756116 -41.120314)
					(mid 148.568189 -41.613757)
					(end 148.60905 -41.087294)
				)
				(xy 148.615908 -41.055798)
				(arc
					(start 148.61667 -41.05529)
					(mid 148.611518 -41.043594)
					(end 148.60143 -41.035732)
				)
				(xy 148.580856 -41.035732) (xy 148.574506 -41.029382) (xy 148.561298 -41.026588) (xy 148.531326 -41.020492)
				(xy 148.531072 -41.020238) (xy 148.24329 -40.959024)
				(arc
					(start 148.179536 -41.25849)
					(mid 148.531834 -41.80078)
					(end 149.074124 -41.448482)
				)
			)
		)
	)
	(zone
		(net "P3V3")
		(layer "F.Cu")
		(hatch none 0.5)
		(connect_pads
			(clearance 0.5)
		)
		(min_thickness 0.25)
		(fill yes
			(thermal_gap 0.5)
			(thermal_bridge_width 0.5)
			(island_removal_mode 0)
		)
		(polygon
			(pts
				(xy 17.145 -80.4672) (xy 16.9672 -80.645) (xy 15.0368 -80.645) (xy 14.9352 -80.7466) (xy 14.9352 -81.788)
				(xy 15.0622 -81.915) (xy 18.2626 -81.915) (xy 18.4404 -81.7372) (xy 18.4404 -80.5434) (xy 18.3642 -80.4672)
			)
		)
		(polygon
			(pts
				(xy 18.034 -81.026) (xy 17.8308 -81.026) (xy 17.8308 -81.5086) (xy 18.034 -81.5086)
			)
		)
	)
	(zone
		(layer "F.Cu")
		(hatch none 0.5)
		(connect_pads
			(clearance 0)
		)
		(min_thickness 0.25)
		(keepout
			(tracks not_allowed)
			(vias allowed)
			(pads allowed)
			(copperpour not_allowed)
			(footprints allowed)
		)
		(placement
			(enabled no)
			(sheetname "")
		)
		(fill
			(thermal_gap 0.5)
			(thermal_bridge_width 0.5)
			(island_removal_mode 0)
		)
		(polygon
			(pts
				(arc
					(start 129.00025 -64.641984)
					(mid 128.683087 -64.833292)
					(end 128.704848 -65.20307)
				)
				(arc
					(start 128.789684 -65.118234)
					(mid 129.170556 -64.829564)
					(end 128.881886 -65.210436)
				)
				(arc
					(start 128.79705 -65.295272)
					(mid 128.893747 -65.342157)
					(end 128.999996 -65.358264)
				)
				(xy 129.549652 -65.358264)
				(arc
					(start 129.789682 -65.118234)
					(mid 130.170554 -64.829564)
					(end 129.881884 -65.210436)
				)
				(xy 129.734056 -65.358264)
				(arc
					(start 129.999994 -65.358264)
					(mid 130.358134 -65.000124)
					(end 129.999994 -64.641984)
				)
			)
		)
	)
	(zone
		(layer "F.Cu")
		(hatch none 0.5)
		(connect_pads
			(clearance 0)
		)
		(min_thickness 0.25)
		(keepout
			(tracks allowed)
			(vias allowed)
			(pads allowed)
			(copperpour allowed)
			(footprints allowed)
		)
		(placement
			(enabled no)
			(sheetname "")
		)
		(fill
			(thermal_gap 0.5)
			(thermal_bridge_width 0.5)
			(island_removal_mode 0)
		)
		(polygon
			(pts
				(xy 141.919198 -62.590426) (xy 141.919198 -61.726826) (xy 142.249398 -61.726826) (xy 142.249398 -62.590426)
			)
		)
	)
	(zone
		(layer "F.Cu")
		(hatch none 0.5)
		(connect_pads
			(clearance 0)
		)
		(min_thickness 0.25)
		(keepout
			(tracks allowed)
			(vias allowed)
			(pads allowed)
			(copperpour allowed)
			(footprints allowed)
		)
		(placement
			(enabled no)
			(sheetname "")
		)
		(fill
			(thermal_gap 0.5)
			(thermal_bridge_width 0.5)
			(island_removal_mode 0)
		)
		(polygon
			(pts
				(xy 132.9182 -44.6024) (xy 132.9182 -44.2214) (xy 133.9342 -44.2214) (xy 133.9342 -44.6024)
			)
		)
	)
	(zone
		(net "VT235_VX")
		(layer "F.Cu")
		(hatch none 0.5)
		(connect_pads
			(clearance 0.5)
		)
		(min_thickness 0.25)
		(fill yes
			(thermal_gap 0.5)
			(thermal_bridge_width 0.5)
			(island_removal_mode 0)
		)
		(polygon
			(pts
				(xy 170.8404 -86.4108) (xy 170.6372 -86.614) (xy 170.6372 -90.5002) (xy 170.4848 -90.6526) (xy 168.91 -90.6526)
				(xy 168.8084 -90.7542) (xy 168.8084 -92.117926) (xy 169.806874 -93.1164) (xy 169.806874 -94.331282)
				(xy 169.933874 -94.458282) (xy 172.219874 -94.458282) (xy 173.382178 -93.295978) (xy 174.8028 -93.295978)
				(xy 175.0314 -93.067378) (xy 175.0314 -87.1728) (xy 174.2694 -86.4108)
			)
		)
		(polygon
			(pts
				(xy 174.8536 -92.3036) (xy 174.6504 -92.3036) (xy 174.6504 -92.5068) (xy 174.8536 -92.5068)
			)
		)
		(polygon
			(pts
				(xy 173.99 -92.3036) (xy 173.7868 -92.3036) (xy 173.7868 -92.5068) (xy 173.99 -92.5068)
			)
		)
	)
	(zone
		(layer "F.Cu")
		(hatch none 0.5)
		(connect_pads
			(clearance 0)
		)
		(min_thickness 0.25)
		(keepout
			(tracks not_allowed)
			(vias allowed)
			(pads allowed)
			(copperpour not_allowed)
			(footprints allowed)
		)
		(placement
			(enabled no)
			(sheetname "")
		)
		(fill
			(thermal_gap 0.5)
			(thermal_bridge_width 0.5)
			(island_removal_mode 0)
		)
		(polygon
			(pts
				(arc
					(start 166.58336 -35.200082)
					(mid 166.199947 -34.816288)
					(end 165.81628 -35.199828)
				)
				(xy 165.81628 -35.524948) (xy 165.831012 -35.524948) (xy 165.874954 -35.56889) (xy 165.874954 -35.569144)
				(arc
					(start 166.071804 -35.765994)
					(mid 166.388385 -36.188493)
					(end 165.965886 -35.871912)
				)
				(xy 165.81628 -35.722306)
				(arc
					(start 165.81628 -35.999928)
					(mid 166.19982 -36.383468)
					(end 166.58336 -35.999928)
				)
				(xy 166.58336 -35.674808) (xy 166.568882 -35.674808)
				(arc
					(start 166.327836 -35.433762)
					(mid 166.011255 -35.011263)
					(end 166.433754 -35.327844)
				)
				(xy 166.58336 -35.47745)
			)
		)
	)
	(zone
		(layer "F.Cu")
		(hatch none 0.5)
		(connect_pads
			(clearance 0)
		)
		(min_thickness 0.25)
		(keepout
			(tracks allowed)
			(vias allowed)
			(pads allowed)
			(copperpour allowed)
			(footprints allowed)
		)
		(placement
			(enabled no)
			(sheetname "")
		)
		(fill
			(thermal_gap 0.5)
			(thermal_bridge_width 0.5)
			(island_removal_mode 0)
		)
		(polygon
			(pts
				(xy 147.400518 -50.300128) (xy 147.19427 -51.164998) (xy 146.823684 -51.076606) (xy 147.029932 -50.211736)
			)
		)
	)
	(zone
		(net "GND")
		(layer "F.Cu")
		(hatch none 0.5)
		(connect_pads
			(clearance 0.5)
		)
		(min_thickness 0.25)
		(fill yes
			(thermal_gap 0.5)
			(thermal_bridge_width 0.5)
			(island_removal_mode 0)
		)
		(polygon
			(pts
				(xy 71.12 -29.0195) (xy 71.0946 -29.0449) (xy 71.0946 -33.9725) (xy 72.6567 -35.5346) (xy 72.6694 -35.5346)
				(xy 72.8218 -35.687) (xy 75.664822 -35.687) (xy 75.795886 -35.555936) (xy 75.795886 -33.074102)
				(xy 75.7809 -33.059116) (xy 75.7809 -32.0421) (xy 72.7583 -29.0195)
			)
		)
		(polygon
			(pts
				(xy 74.9808 -34.6964) (xy 74.7776 -34.6964) (xy 74.7776 -34.8996) (xy 74.9808 -34.8996)
			)
		)
	)
	(zone
		(net "GND")
		(layer "F.Cu")
		(hatch none 0.5)
		(connect_pads
			(clearance 0.5)
		)
		(min_thickness 0.25)
		(fill yes
			(thermal_gap 0.5)
			(thermal_bridge_width 0.5)
			(island_removal_mode 0)
		)
		(polygon
			(pts
				(xy 163.4998 -39.9034) (xy 163.322 -40.0812) (xy 157.734 -40.0812) (xy 157.5562 -40.259) (xy 157.058614 -40.259)
				(xy 156.439108 -40.878506) (xy 156.439108 -41.49852) (xy 156.121862 -41.815766) (xy 156.121862 -42.877486)
				(xy 155.837128 -43.16222) (xy 155.837128 -46.477428) (xy 157.0355 -47.6758) (xy 160.2232 -47.6758)
				(xy 160.967674 -46.931326) (xy 160.967674 -43.062652) (xy 161.307526 -42.7228) (xy 162.3568 -42.7228)
				(xy 162.8648 -42.2148) (xy 163.4744 -42.2148) (xy 163.576 -42.1132) (xy 163.576 -41.8846) (xy 163.4998 -41.8084)
				(xy 159.9438 -41.8084) (xy 159.7914 -41.9608) (xy 159.7914 -42.609262) (xy 160.270698 -43.08856)
				(xy 160.270698 -46.607476) (xy 160.116774 -46.7614) (xy 157.949138 -46.7614) (xy 156.388816 -45.201078)
				(xy 156.388816 -43.491404) (xy 157.3276 -42.55262) (xy 157.3276 -41.0464) (xy 157.861 -40.513) (xy 163.1442 -40.513)
				(xy 163.2204 -40.4368) (xy 164.1856 -40.4368) (xy 164.2364 -40.386) (xy 164.2364 -40.132) (xy 164.0078 -39.9034)
			)
		)
		(polygon
			(pts
				(xy 160.3756 -42.4942) (xy 160.1724 -42.4942) (xy 160.1724 -42.6974) (xy 160.3756 -42.6974)
			)
		)
		(polygon
			(pts
				(xy 156.8196 -42.4942) (xy 156.6164 -42.4942) (xy 156.6164 -42.6974) (xy 156.8196 -42.6974)
			)
		)
		(polygon
			(pts
				(xy 156.8196 -41.8846) (xy 156.6164 -41.8846) (xy 156.6164 -42.0878) (xy 156.8196 -42.0878)
			)
		)
	)
	(zone
		(layer "F.Cu")
		(hatch none 0.5)
		(connect_pads
			(clearance 0)
		)
		(min_thickness 0.25)
		(keepout
			(tracks allowed)
			(vias allowed)
			(pads allowed)
			(copperpour allowed)
			(footprints allowed)
		)
		(placement
			(enabled no)
			(sheetname "")
		)
		(fill
			(thermal_gap 0.5)
			(thermal_bridge_width 0.5)
			(island_removal_mode 0)
		)
		(polygon
			(pts
				(xy 149.915626 -37.828728) (xy 149.709378 -38.693598) (xy 149.338792 -38.605206) (xy 149.54504 -37.740336)
			)
		)
	)
	(zone
		(layer "F.Cu")
		(hatch none 0.5)
		(connect_pads
			(clearance 0)
		)
		(min_thickness 0.25)
		(keepout
			(tracks not_allowed)
			(vias allowed)
			(pads allowed)
			(copperpour not_allowed)
			(footprints allowed)
		)
		(placement
			(enabled no)
			(sheetname "")
		)
		(fill
			(thermal_gap 0.5)
			(thermal_bridge_width 0.5)
			(island_removal_mode 0)
		)
		(polygon
			(pts
				(arc
					(start 172.957998 -30.39999)
					(mid 172.599731 -30.04185)
					(end 172.241718 -30.400244)
				)
				(xy 172.241718 -30.607) (xy 172.3644 -30.729682) (xy 172.3644 -30.861) (xy 172.241972 -30.983428)
				(arc
					(start 172.241972 -31.199836)
					(mid 172.425445 -31.512749)
					(end 172.788072 -31.50489)
				)
				(arc
					(start 172.701966 -31.418784)
					(mid 172.429523 -31.029501)
					(end 172.818806 -31.301944)
				)
				(arc
					(start 172.904912 -31.38805)
					(mid 172.94466 -31.297653)
					(end 172.958252 -31.199836)
				)
				(xy 172.958252 -30.95879) (xy 172.958252 -30.879542)
				(arc
					(start 172.698664 -30.620208)
					(mid 172.429185 -30.229317)
					(end 172.820076 -30.498796)
				)
				(xy 172.957998 -30.636972) (xy 172.957998 -30.498796)
			)
		)
	)
	(zone
		(layer "F.Cu")
		(hatch none 0.5)
		(connect_pads
			(clearance 0)
		)
		(min_thickness 0.25)
		(keepout
			(tracks allowed)
			(vias allowed)
			(pads allowed)
			(copperpour allowed)
			(footprints allowed)
		)
		(placement
			(enabled no)
			(sheetname "")
		)
		(fill
			(thermal_gap 0.5)
			(thermal_bridge_width 0.5)
			(island_removal_mode 0)
		)
		(polygon
			(pts
				(xy 54.230524 -80.099154) (xy 54.230524 -78.693772) (xy 55.20309 -78.693772) (xy 55.20309 -80.099154)
			)
		)
	)
	(zone
		(net "GND")
		(layer "F.Cu")
		(hatch none 0.5)
		(connect_pads
			(clearance 0.5)
		)
		(min_thickness 0.25)
		(fill yes
			(thermal_gap 0.5)
			(thermal_bridge_width 0.5)
			(island_removal_mode 0)
		)
		(polygon
			(pts
				(xy 128.905 -105.791) (xy 128.143 -106.553) (xy 128.143 -114.935) (xy 128.397 -115.189) (xy 135.509 -115.189)
				(xy 136.271 -114.427) (xy 136.271 -106.736642) (xy 136.382252 -106.62539) (xy 136.382252 -105.901998)
				(xy 136.271254 -105.791)
			)
		)
		(polygon
			(pts
				(xy 135.8646 -106.4768) (xy 135.6614 -106.4768) (xy 135.6614 -106.68) (xy 135.8646 -106.68)
			)
		)
	)
	(zone
		(layer "F.Cu")
		(hatch none 0.5)
		(connect_pads
			(clearance 0)
		)
		(min_thickness 0.25)
		(keepout
			(tracks not_allowed)
			(vias allowed)
			(pads allowed)
			(copperpour not_allowed)
			(footprints allowed)
		)
		(placement
			(enabled no)
			(sheetname "")
		)
		(fill
			(thermal_gap 0.5)
			(thermal_bridge_width 0.5)
			(island_removal_mode 0)
		)
		(polygon
			(pts
				(arc
					(start 126.000256 -73.641966)
					(mid 125.893882 -73.658049)
					(end 125.797056 -73.704958)
				)
				(arc
					(start 125.881892 -73.789794)
					(mid 126.170562 -74.170666)
					(end 125.78969 -73.881996)
				)
				(arc
					(start 125.704854 -73.79716)
					(mid 125.682991 -74.166849)
					(end 126.000002 -74.358246)
				)
				(arc
					(start 127 -74.358246)
					(mid 127.35814 -74.000106)
					(end 127 -73.641966)
				)
				(xy 126.734062 -73.641966)
				(arc
					(start 126.88189 -73.789794)
					(mid 127.17056 -74.170666)
					(end 126.789688 -73.881996)
				)
				(xy 126.549658 -73.641966)
			)
		)
	)
	(zone
		(net "GND")
		(layer "F.Cu")
		(hatch none 0.5)
		(connect_pads
			(clearance 0.5)
		)
		(min_thickness 0.25)
		(fill yes
			(thermal_gap 0.5)
			(thermal_bridge_width 0.5)
			(island_removal_mode 0)
		)
		(polygon
			(pts
				(xy 48.628554 -40.486076) (xy 48.3616 -40.75303) (xy 48.3616 -49.101248) (xy 47.424848 -50.038)
				(xy 35.2044 -50.038) (xy 35.052 -50.1904) (xy 35.052 -53.1876) (xy 35.74923 -53.88483) (xy 51.243992 -53.88483)
				(xy 51.382422 -53.7464) (xy 51.382422 -52.907946) (xy 51.7906 -52.499768) (xy 51.7906 -40.716454)
				(xy 51.560222 -40.486076)
			)
		)
		(polygon
			(pts
				(xy 50.874676 -53.53939) (xy 50.671476 -53.53939) (xy 50.671476 -53.74259) (xy 50.874676 -53.74259)
			)
		)
		(polygon
			(pts
				(xy 50.874676 -52.92979) (xy 50.671476 -52.92979) (xy 50.671476 -53.13299) (xy 50.874676 -53.13299)
			)
		)
		(polygon
			(pts
				(xy 45.8724 -50.8254) (xy 45.6692 -50.8254) (xy 45.6692 -51.0286) (xy 45.8724 -51.0286)
			)
		)
		(polygon
			(pts
				(xy 45.0088 -50.8254) (xy 44.8056 -50.8254) (xy 44.8056 -51.0286) (xy 45.0088 -51.0286)
			)
		)
	)
	(zone
		(net "P12V_STBY_SCC")
		(layer "F.Cu")
		(hatch none 0.5)
		(connect_pads
			(clearance 0.5)
		)
		(min_thickness 0.25)
		(fill yes
			(thermal_gap 0.5)
			(thermal_bridge_width 0.5)
			(island_removal_mode 0)
		)
		(polygon
			(pts
				(xy 31.9786 -41.402) (xy 31.9659 -41.4147) (xy 31.2801 -41.4147) (xy 30.607 -42.0878) (xy 30.607 -47.4345)
				(xy 30.8864 -47.7139) (xy 34.3535 -47.7139) (xy 34.6202 -47.4472) (xy 34.6202 -41.6052) (xy 34.417 -41.402)
			)
		)
	)
	(zone
		(layer "F.Cu")
		(hatch none 0.5)
		(connect_pads
			(clearance 0)
		)
		(min_thickness 0.25)
		(keepout
			(tracks allowed)
			(vias allowed)
			(pads allowed)
			(copperpour allowed)
			(footprints allowed)
		)
		(placement
			(enabled no)
			(sheetname "")
		)
		(fill
			(thermal_gap 0.5)
			(thermal_bridge_width 0.5)
			(island_removal_mode 0)
		)
		(polygon
			(pts
				(xy 200.19137 -95.543878) (xy 200.19137 -96.661478) (xy 197.5866 -96.661478) (xy 197.5866 -95.543878)
			)
		)
	)
	(zone
		(net "GND")
		(layer "F.Cu")
		(hatch none 0.5)
		(connect_pads
			(clearance 0.5)
		)
		(min_thickness 0.25)
		(fill yes
			(thermal_gap 0.5)
			(thermal_bridge_width 0.5)
			(island_removal_mode 0)
		)
		(polygon
			(pts
				(xy 73.025 -41.275) (xy 72.263 -42.037) (xy 72.263 -46.355) (xy 72.39 -46.482) (xy 75.608434 -46.482)
				(xy 75.8952 -46.195234) (xy 75.8952 -41.4528) (xy 75.7174 -41.275)
			)
		)
		(polygon
			(pts
				(xy 74.9808 -45.3136) (xy 74.7776 -45.3136) (xy 74.7776 -45.5168) (xy 74.9808 -45.5168)
			)
		)
		(polygon
			(pts
				(xy 75.1078 -42.1894) (xy 74.9046 -42.1894) (xy 74.9046 -42.3926) (xy 75.1078 -42.3926)
			)
		)
	)
	(zone
		(layer "F.Cu")
		(hatch none 0.5)
		(connect_pads
			(clearance 0)
		)
		(min_thickness 0.25)
		(keepout
			(tracks not_allowed)
			(vias allowed)
			(pads allowed)
			(copperpour not_allowed)
			(footprints allowed)
		)
		(placement
			(enabled no)
			(sheetname "")
		)
		(fill
			(thermal_gap 0.5)
			(thermal_bridge_width 0.5)
			(island_removal_mode 0)
		)
		(polygon
			(pts
				(arc
					(start 117.35816 -55.000144)
					(mid 117.00002 -54.642004)
					(end 116.64188 -55.000144)
				)
				(xy 116.64188 -55.266082)
				(arc
					(start 116.789708 -55.118254)
					(mid 117.17058 -54.829584)
					(end 116.88191 -55.210456)
				)
				(xy 116.64188 -55.450486)
				(arc
					(start 116.64188 -55.999888)
					(mid 116.657963 -56.106262)
					(end 116.704872 -56.203088)
				)
				(arc
					(start 116.789708 -56.118252)
					(mid 117.17058 -55.829582)
					(end 116.88191 -56.210454)
				)
				(arc
					(start 116.797074 -56.29529)
					(mid 117.166763 -56.317153)
					(end 117.35816 -56.000142)
				)
			)
		)
	)
	(zone
		(layer "F.Cu")
		(hatch none 0.5)
		(connect_pads
			(clearance 0)
		)
		(min_thickness 0.25)
		(keepout
			(tracks not_allowed)
			(vias allowed)
			(pads allowed)
			(copperpour not_allowed)
			(footprints allowed)
		)
		(placement
			(enabled no)
			(sheetname "")
		)
		(fill
			(thermal_gap 0.5)
			(thermal_bridge_width 0.5)
			(island_removal_mode 0)
		)
		(polygon
			(pts
				(arc
					(start 110.358174 -51.000152)
					(mid 110.000034 -50.642012)
					(end 109.641894 -51.000152)
				)
				(xy 109.641894 -51.308) (xy 109.7534 -51.419506) (xy 109.7534 -51.602894) (xy 109.641894 -51.7144)
				(arc
					(start 109.641894 -51.999896)
					(mid 109.833202 -52.317059)
					(end 110.20298 -52.295298)
				)
				(arc
					(start 110.118144 -52.210462)
					(mid 109.829474 -51.82959)
					(end 110.210346 -52.11826)
				)
				(arc
					(start 110.295182 -52.203096)
					(mid 110.342067 -52.106399)
					(end 110.358174 -52.00015)
				)
				(xy 110.358174 -51.450494)
				(arc
					(start 110.118144 -51.210464)
					(mid 109.829474 -50.829592)
					(end 110.210346 -51.118262)
				)
				(xy 110.358174 -51.26609)
			)
		)
	)
	(zone
		(layer "F.Cu")
		(hatch none 0.5)
		(connect_pads
			(clearance 0)
		)
		(min_thickness 0.25)
		(keepout
			(tracks not_allowed)
			(vias allowed)
			(pads allowed)
			(copperpour not_allowed)
			(footprints allowed)
		)
		(placement
			(enabled no)
			(sheetname "")
		)
		(fill
			(thermal_gap 0.5)
			(thermal_bridge_width 0.5)
			(island_removal_mode 0)
		)
		(polygon
			(pts
				(arc
					(start 175.358044 -30.39999)
					(mid 174.999777 -30.04185)
					(end 174.641764 -30.400244)
				)
				(xy 174.641764 -30.607) (xy 174.7774 -30.742636) (xy 174.7774 -30.861) (xy 174.642018 -30.996382)
				(arc
					(start 174.642018 -31.199836)
					(mid 174.825491 -31.512749)
					(end 175.188118 -31.50489)
				)
				(arc
					(start 175.102012 -31.418784)
					(mid 174.829569 -31.029501)
					(end 175.218852 -31.301944)
				)
				(arc
					(start 175.304958 -31.38805)
					(mid 175.344706 -31.297653)
					(end 175.358298 -31.199836)
				)
				(xy 175.358298 -31.049976) (xy 175.358298 -30.95879) (xy 175.358298 -30.87497)
				(arc
					(start 175.101758 -30.618684)
					(mid 174.829315 -30.229401)
					(end 175.218598 -30.501844)
				)
				(xy 175.358044 -30.641544) (xy 175.358044 -30.501844)
			)
		)
	)
	(zone
		(layer "F.Cu")
		(hatch none 0.5)
		(connect_pads
			(clearance 0)
		)
		(min_thickness 0.25)
		(keepout
			(tracks not_allowed)
			(vias allowed)
			(pads allowed)
			(copperpour not_allowed)
			(footprints allowed)
		)
		(placement
			(enabled no)
			(sheetname "")
		)
		(fill
			(thermal_gap 0.5)
			(thermal_bridge_width 0.5)
			(island_removal_mode 0)
		)
		(polygon
			(pts
				(arc
					(start 107.35818 -52.00015)
					(mid 107.00004 -51.64201)
					(end 106.6419 -52.00015)
				)
				(arc
					(start 106.6419 -52.999894)
					(mid 106.833208 -53.317057)
					(end 107.202986 -53.295296)
				)
				(arc
					(start 107.11815 -53.21046)
					(mid 106.82948 -52.829588)
					(end 107.210352 -53.118258)
				)
				(arc
					(start 107.295188 -53.203094)
					(mid 107.342073 -53.106397)
					(end 107.35818 -53.000148)
				)
				(xy 107.35818 -52.450492)
				(arc
					(start 107.11815 -52.210462)
					(mid 106.82948 -51.82959)
					(end 107.210352 -52.11826)
				)
				(xy 107.35818 -52.266088)
			)
		)
	)
	(zone
		(layer "F.Cu")
		(hatch none 0.5)
		(connect_pads
			(clearance 0)
		)
		(min_thickness 0.25)
		(keepout
			(tracks allowed)
			(vias allowed)
			(pads allowed)
			(copperpour allowed)
			(footprints allowed)
		)
		(placement
			(enabled no)
			(sheetname "")
		)
		(fill
			(thermal_gap 0.5)
			(thermal_bridge_width 0.5)
			(island_removal_mode 0)
		)
		(polygon
			(pts
				(xy 152.4 -77.216) (xy 152.4 -74.8792) (xy 154.4066 -74.8792) (xy 154.4066 -77.216)
			)
		)
	)
	(zone
		(net "GND")
		(layer "F.Cu")
		(hatch none 0.5)
		(connect_pads
			(clearance 0.5)
		)
		(min_thickness 0.25)
		(fill yes
			(thermal_gap 0.5)
			(thermal_bridge_width 0.5)
			(island_removal_mode 0)
		)
		(polygon
			(pts
				(xy 38.0746 -40.386) (xy 37.8206 -40.64) (xy 37.8206 -42.926) (xy 37.9476 -43.053) (xy 43.9166 -43.053)
				(xy 44.0436 -42.926) (xy 44.0436 -40.513) (xy 43.9166 -40.386)
			)
		)
	)
	(zone
		(net "P12V_STBY_SCC")
		(layer "F.Cu")
		(hatch none 0.5)
		(connect_pads
			(clearance 0.5)
		)
		(min_thickness 0.25)
		(fill yes
			(thermal_gap 0.5)
			(thermal_bridge_width 0.5)
			(island_removal_mode 0)
		)
		(polygon
			(pts
				(xy 50.44821 -88.381332) (xy 50.434748 -88.39454) (xy 50.12436 -88.39454) (xy 49.920652 -88.598248)
				(xy 49.920652 -90.586306) (xy 50.165 -90.830654) (xy 62.640972 -90.830654) (xy 62.670944 -90.860626)
				(xy 63.857124 -90.860626) (xy 64.292734 -91.296236) (xy 64.84112 -91.296236) (xy 65.050924 -91.086432)
				(xy 65.050924 -89.537794) (xy 63.894462 -88.381332)
			)
		)
		(polygon
			(pts
				(xy 62.5983 -89.4715) (xy 62.3951 -89.4715) (xy 62.3951 -89.6747) (xy 62.5983 -89.6747)
			)
		)
		(polygon
			(pts
				(xy 61.2013 -89.4715) (xy 60.9981 -89.4715) (xy 60.9981 -89.6747) (xy 61.2013 -89.6747)
			)
		)
	)
	(zone
		(layer "F.Cu")
		(hatch none 0.5)
		(connect_pads
			(clearance 0)
		)
		(min_thickness 0.25)
		(keepout
			(tracks allowed)
			(vias allowed)
			(pads allowed)
			(copperpour allowed)
			(footprints not_allowed)
		)
		(placement
			(enabled no)
			(sheetname "")
		)
		(fill
			(thermal_gap 0.5)
			(thermal_bridge_width 0.5)
			(island_removal_mode 0)
		)
		(polygon
			(pts
				(xy 189.999874 -125.000004) (xy 189.999874 -105.000044) (xy 205.000098 -105.000044)
				(arc
					(start 205.000098 -123.63577)
					(mid 191.499908 -131.430014)
					(end 205.000098 -139.224258)
				)
				(xy 205.000098 -144.999964)
				(arc
					(start 127.00254 -144.999964)
					(mid 125.588329 -144.414179)
					(end 125.002544 -142.999968)
				)
				(arc
					(start 125.002544 -132.263642)
					(mid 123.807045 -129.019301)
					(end 120.79224 -127.32639)
				)
				(xy 112.499902 -126.000002) (xy 97.499932 -126.000002)
				(arc
					(start 89.212674 -127.325628)
					(mid 86.197998 -129.018598)
					(end 85.002624 -132.26288)
				)
				(arc
					(start 85.002624 -142.999968)
					(mid 84.416749 -144.414269)
					(end 83.002374 -144.999964)
				)
				(xy 4.99999 -144.999964)
				(arc
					(start 4.99999 -139.224258)
					(mid 18.50018 -131.430014)
					(end 4.99999 -123.63577)
				)
				(xy 4.99999 -105.000044) (xy 19.99996 -105.000044) (xy 19.99996 -125.000004) (xy 85.002624 -125.000004)
				(xy 85.002624 -119.000016) (xy 125.002544 -119.000016) (xy 125.002544 -125.000004)
			)
		)
	)
	(zone
		(layer "F.Cu")
		(hatch none 0.5)
		(connect_pads
			(clearance 0)
		)
		(min_thickness 0.25)
		(keepout
			(tracks not_allowed)
			(vias allowed)
			(pads allowed)
			(copperpour not_allowed)
			(footprints allowed)
		)
		(placement
			(enabled no)
			(sheetname "")
		)
		(fill
			(thermal_gap 0.5)
			(thermal_bridge_width 0.5)
			(island_removal_mode 0)
		)
		(polygon
			(pts
				(arc
					(start 124.358146 -52.00015)
					(mid 124.000006 -51.64201)
					(end 123.641866 -52.00015)
				)
				(xy 123.641866 -52.266088)
				(arc
					(start 123.789694 -52.11826)
					(mid 124.170566 -51.82959)
					(end 123.881896 -52.210462)
				)
				(xy 123.641866 -52.450492)
				(arc
					(start 123.641866 -52.999894)
					(mid 123.657949 -53.106268)
					(end 123.704858 -53.203094)
				)
				(arc
					(start 123.789694 -53.118258)
					(mid 124.170566 -52.829588)
					(end 123.881896 -53.21046)
				)
				(arc
					(start 123.79706 -53.295296)
					(mid 124.166749 -53.317159)
					(end 124.358146 -53.000148)
				)
				(xy 124.358146 -52.705) (xy 124.2568 -52.603654) (xy 124.2568 -52.4002) (xy 124.358146 -52.298854)
			)
		)
	)
	(zone
		(layer "F.Cu")
		(hatch none 0.5)
		(connect_pads
			(clearance 0)
		)
		(min_thickness 0.25)
		(keepout
			(tracks not_allowed)
			(vias allowed)
			(pads allowed)
			(copperpour not_allowed)
			(footprints allowed)
		)
		(placement
			(enabled no)
			(sheetname "")
		)
		(fill
			(thermal_gap 0.5)
			(thermal_bridge_width 0.5)
			(island_removal_mode 0)
		)
		(polygon
			(pts
				(arc
					(start 121.358152 -51.000152)
					(mid 121.000012 -50.642012)
					(end 120.641872 -51.000152)
				)
				(xy 120.641872 -51.26609)
				(arc
					(start 120.7897 -51.118262)
					(mid 121.170572 -50.829592)
					(end 120.881902 -51.210464)
				)
				(xy 120.641872 -51.450494)
				(arc
					(start 120.641872 -51.999896)
					(mid 120.657955 -52.10627)
					(end 120.704864 -52.203096)
				)
				(arc
					(start 120.7897 -52.11826)
					(mid 121.170572 -51.82959)
					(end 120.881902 -52.210462)
				)
				(arc
					(start 120.797066 -52.295298)
					(mid 121.166755 -52.317161)
					(end 121.358152 -52.00015)
				)
				(xy 121.358152 -51.689) (xy 121.2596 -51.590448) (xy 121.2596 -51.406552) (xy 121.358152 -51.308)
			)
		)
	)
	(zone
		(layer "F.Cu")
		(hatch none 0.5)
		(connect_pads
			(clearance 0)
		)
		(min_thickness 0.25)
		(keepout
			(tracks not_allowed)
			(vias allowed)
			(pads allowed)
			(copperpour not_allowed)
			(footprints allowed)
		)
		(placement
			(enabled no)
			(sheetname "")
		)
		(fill
			(thermal_gap 0.5)
			(thermal_bridge_width 0.5)
			(island_removal_mode 0)
		)
		(polygon
			(pts
				(arc
					(start 126.000256 -72.641968)
					(mid 125.893882 -72.658051)
					(end 125.797056 -72.70496)
				)
				(arc
					(start 125.881892 -72.789796)
					(mid 126.170562 -73.170668)
					(end 125.78969 -72.881998)
				)
				(arc
					(start 125.704854 -72.797162)
					(mid 125.682991 -73.166851)
					(end 126.000002 -73.358248)
				)
				(arc
					(start 127 -73.358248)
					(mid 127.35814 -73.000108)
					(end 127 -72.641968)
				)
				(xy 126.734062 -72.641968)
				(arc
					(start 126.88189 -72.789796)
					(mid 127.17056 -73.170668)
					(end 126.789688 -72.881998)
				)
				(xy 126.549658 -72.641968)
			)
		)
	)
	(zone
		(layer "F.Cu")
		(hatch none 0.5)
		(connect_pads
			(clearance 0)
		)
		(min_thickness 0.25)
		(keepout
			(tracks not_allowed)
			(vias allowed)
			(pads allowed)
			(copperpour not_allowed)
			(footprints allowed)
		)
		(placement
			(enabled no)
			(sheetname "")
		)
		(fill
			(thermal_gap 0.5)
			(thermal_bridge_width 0.5)
			(island_removal_mode 0)
		)
		(polygon
			(pts
				(arc
					(start 119.358156 -51.000152)
					(mid 119.000016 -50.642012)
					(end 118.641876 -51.000152)
				)
				(xy 118.641876 -51.26609)
				(arc
					(start 118.789704 -51.118262)
					(mid 119.170576 -50.829592)
					(end 118.881906 -51.210464)
				)
				(xy 118.641876 -51.450494)
				(arc
					(start 118.641876 -51.999896)
					(mid 118.657959 -52.10627)
					(end 118.704868 -52.203096)
				)
				(arc
					(start 118.789704 -52.11826)
					(mid 119.170576 -51.82959)
					(end 118.881906 -52.210462)
				)
				(arc
					(start 118.79707 -52.295298)
					(mid 119.166759 -52.317161)
					(end 119.358156 -52.00015)
				)
				(xy 119.358156 -51.689) (xy 119.253 -51.583844) (xy 119.253 -51.4096) (xy 119.358156 -51.304444)
			)
		)
	)
	(zone
		(layer "F.Cu")
		(hatch none 0.5)
		(connect_pads
			(clearance 0)
		)
		(min_thickness 0.25)
		(keepout
			(tracks not_allowed)
			(vias allowed)
			(pads allowed)
			(copperpour not_allowed)
			(footprints allowed)
		)
		(placement
			(enabled no)
			(sheetname "")
		)
		(fill
			(thermal_gap 0.5)
			(thermal_bridge_width 0.5)
			(island_removal_mode 0)
		)
		(polygon
			(pts
				(arc
					(start 122.35815 -55.000144)
					(mid 122.00001 -54.642004)
					(end 121.64187 -55.000144)
				)
				(xy 121.64187 -55.266082)
				(arc
					(start 121.789698 -55.118254)
					(mid 122.17057 -54.829584)
					(end 121.8819 -55.210456)
				)
				(xy 121.64187 -55.450486)
				(arc
					(start 121.64187 -55.999888)
					(mid 121.657953 -56.106262)
					(end 121.704862 -56.203088)
				)
				(arc
					(start 121.789698 -56.118252)
					(mid 122.17057 -55.829582)
					(end 121.8819 -56.210454)
				)
				(arc
					(start 121.797064 -56.29529)
					(mid 122.166753 -56.317153)
					(end 122.35815 -56.000142)
				)
			)
		)
	)
	(zone
		(layer "F.Cu")
		(hatch none 0.5)
		(connect_pads
			(clearance 0)
		)
		(min_thickness 0.25)
		(keepout
			(tracks allowed)
			(vias allowed)
			(pads allowed)
			(copperpour allowed)
			(footprints allowed)
		)
		(placement
			(enabled no)
			(sheetname "")
		)
		(fill
			(thermal_gap 0.5)
			(thermal_bridge_width 0.5)
			(island_removal_mode 0)
		)
		(polygon
			(pts
				(xy 155.2194 -99.1108) (xy 155.2194 -97.79) (xy 157.1498 -97.79) (xy 157.1498 -99.1108)
			)
		)
	)
	(zone
		(layer "F.Cu")
		(hatch none 0.5)
		(connect_pads
			(clearance 0)
		)
		(min_thickness 0.25)
		(keepout
			(tracks not_allowed)
			(vias allowed)
			(pads allowed)
			(copperpour not_allowed)
			(footprints allowed)
		)
		(placement
			(enabled no)
			(sheetname "")
		)
		(fill
			(thermal_gap 0.5)
			(thermal_bridge_width 0.5)
			(island_removal_mode 0)
		)
		(polygon
			(pts
				(arc
					(start 103.358188 -52.00015)
					(mid 103.000048 -51.64201)
					(end 102.641908 -52.00015)
				)
				(arc
					(start 102.641908 -52.999894)
					(mid 102.833216 -53.317057)
					(end 103.202994 -53.295296)
				)
				(arc
					(start 103.118158 -53.21046)
					(mid 102.829488 -52.829588)
					(end 103.21036 -53.118258)
				)
				(arc
					(start 103.295196 -53.203094)
					(mid 103.342081 -53.106397)
					(end 103.358188 -53.000148)
				)
				(xy 103.358188 -52.450492)
				(arc
					(start 103.118158 -52.210462)
					(mid 102.829488 -51.82959)
					(end 103.21036 -52.11826)
				)
				(xy 103.358188 -52.266088)
			)
		)
	)
	(zone
		(layer "F.Cu")
		(hatch none 0.5)
		(connect_pads
			(clearance 0)
		)
		(min_thickness 0.25)
		(keepout
			(tracks not_allowed)
			(vias allowed)
			(pads allowed)
			(copperpour not_allowed)
			(footprints allowed)
		)
		(placement
			(enabled no)
			(sheetname "")
		)
		(fill
			(thermal_gap 0.5)
			(thermal_bridge_width 0.5)
			(island_removal_mode 0)
		)
		(polygon
			(pts
				(arc
					(start 166.58336 -32.80029)
					(mid 166.199947 -32.416496)
					(end 165.81628 -32.800036)
				)
				(xy 165.81628 -33.124902) (xy 165.831012 -33.124902) (xy 165.874954 -33.168844) (xy 165.874954 -33.169098)
				(arc
					(start 166.071804 -33.365948)
					(mid 166.388385 -33.788447)
					(end 165.965886 -33.471866)
				)
				(xy 165.81628 -33.32226)
				(arc
					(start 165.81628 -33.599882)
					(mid 166.19982 -33.983422)
					(end 166.58336 -33.599882)
				)
				(xy 166.58336 -33.274762) (xy 166.568628 -33.274762)
				(arc
					(start 166.327836 -33.03397)
					(mid 166.011255 -32.611471)
					(end 166.433754 -32.928052)
				)
				(xy 166.58336 -33.077658)
			)
		)
	)
	(zone
		(net "PCE_AVDD")
		(layer "F.Cu")
		(hatch none 0.5)
		(connect_pads
			(clearance 0.5)
		)
		(min_thickness 0.25)
		(fill yes
			(thermal_gap 0.5)
			(thermal_bridge_width 0.5)
			(island_removal_mode 0)
		)
		(polygon
			(pts
				(xy 171.6786 -76.2) (xy 170.9928 -76.8858) (xy 170.9928 -81.2292) (xy 172.0977 -82.3341) (xy 172.5549 -82.3341)
				(xy 172.593 -82.3722) (xy 175.4886 -82.3722) (xy 175.641 -82.2198) (xy 175.641 -76.4286) (xy 175.4124 -76.2)
			)
		)
		(polygon
			(pts
				(xy 173.736 -81.2038) (xy 173.5328 -81.2038) (xy 173.5328 -81.407) (xy 173.736 -81.407)
			)
		)
		(polygon
			(pts
				(xy 172.8724 -81.2038) (xy 172.6692 -81.2038) (xy 172.6692 -81.407) (xy 172.8724 -81.407)
			)
		)
		(polygon
			(pts
				(xy 174.752 -78.1304) (xy 174.5488 -78.1304) (xy 174.5488 -78.3336) (xy 174.752 -78.3336)
			)
		)
		(polygon
			(pts
				(xy 174.752 -77.2668) (xy 174.5488 -77.2668) (xy 174.5488 -77.47) (xy 174.752 -77.47)
			)
		)
		(polygon
			(pts
				(xy 175.133 -76.9874) (xy 174.9298 -76.9874) (xy 174.9298 -77.1906) (xy 175.133 -77.1906)
			)
		)
	)
	(zone
		(layer "F.Cu")
		(hatch none 0.5)
		(connect_pads
			(clearance 0)
		)
		(min_thickness 0.25)
		(keepout
			(tracks allowed)
			(vias allowed)
			(pads allowed)
			(copperpour allowed)
			(footprints not_allowed)
		)
		(placement
			(enabled no)
			(sheetname "")
		)
		(fill
			(thermal_gap 0.5)
			(thermal_bridge_width 0.5)
			(island_removal_mode 0)
		)
		(polygon
			(pts
				(arc
					(start 154.500072 -29.500068)
					(mid 151.500078 -32.500062)
					(end 148.500084 -29.500068)
				)
				(arc
					(start 148.500084 -29.500068)
					(mid 151.500078 -26.500074)
					(end 154.500072 -29.500068)
				)
			)
		)
	)
	(zone
		(net "P1V8_E")
		(layer "F.Cu")
		(hatch none 0.5)
		(connect_pads
			(clearance 0.5)
		)
		(min_thickness 0.25)
		(fill yes
			(thermal_gap 0.5)
			(thermal_bridge_width 0.5)
			(island_removal_mode 0)
		)
		(polygon
			(pts
				(xy 165.2651 -4.724654) (xy 164.9984 -4.991354) (xy 164.9984 -7.203186) (xy 165.149022 -7.353808)
				(xy 166.001192 -7.353808) (xy 166.2049 -7.1501) (xy 166.2049 -6.8326) (xy 166.4335 -6.604) (xy 167.9702 -6.604)
				(xy 168.1226 -6.4516) (xy 168.1226 -4.8514) (xy 167.995854 -4.724654)
			)
		)
	)
	(zone
		(layer "F.Cu")
		(hatch none 0.5)
		(connect_pads
			(clearance 0)
		)
		(min_thickness 0.25)
		(keepout
			(tracks not_allowed)
			(vias allowed)
			(pads allowed)
			(copperpour not_allowed)
			(footprints allowed)
		)
		(placement
			(enabled no)
			(sheetname "")
		)
		(fill
			(thermal_gap 0.5)
			(thermal_bridge_width 0.5)
			(island_removal_mode 0)
		)
		(polygon
			(pts
				(arc
					(start 122.35815 -52.00015)
					(mid 122.00001 -51.64201)
					(end 121.64187 -52.00015)
				)
				(xy 121.64187 -52.266088)
				(arc
					(start 121.789698 -52.11826)
					(mid 122.17057 -51.82959)
					(end 121.8819 -52.210462)
				)
				(xy 121.64187 -52.450492)
				(arc
					(start 121.64187 -52.999894)
					(mid 121.657953 -53.106268)
					(end 121.704862 -53.203094)
				)
				(arc
					(start 121.789698 -53.118258)
					(mid 122.17057 -52.829588)
					(end 121.8819 -53.21046)
				)
				(arc
					(start 121.797064 -53.295296)
					(mid 122.166753 -53.317159)
					(end 122.35815 -53.000148)
				)
			)
		)
	)
	(zone
		(layers "F.Cu" "B.Cu" "In1.Cu" "In2.Cu" "In3.Cu" "In4.Cu" "In5.Cu" "In6.Cu")
		(name "Package Keepin")
		(hatch none 0.5)
		(connect_pads
			(clearance 0)
		)
		(min_thickness 0.25)
		(keepout
			(tracks allowed)
			(vias allowed)
			(pads allowed)
			(copperpour allowed)
			(footprints allowed)
		)
		(placement
			(enabled no)
			(sheetname "")
		)
		(fill
			(thermal_gap 0.5)
			(thermal_bridge_width 0.5)
			(island_removal_mode 0)
		)
		(polygon
			(pts
				(xy 5.0038 -5.0038) (xy 5.0038 -139.996164) (xy 79.998824 -139.996164)
				(arc
					(start 79.998824 -132.262626)
					(mid 82.390684 -125.771783)
					(end 88.422226 -122.384566)
				)
				(xy 97.102168 -120.996202) (xy 112.897666 -120.996202)
				(arc
					(start 121.582688 -122.385328)
					(mid 127.614564 -125.772478)
					(end 130.006344 -132.263642)
				)
				(xy 130.006344 -139.996164) (xy 204.996288 -139.996164) (xy 204.996288 -5.0038)
			)
		)
	)
	(zone
		(layers "F.Cu" "B.Cu" "In1.Cu" "In2.Cu" "In3.Cu" "In4.Cu" "In5.Cu" "In6.Cu")
		(hatch none 0.5)
		(connect_pads
			(clearance 0)
		)
		(min_thickness 0.25)
		(keepout
			(tracks not_allowed)
			(vias allowed)
			(pads allowed)
			(copperpour not_allowed)
			(footprints allowed)
		)
		(placement
			(enabled no)
			(sheetname "")
		)
		(fill
			(thermal_gap 0.5)
			(thermal_bridge_width 0.5)
			(island_removal_mode 0)
		)
		(polygon
			(pts
				(arc
					(start 139.750038 -134.999984)
					(mid 130.24993 -134.999984)
					(end 139.750038 -134.999984)
				)
			)
		)
	)
	(zone
		(layers "F.Cu" "B.Cu" "In1.Cu" "In2.Cu" "In3.Cu" "In4.Cu" "In5.Cu" "In6.Cu")
		(hatch none 0.5)
		(connect_pads
			(clearance 0)
		)
		(min_thickness 0.25)
		(keepout
			(tracks not_allowed)
			(vias allowed)
			(pads allowed)
			(copperpour not_allowed)
			(footprints allowed)
		)
		(placement
			(enabled no)
			(sheetname "")
		)
		(fill
			(thermal_gap 0.5)
			(thermal_bridge_width 0.5)
			(island_removal_mode 0)
		)
		(polygon
			(pts
				(arc
					(start 137.999978 -94.309946)
					(mid 131.99999 -94.309946)
					(end 137.999978 -94.309946)
				)
			)
		)
	)
	(zone
		(layers "F.Cu" "B.Cu" "In1.Cu" "In2.Cu" "In3.Cu" "In4.Cu" "In5.Cu" "In6.Cu")
		(hatch none 0.5)
		(connect_pads
			(clearance 0)
		)
		(min_thickness 0.25)
		(keepout
			(tracks not_allowed)
			(vias allowed)
			(pads allowed)
			(copperpour not_allowed)
			(footprints allowed)
		)
		(placement
			(enabled no)
			(sheetname "")
		)
		(fill
			(thermal_gap 0.5)
			(thermal_bridge_width 0.5)
			(island_removal_mode 0)
		)
		(polygon
			(pts
				(arc
					(start 201.499978 -50.500026)
					(mid 195.49999 -50.500026)
					(end 201.499978 -50.500026)
				)
			)
		)
	)
	(zone
		(layers "F.Cu" "B.Cu" "In1.Cu" "In2.Cu" "In3.Cu" "In4.Cu" "In5.Cu" "In6.Cu")
		(hatch none 0.5)
		(connect_pads
			(clearance 0)
		)
		(min_thickness 0.25)
		(keepout
			(tracks not_allowed)
			(vias allowed)
			(pads allowed)
			(copperpour not_allowed)
			(footprints allowed)
		)
		(placement
			(enabled no)
			(sheetname "")
		)
		(fill
			(thermal_gap 0.5)
			(thermal_bridge_width 0.5)
			(island_removal_mode 0)
		)
		(polygon
			(pts
				(arc
					(start 32.980884 -9.924796)
					(mid 25.980644 -9.924796)
					(end 32.980884 -9.924796)
				)
			)
		)
	)
	(zone
		(layers "F.Cu" "B.Cu" "In1.Cu" "In2.Cu" "In3.Cu" "In4.Cu" "In5.Cu" "In6.Cu")
		(name "Route Keepin")
		(hatch none 0.5)
		(connect_pads
			(clearance 0)
		)
		(min_thickness 0.25)
		(keepout
			(tracks allowed)
			(vias allowed)
			(pads allowed)
			(copperpour allowed)
			(footprints allowed)
		)
		(placement
			(enabled no)
			(sheetname "")
		)
		(fill
			(thermal_gap 0.5)
			(thermal_bridge_width 0.5)
			(island_removal_mode 0)
		)
		(polygon
			(pts
				(arc
					(start 1.999996 -0.762)
					(mid 1.124601 -1.124601)
					(end 0.762 -1.999996)
				)
				(arc
					(start 0.762 -142.999968)
					(mid 1.124601 -143.875363)
					(end 1.999996 -144.237964)
				)
				(arc
					(start 83.002882 -144.237964)
					(mid 83.878113 -143.875274)
					(end 84.240624 -142.999968)
				)
				(arc
					(start 84.240624 -132.262626)
					(mid 85.618298 -128.524123)
					(end 89.092278 -126.57328)
				)
				(xy 97.43948 -125.238002) (xy 112.560354 -125.238002)
				(arc
					(start 120.912636 -126.574042)
					(mid 124.386823 -128.524928)
					(end 125.764544 -132.263642)
				)
				(arc
					(start 125.764544 -142.999968)
					(mid 126.127145 -143.875363)
					(end 127.00254 -144.237964)
				)
				(arc
					(start 208.000092 -144.237964)
					(mid 208.875487 -143.875363)
					(end 209.238088 -142.999968)
				)
				(arc
					(start 209.238088 -1.999996)
					(mid 208.875487 -1.124601)
					(end 208.000092 -0.762)
				)
			)
		)
	)
	(zone
		(layers "F.Cu" "B.Cu" "In1.Cu" "In2.Cu" "In3.Cu" "In4.Cu" "In5.Cu" "In6.Cu")
		(hatch none 0.5)
		(connect_pads
			(clearance 0)
		)
		(min_thickness 0.25)
		(keepout
			(tracks not_allowed)
			(vias allowed)
			(pads allowed)
			(copperpour not_allowed)
			(footprints allowed)
		)
		(placement
			(enabled no)
			(sheetname "")
		)
		(fill
			(thermal_gap 0.5)
			(thermal_bridge_width 0.5)
			(island_removal_mode 0)
		)
		(polygon
			(pts
				(arc
					(start 154.500072 -29.500068)
					(mid 148.500084 -29.500068)
					(end 154.500072 -29.500068)
				)
			)
		)
	)
	(zone
		(layers "F.Cu" "B.Cu" "In1.Cu" "In2.Cu" "In3.Cu" "In4.Cu" "In5.Cu" "In6.Cu")
		(hatch none 0.5)
		(connect_pads
			(clearance 0)
		)
		(min_thickness 0.25)
		(keepout
			(tracks not_allowed)
			(vias allowed)
			(pads allowed)
			(copperpour not_allowed)
			(footprints allowed)
		)
		(placement
			(enabled no)
			(sheetname "")
		)
		(fill
			(thermal_gap 0.5)
			(thermal_bridge_width 0.5)
			(island_removal_mode 0)
		)
		(polygon
			(pts
				(arc
					(start 79.749904 -134.999984)
					(mid 70.250304 -134.999984)
					(end 79.749904 -134.999984)
				)
			)
		)
	)
	(zone
		(layers "F.Cu" "B.Cu" "In1.Cu" "In2.Cu" "In3.Cu" "In4.Cu" "In5.Cu" "In6.Cu")
		(hatch none 0.5)
		(connect_pads
			(clearance 0)
		)
		(min_thickness 0.25)
		(keepout
			(tracks not_allowed)
			(vias allowed)
			(pads allowed)
			(copperpour not_allowed)
			(footprints allowed)
		)
		(placement
			(enabled no)
			(sheetname "")
		)
		(fill
			(thermal_gap 0.5)
			(thermal_bridge_width 0.5)
			(island_removal_mode 0)
		)
		(polygon
			(pts
				(arc
					(start 98.000058 -39.680134)
					(mid 92.00007 -39.680134)
					(end 98.000058 -39.680134)
				)
			)
		)
	)
	(zone
		(layers "F.Cu" "B.Cu" "In2.Cu")
		(hatch none 0.5)
		(connect_pads
			(clearance 0)
		)
		(min_thickness 0.25)
		(keepout
			(tracks not_allowed)
			(vias allowed)
			(pads allowed)
			(copperpour not_allowed)
			(footprints allowed)
		)
		(placement
			(enabled no)
			(sheetname "")
		)
		(fill yes
			(thermal_gap 0.5)
			(thermal_bridge_width 0.5)
			(island_removal_mode 0)
		)
		(polygon
			(pts
				(arc
					(start 189.561216 -2.600198)
					(mid 188.999876 -2.038858)
					(end 188.438536 -2.600198)
				)
				(arc
					(start 188.438536 -3.999738)
					(mid 188.998479 -4.56133)
					(end 189.561216 -4.002532)
				)
				(arc
					(start 189.393576 -4.002532)
					(mid 188.999876 -4.3937)
					(end 188.606176 -4.002532)
				)
				(arc
					(start 188.606176 -3.999992)
					(mid 188.999876 -3.606292)
					(end 189.393576 -3.999992)
				)
				(xy 189.561216 -3.999992) (xy 189.561216 -2.602738)
				(arc
					(start 189.393576 -2.602738)
					(mid 188.999876 -2.993906)
					(end 188.606176 -2.602738)
				)
				(arc
					(start 188.606176 -2.600198)
					(mid 188.999876 -2.206498)
					(end 189.393576 -2.600198)
				)
			)
		)
	)
	(zone
		(layers "F.Cu" "B.Cu" "In2.Cu")
		(hatch none 0.5)
		(connect_pads
			(clearance 0)
		)
		(min_thickness 0.25)
		(keepout
			(tracks not_allowed)
			(vias allowed)
			(pads allowed)
			(copperpour not_allowed)
			(footprints allowed)
		)
		(placement
			(enabled no)
			(sheetname "")
		)
		(fill yes
			(thermal_gap 0.5)
			(thermal_bridge_width 0.5)
			(island_removal_mode 0)
		)
		(polygon
			(pts
				(arc
					(start 120.761506 -9.800082)
					(mid 120.200166 -9.238742)
					(end 119.638826 -9.800082)
				)
				(arc
					(start 119.638826 -11.199876)
					(mid 120.198769 -11.761468)
					(end 120.761506 -11.20267)
				)
				(arc
					(start 120.593866 -11.20267)
					(mid 120.200166 -11.593838)
					(end 119.806466 -11.20267)
				)
				(arc
					(start 119.806466 -11.20013)
					(mid 120.200166 -10.80643)
					(end 120.593866 -11.20013)
				)
				(xy 120.761506 -11.20013) (xy 120.761506 -9.802622)
				(arc
					(start 120.593866 -9.802622)
					(mid 120.200166 -10.19379)
					(end 119.806466 -9.802622)
				)
				(arc
					(start 119.806466 -9.800082)
					(mid 120.200166 -9.406382)
					(end 120.593866 -9.800082)
				)
			)
		)
	)
	(zone
		(layers "F.Cu" "B.Cu" "In2.Cu")
		(hatch none 0.5)
		(connect_pads
			(clearance 0)
		)
		(min_thickness 0.25)
		(keepout
			(tracks not_allowed)
			(vias allowed)
			(pads allowed)
			(copperpour not_allowed)
			(footprints allowed)
		)
		(placement
			(enabled no)
			(sheetname "")
		)
		(fill yes
			(thermal_gap 0.5)
			(thermal_bridge_width 0.5)
			(island_removal_mode 0)
		)
		(polygon
			(pts
				(arc
					(start 113.561368 -9.800082)
					(mid 113.000028 -9.238742)
					(end 112.438688 -9.800082)
				)
				(arc
					(start 112.438688 -11.199876)
					(mid 112.998631 -11.761468)
					(end 113.561368 -11.20267)
				)
				(arc
					(start 113.393728 -11.20267)
					(mid 113.000028 -11.593838)
					(end 112.606328 -11.20267)
				)
				(arc
					(start 112.606328 -11.20013)
					(mid 113.000028 -10.80643)
					(end 113.393728 -11.20013)
				)
				(xy 113.561368 -11.20013) (xy 113.561368 -9.802622)
				(arc
					(start 113.393728 -9.802622)
					(mid 113.000028 -10.19379)
					(end 112.606328 -9.802622)
				)
				(arc
					(start 112.606328 -9.800082)
					(mid 113.000028 -9.406382)
					(end 113.393728 -9.800082)
				)
			)
		)
	)
	(zone
		(layers "F.Cu" "B.Cu" "In2.Cu")
		(hatch none 0.5)
		(connect_pads
			(clearance 0)
		)
		(min_thickness 0.25)
		(keepout
			(tracks not_allowed)
			(vias allowed)
			(pads allowed)
			(copperpour not_allowed)
			(footprints allowed)
		)
		(placement
			(enabled no)
			(sheetname "")
		)
		(fill yes
			(thermal_gap 0.5)
			(thermal_bridge_width 0.5)
			(island_removal_mode 0)
		)
		(polygon
			(pts
				(arc
					(start 136.961372 -10.999978)
					(mid 136.400032 -10.438638)
					(end 135.838692 -10.999978)
				)
				(arc
					(start 135.838692 -12.399772)
					(mid 136.398635 -12.961364)
					(end 136.961372 -12.402566)
				)
				(arc
					(start 136.793732 -12.402566)
					(mid 136.400032 -12.793734)
					(end 136.006332 -12.402566)
				)
				(arc
					(start 136.006332 -12.400026)
					(mid 136.400032 -12.006326)
					(end 136.793732 -12.400026)
				)
				(xy 136.961372 -12.400026) (xy 136.961372 -11.002518)
				(arc
					(start 136.793732 -11.002518)
					(mid 136.400032 -11.393686)
					(end 136.006332 -11.002518)
				)
				(arc
					(start 136.006332 -10.999978)
					(mid 136.400032 -10.606278)
					(end 136.793732 -10.999978)
				)
			)
		)
	)
	(zone
		(layers "F.Cu" "B.Cu" "In2.Cu")
		(hatch none 0.5)
		(connect_pads
			(clearance 0)
		)
		(min_thickness 0.25)
		(keepout
			(tracks not_allowed)
			(vias allowed)
			(pads allowed)
			(copperpour not_allowed)
			(footprints allowed)
		)
		(placement
			(enabled no)
			(sheetname "")
		)
		(fill yes
			(thermal_gap 0.5)
			(thermal_bridge_width 0.5)
			(island_removal_mode 0)
		)
		(polygon
			(pts
				(arc
					(start 133.36143 -10.999978)
					(mid 132.80009 -10.438638)
					(end 132.23875 -10.999978)
				)
				(arc
					(start 132.23875 -12.399772)
					(mid 132.798693 -12.961364)
					(end 133.36143 -12.402566)
				)
				(arc
					(start 133.19379 -12.402566)
					(mid 132.80009 -12.793734)
					(end 132.40639 -12.402566)
				)
				(arc
					(start 132.40639 -12.400026)
					(mid 132.80009 -12.006326)
					(end 133.19379 -12.400026)
				)
				(xy 133.36143 -12.400026) (xy 133.36143 -11.002518)
				(arc
					(start 133.19379 -11.002518)
					(mid 132.80009 -11.393686)
					(end 132.40639 -11.002518)
				)
				(arc
					(start 132.40639 -10.999978)
					(mid 132.80009 -10.606278)
					(end 133.19379 -10.999978)
				)
			)
		)
	)
	(zone
		(layers "F.Cu" "B.Cu" "In2.Cu")
		(hatch none 0.5)
		(connect_pads
			(clearance 0)
		)
		(min_thickness 0.25)
		(keepout
			(tracks not_allowed)
			(vias allowed)
			(pads allowed)
			(copperpour not_allowed)
			(footprints allowed)
		)
		(placement
			(enabled no)
			(sheetname "")
		)
		(fill yes
			(thermal_gap 0.5)
			(thermal_bridge_width 0.5)
			(island_removal_mode 0)
		)
		(polygon
			(pts
				(arc
					(start 124.361448 -9.800082)
					(mid 123.800108 -9.238742)
					(end 123.238768 -9.800082)
				)
				(arc
					(start 123.238768 -11.199876)
					(mid 123.798711 -11.761468)
					(end 124.361448 -11.20267)
				)
				(arc
					(start 124.193808 -11.20267)
					(mid 123.800108 -11.593838)
					(end 123.406408 -11.20267)
				)
				(arc
					(start 123.406408 -11.20013)
					(mid 123.800108 -10.80643)
					(end 124.193808 -11.20013)
				)
				(xy 124.361448 -11.20013) (xy 124.361448 -9.802622)
				(arc
					(start 124.193808 -9.802622)
					(mid 123.800108 -10.19379)
					(end 123.406408 -9.802622)
				)
				(arc
					(start 123.406408 -9.800082)
					(mid 123.800108 -9.406382)
					(end 124.193808 -9.800082)
				)
			)
		)
	)
	(zone
		(layers "F.Cu" "B.Cu" "In2.Cu")
		(hatch none 0.5)
		(connect_pads
			(clearance 0)
		)
		(min_thickness 0.25)
		(keepout
			(tracks not_allowed)
			(vias allowed)
			(pads allowed)
			(copperpour not_allowed)
			(footprints allowed)
		)
		(placement
			(enabled no)
			(sheetname "")
		)
		(fill yes
			(thermal_gap 0.5)
			(thermal_bridge_width 0.5)
			(island_removal_mode 0)
		)
		(polygon
			(pts
				(arc
					(start 145.961354 -9.800082)
					(mid 145.400014 -9.238742)
					(end 144.838674 -9.800082)
				)
				(arc
					(start 144.838674 -11.199876)
					(mid 145.398617 -11.761468)
					(end 145.961354 -11.20267)
				)
				(arc
					(start 145.793714 -11.20267)
					(mid 145.400014 -11.593838)
					(end 145.006314 -11.20267)
				)
				(arc
					(start 145.006314 -11.20013)
					(mid 145.400014 -10.80643)
					(end 145.793714 -11.20013)
				)
				(xy 145.961354 -11.20013) (xy 145.961354 -9.802622)
				(arc
					(start 145.793714 -9.802622)
					(mid 145.400014 -10.19379)
					(end 145.006314 -9.802622)
				)
				(arc
					(start 145.006314 -9.800082)
					(mid 145.400014 -9.406382)
					(end 145.793714 -9.800082)
				)
			)
		)
	)
	(zone
		(layers "F.Cu" "B.Cu" "In2.Cu")
		(hatch none 0.5)
		(connect_pads
			(clearance 0)
		)
		(min_thickness 0.25)
		(keepout
			(tracks not_allowed)
			(vias allowed)
			(pads allowed)
			(copperpour not_allowed)
			(footprints allowed)
		)
		(placement
			(enabled no)
			(sheetname "")
		)
		(fill yes
			(thermal_gap 0.5)
			(thermal_bridge_width 0.5)
			(island_removal_mode 0)
		)
		(polygon
			(pts
				(arc
					(start 115.361466 -10.999978)
					(mid 114.800126 -10.438638)
					(end 114.238786 -10.999978)
				)
				(arc
					(start 114.238786 -12.399772)
					(mid 114.798729 -12.961364)
					(end 115.361466 -12.402566)
				)
				(arc
					(start 115.193826 -12.402566)
					(mid 114.800126 -12.793734)
					(end 114.406426 -12.402566)
				)
				(arc
					(start 114.406426 -12.400026)
					(mid 114.800126 -12.006326)
					(end 115.193826 -12.400026)
				)
				(xy 115.361466 -12.400026) (xy 115.361466 -11.002518)
				(arc
					(start 115.193826 -11.002518)
					(mid 114.800126 -11.393686)
					(end 114.406426 -11.002518)
				)
				(arc
					(start 114.406426 -10.999978)
					(mid 114.800126 -10.606278)
					(end 115.193826 -10.999978)
				)
			)
		)
	)
	(zone
		(layers "F.Cu" "B.Cu" "In2.Cu")
		(hatch none 0.5)
		(connect_pads
			(clearance 0)
		)
		(min_thickness 0.25)
		(keepout
			(tracks not_allowed)
			(vias allowed)
			(pads allowed)
			(copperpour not_allowed)
			(footprints allowed)
		)
		(placement
			(enabled no)
			(sheetname "")
		)
		(fill yes
			(thermal_gap 0.5)
			(thermal_bridge_width 0.5)
			(island_removal_mode 0)
		)
		(polygon
			(pts
				(arc
					(start 90.161364 -10.999978)
					(mid 89.600024 -10.438638)
					(end 89.038684 -10.999978)
				)
				(arc
					(start 89.038684 -12.399772)
					(mid 89.598627 -12.961364)
					(end 90.161364 -12.402566)
				)
				(arc
					(start 89.993724 -12.402566)
					(mid 89.600024 -12.793734)
					(end 89.206324 -12.402566)
				)
				(arc
					(start 89.206324 -12.400026)
					(mid 89.600024 -12.006326)
					(end 89.993724 -12.400026)
				)
				(xy 90.161364 -12.400026) (xy 90.161364 -11.002518)
				(arc
					(start 89.993724 -11.002518)
					(mid 89.600024 -11.393686)
					(end 89.206324 -11.002518)
				)
				(arc
					(start 89.206324 -10.999978)
					(mid 89.600024 -10.606278)
					(end 89.993724 -10.999978)
				)
			)
		)
	)
	(zone
		(layers "F.Cu" "B.Cu" "In2.Cu")
		(hatch none 0.5)
		(connect_pads
			(clearance 0)
		)
		(min_thickness 0.25)
		(keepout
			(tracks not_allowed)
			(vias allowed)
			(pads allowed)
			(copperpour not_allowed)
			(footprints allowed)
		)
		(placement
			(enabled no)
			(sheetname "")
		)
		(fill yes
			(thermal_gap 0.5)
			(thermal_bridge_width 0.5)
			(island_removal_mode 0)
		)
		(polygon
			(pts
				(arc
					(start 126.161546 -10.999978)
					(mid 125.600206 -10.438638)
					(end 125.038866 -10.999978)
				)
				(arc
					(start 125.038866 -12.399772)
					(mid 125.598809 -12.961364)
					(end 126.161546 -12.402566)
				)
				(arc
					(start 125.993906 -12.402566)
					(mid 125.600206 -12.793734)
					(end 125.206506 -12.402566)
				)
				(arc
					(start 125.206506 -12.400026)
					(mid 125.600206 -12.006326)
					(end 125.993906 -12.400026)
				)
				(xy 126.161546 -12.400026) (xy 126.161546 -11.002518)
				(arc
					(start 125.993906 -11.002518)
					(mid 125.600206 -11.393686)
					(end 125.206506 -11.002518)
				)
				(arc
					(start 125.206506 -10.999978)
					(mid 125.600206 -10.606278)
					(end 125.993906 -10.999978)
				)
			)
		)
	)
	(zone
		(layers "F.Cu" "B.Cu" "In2.Cu")
		(hatch none 0.5)
		(connect_pads
			(clearance 0)
		)
		(min_thickness 0.25)
		(keepout
			(tracks not_allowed)
			(vias allowed)
			(pads allowed)
			(copperpour not_allowed)
			(footprints allowed)
		)
		(placement
			(enabled no)
			(sheetname "")
		)
		(fill yes
			(thermal_gap 0.5)
			(thermal_bridge_width 0.5)
			(island_removal_mode 0)
		)
		(polygon
			(pts
				(arc
					(start 185.961274 -2.600198)
					(mid 185.399934 -2.038858)
					(end 184.838594 -2.600198)
				)
				(arc
					(start 184.838594 -3.999738)
					(mid 185.398537 -4.56133)
					(end 185.961274 -4.002532)
				)
				(arc
					(start 185.793634 -4.002532)
					(mid 185.399934 -4.3937)
					(end 185.006234 -4.002532)
				)
				(arc
					(start 185.006234 -3.999992)
					(mid 185.399934 -3.606292)
					(end 185.793634 -3.999992)
				)
				(xy 185.961274 -3.999992) (xy 185.961274 -2.602738)
				(arc
					(start 185.793634 -2.602738)
					(mid 185.399934 -2.993906)
					(end 185.006234 -2.602738)
				)
				(arc
					(start 185.006234 -2.600198)
					(mid 185.399934 -2.206498)
					(end 185.793634 -2.600198)
				)
			)
		)
	)
	(zone
		(layers "F.Cu" "B.Cu" "In2.Cu")
		(hatch none 0.5)
		(connect_pads
			(clearance 0)
		)
		(min_thickness 0.25)
		(keepout
			(tracks not_allowed)
			(vias allowed)
			(pads allowed)
			(copperpour not_allowed)
			(footprints allowed)
		)
		(placement
			(enabled no)
			(sheetname "")
		)
		(fill yes
			(thermal_gap 0.5)
			(thermal_bridge_width 0.5)
			(island_removal_mode 0)
		)
		(polygon
			(pts
				(arc
					(start 104.561386 -10.999978)
					(mid 104.000046 -10.438638)
					(end 103.438706 -10.999978)
				)
				(arc
					(start 103.438706 -12.399772)
					(mid 103.998649 -12.961364)
					(end 104.561386 -12.402566)
				)
				(arc
					(start 104.393746 -12.402566)
					(mid 104.000046 -12.793734)
					(end 103.606346 -12.402566)
				)
				(arc
					(start 103.606346 -12.400026)
					(mid 104.000046 -12.006326)
					(end 104.393746 -12.400026)
				)
				(xy 104.561386 -12.400026) (xy 104.561386 -11.002518)
				(arc
					(start 104.393746 -11.002518)
					(mid 104.000046 -11.393686)
					(end 103.606346 -11.002518)
				)
				(arc
					(start 103.606346 -10.999978)
					(mid 104.000046 -10.606278)
					(end 104.393746 -10.999978)
				)
			)
		)
	)
	(zone
		(layers "F.Cu" "B.Cu" "In2.Cu")
		(hatch none 0.5)
		(connect_pads
			(clearance 0)
		)
		(min_thickness 0.25)
		(keepout
			(tracks not_allowed)
			(vias allowed)
			(pads allowed)
			(copperpour not_allowed)
			(footprints allowed)
		)
		(placement
			(enabled no)
			(sheetname "")
		)
		(fill yes
			(thermal_gap 0.5)
			(thermal_bridge_width 0.5)
			(island_removal_mode 0)
		)
		(polygon
			(pts
				(arc
					(start 129.761488 -10.999978)
					(mid 129.200148 -10.438638)
					(end 128.638808 -10.999978)
				)
				(arc
					(start 128.638808 -12.399772)
					(mid 129.198751 -12.961364)
					(end 129.761488 -12.402566)
				)
				(arc
					(start 129.593848 -12.402566)
					(mid 129.200148 -12.793734)
					(end 128.806448 -12.402566)
				)
				(arc
					(start 128.806448 -12.400026)
					(mid 129.200148 -12.006326)
					(end 129.593848 -12.400026)
				)
				(xy 129.761488 -12.400026) (xy 129.761488 -11.002518)
				(arc
					(start 129.593848 -11.002518)
					(mid 129.200148 -11.393686)
					(end 128.806448 -11.002518)
				)
				(arc
					(start 128.806448 -10.999978)
					(mid 129.200148 -10.606278)
					(end 129.593848 -10.999978)
				)
			)
		)
	)
	(zone
		(layers "F.Cu" "B.Cu" "In2.Cu")
		(hatch none 0.5)
		(connect_pads
			(clearance 0)
		)
		(min_thickness 0.25)
		(keepout
			(tracks not_allowed)
			(vias allowed)
			(pads allowed)
			(copperpour not_allowed)
			(footprints allowed)
		)
		(placement
			(enabled no)
			(sheetname "")
		)
		(fill yes
			(thermal_gap 0.5)
			(thermal_bridge_width 0.5)
			(island_removal_mode 0)
		)
		(polygon
			(pts
				(arc
					(start 127.96139 -9.800082)
					(mid 127.40005 -9.238742)
					(end 126.83871 -9.800082)
				)
				(arc
					(start 126.83871 -11.199876)
					(mid 127.398653 -11.761468)
					(end 127.96139 -11.20267)
				)
				(arc
					(start 127.79375 -11.20267)
					(mid 127.40005 -11.593838)
					(end 127.00635 -11.20267)
				)
				(arc
					(start 127.00635 -11.20013)
					(mid 127.40005 -10.80643)
					(end 127.79375 -11.20013)
				)
				(xy 127.96139 -11.20013) (xy 127.96139 -9.802622)
				(arc
					(start 127.79375 -9.802622)
					(mid 127.40005 -10.19379)
					(end 127.00635 -9.802622)
				)
				(arc
					(start 127.00635 -9.800082)
					(mid 127.40005 -9.406382)
					(end 127.79375 -9.800082)
				)
			)
		)
	)
	(zone
		(layers "F.Cu" "B.Cu" "In2.Cu")
		(hatch none 0.5)
		(connect_pads
			(clearance 0)
		)
		(min_thickness 0.25)
		(keepout
			(tracks not_allowed)
			(vias allowed)
			(pads allowed)
			(copperpour not_allowed)
			(footprints allowed)
		)
		(placement
			(enabled no)
			(sheetname "")
		)
		(fill yes
			(thermal_gap 0.5)
			(thermal_bridge_width 0.5)
			(island_removal_mode 0)
		)
		(polygon
			(pts
				(arc
					(start 193.161158 -2.600198)
					(mid 192.599818 -2.038858)
					(end 192.038478 -2.600198)
				)
				(arc
					(start 192.038478 -3.999738)
					(mid 192.598421 -4.56133)
					(end 193.161158 -4.002532)
				)
				(arc
					(start 192.993518 -4.002532)
					(mid 192.599818 -4.3937)
					(end 192.206118 -4.002532)
				)
				(arc
					(start 192.206118 -3.999992)
					(mid 192.599818 -3.606292)
					(end 192.993518 -3.999992)
				)
				(xy 193.161158 -3.999992) (xy 193.161158 -2.602738)
				(arc
					(start 192.993518 -2.602738)
					(mid 192.599818 -2.993906)
					(end 192.206118 -2.602738)
				)
				(arc
					(start 192.206118 -2.600198)
					(mid 192.599818 -2.206498)
					(end 192.993518 -2.600198)
				)
			)
		)
	)
	(zone
		(layers "F.Cu" "B.Cu" "In2.Cu")
		(hatch none 0.5)
		(connect_pads
			(clearance 0)
		)
		(min_thickness 0.25)
		(keepout
			(tracks not_allowed)
			(vias allowed)
			(pads allowed)
			(copperpour not_allowed)
			(footprints allowed)
		)
		(placement
			(enabled no)
			(sheetname "")
		)
		(fill yes
			(thermal_gap 0.5)
			(thermal_bridge_width 0.5)
			(island_removal_mode 0)
		)
		(polygon
			(pts
				(arc
					(start 142.361412 -9.800082)
					(mid 141.800072 -9.238742)
					(end 141.238732 -9.800082)
				)
				(arc
					(start 141.238732 -11.199876)
					(mid 141.798675 -11.761468)
					(end 142.361412 -11.20267)
				)
				(arc
					(start 142.193772 -11.20267)
					(mid 141.800072 -11.593838)
					(end 141.406372 -11.20267)
				)
				(arc
					(start 141.406372 -11.20013)
					(mid 141.800072 -10.80643)
					(end 142.193772 -11.20013)
				)
				(xy 142.361412 -11.20013) (xy 142.361412 -9.802622)
				(arc
					(start 142.193772 -9.802622)
					(mid 141.800072 -10.19379)
					(end 141.406372 -9.802622)
				)
				(arc
					(start 141.406372 -9.800082)
					(mid 141.800072 -9.406382)
					(end 142.193772 -9.800082)
				)
			)
		)
	)
	(zone
		(layers "F.Cu" "B.Cu" "In2.Cu")
		(hatch none 0.5)
		(connect_pads
			(clearance 0)
		)
		(min_thickness 0.25)
		(keepout
			(tracks not_allowed)
			(vias allowed)
			(pads allowed)
			(copperpour not_allowed)
			(footprints allowed)
		)
		(placement
			(enabled no)
			(sheetname "")
		)
		(fill yes
			(thermal_gap 0.5)
			(thermal_bridge_width 0.5)
			(island_removal_mode 0)
		)
		(polygon
			(pts
				(arc
					(start 91.961462 -9.800082)
					(mid 91.400122 -9.238742)
					(end 90.838782 -9.800082)
				)
				(arc
					(start 90.838782 -11.199876)
					(mid 91.398725 -11.761468)
					(end 91.961462 -11.20267)
				)
				(arc
					(start 91.793822 -11.20267)
					(mid 91.400122 -11.593838)
					(end 91.006422 -11.20267)
				)
				(arc
					(start 91.006422 -11.20013)
					(mid 91.400122 -10.80643)
					(end 91.793822 -11.20013)
				)
				(xy 91.961462 -11.20013) (xy 91.961462 -9.802622)
				(arc
					(start 91.793822 -9.802622)
					(mid 91.400122 -10.19379)
					(end 91.006422 -9.802622)
				)
				(arc
					(start 91.006422 -9.800082)
					(mid 91.400122 -9.406382)
					(end 91.793822 -9.800082)
				)
			)
		)
	)
	(zone
		(layers "F.Cu" "B.Cu" "In2.Cu")
		(hatch none 0.5)
		(connect_pads
			(clearance 0)
		)
		(min_thickness 0.25)
		(keepout
			(tracks not_allowed)
			(vias allowed)
			(pads allowed)
			(copperpour not_allowed)
			(footprints allowed)
		)
		(placement
			(enabled no)
			(sheetname "")
		)
		(fill yes
			(thermal_gap 0.5)
			(thermal_bridge_width 0.5)
			(island_removal_mode 0)
		)
		(polygon
			(pts
				(arc
					(start 88.36152 -9.800082)
					(mid 87.80018 -9.238742)
					(end 87.23884 -9.800082)
				)
				(arc
					(start 87.23884 -11.199876)
					(mid 87.798783 -11.761468)
					(end 88.36152 -11.20267)
				)
				(arc
					(start 88.19388 -11.20267)
					(mid 87.80018 -11.593838)
					(end 87.40648 -11.20267)
				)
				(arc
					(start 87.40648 -11.20013)
					(mid 87.80018 -10.80643)
					(end 88.19388 -11.20013)
				)
				(xy 88.36152 -11.20013) (xy 88.36152 -9.802622)
				(arc
					(start 88.19388 -9.802622)
					(mid 87.80018 -10.19379)
					(end 87.40648 -9.802622)
				)
				(arc
					(start 87.40648 -9.800082)
					(mid 87.80018 -9.406382)
					(end 88.19388 -9.800082)
				)
			)
		)
	)
	(zone
		(layers "F.Cu" "B.Cu" "In2.Cu")
		(hatch none 0.5)
		(connect_pads
			(clearance 0)
		)
		(min_thickness 0.25)
		(keepout
			(tracks not_allowed)
			(vias allowed)
			(pads allowed)
			(copperpour not_allowed)
			(footprints allowed)
		)
		(placement
			(enabled no)
			(sheetname "")
		)
		(fill yes
			(thermal_gap 0.5)
			(thermal_bridge_width 0.5)
			(island_removal_mode 0)
		)
		(polygon
			(pts
				(arc
					(start 140.561314 -10.999978)
					(mid 139.999974 -10.438638)
					(end 139.438634 -10.999978)
				)
				(arc
					(start 139.438634 -12.399772)
					(mid 139.998577 -12.961364)
					(end 140.561314 -12.402566)
				)
				(arc
					(start 140.393674 -12.402566)
					(mid 139.999974 -12.793734)
					(end 139.606274 -12.402566)
				)
				(arc
					(start 139.606274 -12.400026)
					(mid 139.999974 -12.006326)
					(end 140.393674 -12.400026)
				)
				(xy 140.561314 -12.400026) (xy 140.561314 -11.002518)
				(arc
					(start 140.393674 -11.002518)
					(mid 139.999974 -11.393686)
					(end 139.606274 -11.002518)
				)
				(arc
					(start 139.606274 -10.999978)
					(mid 139.999974 -10.606278)
					(end 140.393674 -10.999978)
				)
			)
		)
	)
	(zone
		(layers "F.Cu" "B.Cu" "In2.Cu")
		(hatch none 0.5)
		(connect_pads
			(clearance 0)
		)
		(min_thickness 0.25)
		(keepout
			(tracks not_allowed)
			(vias allowed)
			(pads allowed)
			(copperpour not_allowed)
			(footprints allowed)
		)
		(placement
			(enabled no)
			(sheetname "")
		)
		(fill yes
			(thermal_gap 0.5)
			(thermal_bridge_width 0.5)
			(island_removal_mode 0)
		)
		(polygon
			(pts
				(arc
					(start 117.16131 -9.800082)
					(mid 116.59997 -9.238742)
					(end 116.03863 -9.800082)
				)
				(arc
					(start 116.03863 -11.199876)
					(mid 116.598573 -11.761468)
					(end 117.16131 -11.20267)
				)
				(arc
					(start 116.99367 -11.20267)
					(mid 116.59997 -11.593838)
					(end 116.20627 -11.20267)
				)
				(arc
					(start 116.20627 -11.20013)
					(mid 116.59997 -10.80643)
					(end 116.99367 -11.20013)
				)
				(xy 117.16131 -11.20013) (xy 117.16131 -9.802622)
				(arc
					(start 116.99367 -9.802622)
					(mid 116.59997 -10.19379)
					(end 116.20627 -9.802622)
				)
				(arc
					(start 116.20627 -9.800082)
					(mid 116.59997 -9.406382)
					(end 116.99367 -9.800082)
				)
			)
		)
	)
	(zone
		(layers "F.Cu" "B.Cu" "In2.Cu")
		(hatch none 0.5)
		(connect_pads
			(clearance 0)
		)
		(min_thickness 0.25)
		(keepout
			(tracks not_allowed)
			(vias allowed)
			(pads allowed)
			(copperpour not_allowed)
			(footprints allowed)
		)
		(placement
			(enabled no)
			(sheetname "")
		)
		(fill yes
			(thermal_gap 0.5)
			(thermal_bridge_width 0.5)
			(island_removal_mode 0)
		)
		(polygon
			(pts
				(arc
					(start 106.247184 -103.450136)
					(mid 105.8711 -102.968008)
					(end 105.311956 -103.21544)
				)
				(xy 105.311194 -103.214932) (xy 104.561386 -104.614472) (xy 104.561386 -104.61498)
				(arc
					(start 104.561894 -104.615234)
					(mid 104.765348 -105.28808)
					(end 105.438194 -105.084626)
				)
				(xy 105.438956 -105.085134) (xy 105.56367 -104.85247)
				(arc
					(start 105.381044 -104.85247)
					(mid 105.000044 -105.230938)
					(end 104.619044 -104.85247)
				)
				(arc
					(start 104.619044 -104.84993)
					(mid 105.000044 -104.46893)
					(end 105.381044 -104.84993)
				)
				(xy 105.56494 -104.84993) (xy 106.189018 -103.68534)
				(arc
					(start 106.188256 -103.684832)
					(mid 106.231895 -103.572354)
					(end 106.247184 -103.452676)
				)
				(arc
					(start 106.131106 -103.452676)
					(mid 105.750106 -103.831144)
					(end 105.369106 -103.452676)
				)
				(arc
					(start 105.369106 -103.450136)
					(mid 105.750106 -103.069136)
					(end 106.131106 -103.450136)
				)
			)
		)
	)
	(zone
		(layers "F.Cu" "B.Cu" "In2.Cu")
		(hatch none 0.5)
		(connect_pads
			(clearance 0)
		)
		(min_thickness 0.25)
		(keepout
			(tracks not_allowed)
			(vias allowed)
			(pads allowed)
			(copperpour not_allowed)
			(footprints allowed)
		)
		(placement
			(enabled no)
			(sheetname "")
		)
		(fill yes
			(thermal_gap 0.5)
			(thermal_bridge_width 0.5)
			(island_removal_mode 0)
		)
		(polygon
			(pts
				(arc
					(start 93.761306 -10.999978)
					(mid 93.199966 -10.438638)
					(end 92.638626 -10.999978)
				)
				(arc
					(start 92.638626 -12.399772)
					(mid 93.198569 -12.961364)
					(end 93.761306 -12.402566)
				)
				(arc
					(start 93.593666 -12.402566)
					(mid 93.199966 -12.793734)
					(end 92.806266 -12.402566)
				)
				(arc
					(start 92.806266 -12.400026)
					(mid 93.199966 -12.006326)
					(end 93.593666 -12.400026)
				)
				(xy 93.761306 -12.400026) (xy 93.761306 -11.002518)
				(arc
					(start 93.593666 -11.002518)
					(mid 93.199966 -11.393686)
					(end 92.806266 -11.002518)
				)
				(arc
					(start 92.806266 -10.999978)
					(mid 93.199966 -10.606278)
					(end 93.593666 -10.999978)
				)
			)
		)
	)
	(zone
		(layers "F.Cu" "B.Cu" "In2.Cu")
		(hatch none 0.5)
		(connect_pads
			(clearance 0)
		)
		(min_thickness 0.25)
		(keepout
			(tracks not_allowed)
			(vias allowed)
			(pads allowed)
			(copperpour not_allowed)
			(footprints allowed)
		)
		(placement
			(enabled no)
			(sheetname "")
		)
		(fill yes
			(thermal_gap 0.5)
			(thermal_bridge_width 0.5)
			(island_removal_mode 0)
		)
		(polygon
			(pts
				(arc
					(start 103.996998 -107.249976)
					(mid 103.620914 -106.767848)
					(end 103.06177 -107.01528)
				)
				(xy 103.061008 -107.015026) (xy 102.311454 -108.41482) (xy 102.311454 -108.415074)
				(arc
					(start 102.311962 -108.415328)
					(mid 102.515416 -109.088174)
					(end 103.188262 -108.88472)
				)
				(xy 103.189024 -108.884974) (xy 103.313484 -108.652564)
				(arc
					(start 103.131112 -108.652564)
					(mid 102.750112 -109.031032)
					(end 102.369112 -108.652564)
				)
				(arc
					(start 102.369112 -108.650024)
					(mid 102.750112 -108.269024)
					(end 103.131112 -108.650024)
				)
				(xy 103.314754 -108.650024) (xy 103.938832 -107.484926)
				(arc
					(start 103.93807 -107.484672)
					(mid 103.981709 -107.372194)
					(end 103.996998 -107.252516)
				)
				(arc
					(start 103.88092 -107.252516)
					(mid 103.49992 -107.630984)
					(end 103.11892 -107.252516)
				)
				(arc
					(start 103.11892 -107.249976)
					(mid 103.49992 -106.868976)
					(end 103.88092 -107.249976)
				)
			)
		)
	)
	(zone
		(layers "F.Cu" "B.Cu" "In2.Cu")
		(hatch none 0.5)
		(connect_pads
			(clearance 0)
		)
		(min_thickness 0.25)
		(keepout
			(tracks not_allowed)
			(vias allowed)
			(pads allowed)
			(copperpour not_allowed)
			(footprints allowed)
		)
		(placement
			(enabled no)
			(sheetname "")
		)
		(fill yes
			(thermal_gap 0.5)
			(thermal_bridge_width 0.5)
			(island_removal_mode 0)
		)
		(polygon
			(pts
				(arc
					(start 187.761118 -3.800094)
					(mid 187.199778 -3.238754)
					(end 186.638438 -3.800094)
				)
				(arc
					(start 186.638438 -5.199888)
					(mid 187.198381 -5.76148)
					(end 187.761118 -5.202682)
				)
				(arc
					(start 187.593478 -5.202682)
					(mid 187.199778 -5.59385)
					(end 186.806078 -5.202682)
				)
				(arc
					(start 186.806078 -5.200142)
					(mid 187.199778 -4.806442)
					(end 187.593478 -5.200142)
				)
				(xy 187.761118 -5.200142) (xy 187.761118 -3.802634)
				(arc
					(start 187.593478 -3.802634)
					(mid 187.199778 -4.193802)
					(end 186.806078 -3.802634)
				)
				(arc
					(start 186.806078 -3.800094)
					(mid 187.199778 -3.406394)
					(end 187.593478 -3.800094)
				)
			)
		)
	)
	(zone
		(layers "F.Cu" "B.Cu" "In2.Cu")
		(hatch none 0.5)
		(connect_pads
			(clearance 0)
		)
		(min_thickness 0.25)
		(keepout
			(tracks not_allowed)
			(vias allowed)
			(pads allowed)
			(copperpour not_allowed)
			(footprints allowed)
		)
		(placement
			(enabled no)
			(sheetname "")
		)
		(fill yes
			(thermal_gap 0.5)
			(thermal_bridge_width 0.5)
			(island_removal_mode 0)
		)
		(polygon
			(pts
				(arc
					(start 149.561296 -9.800082)
					(mid 148.999956 -9.238742)
					(end 148.438616 -9.800082)
				)
				(arc
					(start 148.438616 -11.199876)
					(mid 148.998559 -11.761468)
					(end 149.561296 -11.20267)
				)
				(arc
					(start 149.393656 -11.20267)
					(mid 148.999956 -11.593838)
					(end 148.606256 -11.20267)
				)
				(arc
					(start 148.606256 -11.20013)
					(mid 148.999956 -10.80643)
					(end 149.393656 -11.20013)
				)
				(xy 149.561296 -11.20013) (xy 149.561296 -9.802622)
				(arc
					(start 149.393656 -9.802622)
					(mid 148.999956 -10.19379)
					(end 148.606256 -9.802622)
				)
				(arc
					(start 148.606256 -9.800082)
					(mid 148.999956 -9.406382)
					(end 149.393656 -9.800082)
				)
			)
		)
	)
	(zone
		(layers "F.Cu" "B.Cu" "In2.Cu")
		(hatch none 0.5)
		(connect_pads
			(clearance 0)
		)
		(min_thickness 0.25)
		(keepout
			(tracks not_allowed)
			(vias allowed)
			(pads allowed)
			(copperpour not_allowed)
			(footprints allowed)
		)
		(placement
			(enabled no)
			(sheetname "")
		)
		(fill yes
			(thermal_gap 0.5)
			(thermal_bridge_width 0.5)
			(island_removal_mode 0)
		)
		(polygon
			(pts
				(arc
					(start 122.56135 -10.999978)
					(mid 122.00001 -10.438638)
					(end 121.43867 -10.999978)
				)
				(arc
					(start 121.43867 -12.399772)
					(mid 121.998613 -12.961364)
					(end 122.56135 -12.402566)
				)
				(arc
					(start 122.39371 -12.402566)
					(mid 122.00001 -12.793734)
					(end 121.60631 -12.402566)
				)
				(arc
					(start 121.60631 -12.400026)
					(mid 122.00001 -12.006326)
					(end 122.39371 -12.400026)
				)
				(xy 122.56135 -12.400026) (xy 122.56135 -11.002518)
				(arc
					(start 122.39371 -11.002518)
					(mid 122.00001 -11.393686)
					(end 121.60631 -11.002518)
				)
				(arc
					(start 121.60631 -10.999978)
					(mid 122.00001 -10.606278)
					(end 122.39371 -10.999978)
				)
			)
		)
	)
	(zone
		(layers "F.Cu" "B.Cu" "In2.Cu")
		(hatch none 0.5)
		(connect_pads
			(clearance 0)
		)
		(min_thickness 0.25)
		(keepout
			(tracks not_allowed)
			(vias allowed)
			(pads allowed)
			(copperpour not_allowed)
			(footprints allowed)
		)
		(placement
			(enabled no)
			(sheetname "")
		)
		(fill yes
			(thermal_gap 0.5)
			(thermal_bridge_width 0.5)
			(island_removal_mode 0)
		)
		(polygon
			(pts
				(arc
					(start 118.961408 -10.999978)
					(mid 118.400068 -10.438638)
					(end 117.838728 -10.999978)
				)
				(arc
					(start 117.838728 -12.399772)
					(mid 118.398671 -12.961364)
					(end 118.961408 -12.402566)
				)
				(arc
					(start 118.793768 -12.402566)
					(mid 118.400068 -12.793734)
					(end 118.006368 -12.402566)
				)
				(arc
					(start 118.006368 -12.400026)
					(mid 118.400068 -12.006326)
					(end 118.793768 -12.400026)
				)
				(xy 118.961408 -12.400026) (xy 118.961408 -11.002518)
				(arc
					(start 118.793768 -11.002518)
					(mid 118.400068 -11.393686)
					(end 118.006368 -11.002518)
				)
				(arc
					(start 118.006368 -10.999978)
					(mid 118.400068 -10.606278)
					(end 118.793768 -10.999978)
				)
			)
		)
	)
	(zone
		(layers "F.Cu" "B.Cu" "In2.Cu")
		(hatch none 0.5)
		(connect_pads
			(clearance 0)
		)
		(min_thickness 0.25)
		(keepout
			(tracks not_allowed)
			(vias allowed)
			(pads allowed)
			(copperpour not_allowed)
			(footprints allowed)
		)
		(placement
			(enabled no)
			(sheetname "")
		)
		(fill yes
			(thermal_gap 0.5)
			(thermal_bridge_width 0.5)
			(island_removal_mode 0)
		)
		(polygon
			(pts
				(arc
					(start 180.561234 -3.800094)
					(mid 179.999894 -3.238754)
					(end 179.438554 -3.800094)
				)
				(arc
					(start 179.438554 -5.199888)
					(mid 179.998497 -5.76148)
					(end 180.561234 -5.202682)
				)
				(arc
					(start 180.393594 -5.202682)
					(mid 179.999894 -5.59385)
					(end 179.606194 -5.202682)
				)
				(arc
					(start 179.606194 -5.200142)
					(mid 179.999894 -4.806442)
					(end 180.393594 -5.200142)
				)
				(xy 180.561234 -5.200142) (xy 180.561234 -3.802634)
				(arc
					(start 180.393594 -3.802634)
					(mid 179.999894 -4.193802)
					(end 179.606194 -3.802634)
				)
				(arc
					(start 179.606194 -3.800094)
					(mid 179.999894 -3.406394)
					(end 180.393594 -3.800094)
				)
			)
		)
	)
	(zone
		(layers "F.Cu" "B.Cu" "In2.Cu")
		(hatch none 0.5)
		(connect_pads
			(clearance 0)
		)
		(min_thickness 0.25)
		(keepout
			(tracks not_allowed)
			(vias allowed)
			(pads allowed)
			(copperpour not_allowed)
			(footprints allowed)
		)
		(placement
			(enabled no)
			(sheetname "")
		)
		(fill yes
			(thermal_gap 0.5)
			(thermal_bridge_width 0.5)
			(island_removal_mode 0)
		)
		(polygon
			(pts
				(arc
					(start 108.161328 -10.999978)
					(mid 107.599988 -10.438638)
					(end 107.038648 -10.999978)
				)
				(arc
					(start 107.038648 -12.399772)
					(mid 107.598591 -12.961364)
					(end 108.161328 -12.402566)
				)
				(arc
					(start 107.993688 -12.402566)
					(mid 107.599988 -12.793734)
					(end 107.206288 -12.402566)
				)
				(arc
					(start 107.206288 -12.400026)
					(mid 107.599988 -12.006326)
					(end 107.993688 -12.400026)
				)
				(xy 108.161328 -12.400026) (xy 108.161328 -11.002518)
				(arc
					(start 107.993688 -11.002518)
					(mid 107.599988 -11.393686)
					(end 107.206288 -11.002518)
				)
				(arc
					(start 107.206288 -10.999978)
					(mid 107.599988 -10.606278)
					(end 107.993688 -10.999978)
				)
			)
		)
	)
	(zone
		(layers "F.Cu" "B.Cu" "In2.Cu")
		(hatch none 0.5)
		(connect_pads
			(clearance 0)
		)
		(min_thickness 0.25)
		(keepout
			(tracks not_allowed)
			(vias allowed)
			(pads allowed)
			(copperpour not_allowed)
			(footprints allowed)
		)
		(placement
			(enabled no)
			(sheetname "")
		)
		(fill yes
			(thermal_gap 0.5)
			(thermal_bridge_width 0.5)
			(island_removal_mode 0)
		)
		(polygon
			(pts
				(arc
					(start 100.961444 -10.999978)
					(mid 100.400104 -10.438638)
					(end 99.838764 -10.999978)
				)
				(arc
					(start 99.838764 -12.399772)
					(mid 100.398707 -12.961364)
					(end 100.961444 -12.402566)
				)
				(arc
					(start 100.793804 -12.402566)
					(mid 100.400104 -12.793734)
					(end 100.006404 -12.402566)
				)
				(arc
					(start 100.006404 -12.400026)
					(mid 100.400104 -12.006326)
					(end 100.793804 -12.400026)
				)
				(xy 100.961444 -12.400026) (xy 100.961444 -11.002518)
				(arc
					(start 100.793804 -11.002518)
					(mid 100.400104 -11.393686)
					(end 100.006404 -11.002518)
				)
				(arc
					(start 100.006404 -10.999978)
					(mid 100.400104 -10.606278)
					(end 100.793804 -10.999978)
				)
			)
		)
	)
	(zone
		(layers "F.Cu" "B.Cu" "In2.Cu")
		(hatch none 0.5)
		(connect_pads
			(clearance 0)
		)
		(min_thickness 0.25)
		(keepout
			(tracks not_allowed)
			(vias allowed)
			(pads allowed)
			(copperpour not_allowed)
			(footprints allowed)
		)
		(placement
			(enabled no)
			(sheetname "")
		)
		(fill yes
			(thermal_gap 0.5)
			(thermal_bridge_width 0.5)
			(island_removal_mode 0)
		)
		(polygon
			(pts
				(arc
					(start 106.361484 -9.800082)
					(mid 105.800144 -9.238742)
					(end 105.238804 -9.800082)
				)
				(arc
					(start 105.238804 -11.199876)
					(mid 105.798747 -11.761468)
					(end 106.361484 -11.20267)
				)
				(arc
					(start 106.193844 -11.20267)
					(mid 105.800144 -11.593838)
					(end 105.406444 -11.20267)
				)
				(arc
					(start 105.406444 -11.20013)
					(mid 105.800144 -10.80643)
					(end 106.193844 -11.20013)
				)
				(xy 106.361484 -11.20013) (xy 106.361484 -9.802622)
				(arc
					(start 106.193844 -9.802622)
					(mid 105.800144 -10.19379)
					(end 105.406444 -9.802622)
				)
				(arc
					(start 105.406444 -9.800082)
					(mid 105.800144 -9.406382)
					(end 106.193844 -9.800082)
				)
			)
		)
	)
	(zone
		(layers "F.Cu" "B.Cu" "In2.Cu")
		(hatch none 0.5)
		(connect_pads
			(clearance 0)
		)
		(min_thickness 0.25)
		(keepout
			(tracks not_allowed)
			(vias allowed)
			(pads allowed)
			(copperpour not_allowed)
			(footprints allowed)
		)
		(placement
			(enabled no)
			(sheetname "")
		)
		(fill yes
			(thermal_gap 0.5)
			(thermal_bridge_width 0.5)
			(island_removal_mode 0)
		)
		(polygon
			(pts
				(arc
					(start 95.561404 -9.800082)
					(mid 95.000064 -9.238742)
					(end 94.438724 -9.800082)
				)
				(arc
					(start 94.438724 -11.199876)
					(mid 94.998667 -11.761468)
					(end 95.561404 -11.20267)
				)
				(arc
					(start 95.393764 -11.20267)
					(mid 95.000064 -11.593838)
					(end 94.606364 -11.20267)
				)
				(arc
					(start 94.606364 -11.20013)
					(mid 95.000064 -10.80643)
					(end 95.393764 -11.20013)
				)
				(xy 95.561404 -11.20013) (xy 95.561404 -9.802622)
				(arc
					(start 95.393764 -9.802622)
					(mid 95.000064 -10.19379)
					(end 94.606364 -9.802622)
				)
				(arc
					(start 94.606364 -9.800082)
					(mid 95.000064 -9.406382)
					(end 95.393764 -9.800082)
				)
			)
		)
	)
	(zone
		(layers "F.Cu" "B.Cu" "In2.Cu")
		(hatch none 0.5)
		(connect_pads
			(clearance 0)
		)
		(min_thickness 0.25)
		(keepout
			(tracks not_allowed)
			(vias allowed)
			(pads allowed)
			(copperpour not_allowed)
			(footprints allowed)
		)
		(placement
			(enabled no)
			(sheetname "")
		)
		(fill yes
			(thermal_gap 0.5)
			(thermal_bridge_width 0.5)
			(island_removal_mode 0)
		)
		(polygon
			(pts
				(arc
					(start 135.161528 -9.800082)
					(mid 134.600188 -9.238742)
					(end 134.038848 -9.800082)
				)
				(arc
					(start 134.038848 -11.199876)
					(mid 134.598791 -11.761468)
					(end 135.161528 -11.20267)
				)
				(arc
					(start 134.993888 -11.20267)
					(mid 134.600188 -11.593838)
					(end 134.206488 -11.20267)
				)
				(arc
					(start 134.206488 -11.20013)
					(mid 134.600188 -10.80643)
					(end 134.993888 -11.20013)
				)
				(xy 135.161528 -11.20013) (xy 135.161528 -9.802622)
				(arc
					(start 134.993888 -9.802622)
					(mid 134.600188 -10.19379)
					(end 134.206488 -9.802622)
				)
				(arc
					(start 134.206488 -9.800082)
					(mid 134.600188 -9.406382)
					(end 134.993888 -9.800082)
				)
			)
		)
	)
	(zone
		(layers "F.Cu" "B.Cu" "In2.Cu")
		(hatch none 0.5)
		(connect_pads
			(clearance 0)
		)
		(min_thickness 0.25)
		(keepout
			(tracks not_allowed)
			(vias allowed)
			(pads allowed)
			(copperpour not_allowed)
			(footprints allowed)
		)
		(placement
			(enabled no)
			(sheetname "")
		)
		(fill yes
			(thermal_gap 0.5)
			(thermal_bridge_width 0.5)
			(island_removal_mode 0)
		)
		(polygon
			(pts
				(arc
					(start 86.561422 -10.999978)
					(mid 86.000082 -10.438638)
					(end 85.438742 -10.999978)
				)
				(arc
					(start 85.438742 -12.399772)
					(mid 85.998685 -12.961364)
					(end 86.561422 -12.402566)
				)
				(arc
					(start 86.393782 -12.402566)
					(mid 86.000082 -12.793734)
					(end 85.606382 -12.402566)
				)
				(arc
					(start 85.606382 -12.400026)
					(mid 86.000082 -12.006326)
					(end 86.393782 -12.400026)
				)
				(xy 86.561422 -12.400026) (xy 86.561422 -11.002518)
				(arc
					(start 86.393782 -11.002518)
					(mid 86.000082 -11.393686)
					(end 85.606382 -11.002518)
				)
				(arc
					(start 85.606382 -10.999978)
					(mid 86.000082 -10.606278)
					(end 86.393782 -10.999978)
				)
			)
		)
	)
	(zone
		(layers "F.Cu" "B.Cu" "In2.Cu")
		(hatch none 0.5)
		(connect_pads
			(clearance 0)
		)
		(min_thickness 0.25)
		(keepout
			(tracks not_allowed)
			(vias allowed)
			(pads allowed)
			(copperpour not_allowed)
			(footprints allowed)
		)
		(placement
			(enabled no)
			(sheetname "")
		)
		(fill yes
			(thermal_gap 0.5)
			(thermal_bridge_width 0.5)
			(island_removal_mode 0)
		)
		(polygon
			(pts
				(arc
					(start 144.16151 -10.999978)
					(mid 143.60017 -10.438638)
					(end 143.03883 -10.999978)
				)
				(arc
					(start 143.03883 -12.399772)
					(mid 143.598773 -12.961364)
					(end 144.16151 -12.402566)
				)
				(arc
					(start 143.99387 -12.402566)
					(mid 143.60017 -12.793734)
					(end 143.20647 -12.402566)
				)
				(arc
					(start 143.20647 -12.400026)
					(mid 143.60017 -12.006326)
					(end 143.99387 -12.400026)
				)
				(xy 144.16151 -12.400026) (xy 144.16151 -11.002518)
				(arc
					(start 143.99387 -11.002518)
					(mid 143.60017 -11.393686)
					(end 143.20647 -11.002518)
				)
				(arc
					(start 143.20647 -10.999978)
					(mid 143.60017 -10.606278)
					(end 143.99387 -10.999978)
				)
			)
		)
	)
	(zone
		(layers "F.Cu" "B.Cu" "In2.Cu")
		(hatch none 0.5)
		(connect_pads
			(clearance 0)
		)
		(min_thickness 0.25)
		(keepout
			(tracks not_allowed)
			(vias allowed)
			(pads allowed)
			(copperpour not_allowed)
			(footprints allowed)
		)
		(placement
			(enabled no)
			(sheetname "")
		)
		(fill yes
			(thermal_gap 0.5)
			(thermal_bridge_width 0.5)
			(island_removal_mode 0)
		)
		(polygon
			(pts
				(arc
					(start 147.761452 -10.999978)
					(mid 147.200112 -10.438638)
					(end 146.638772 -10.999978)
				)
				(arc
					(start 146.638772 -12.399772)
					(mid 147.198715 -12.961364)
					(end 147.761452 -12.402566)
				)
				(arc
					(start 147.593812 -12.402566)
					(mid 147.200112 -12.793734)
					(end 146.806412 -12.402566)
				)
				(arc
					(start 146.806412 -12.400026)
					(mid 147.200112 -12.006326)
					(end 147.593812 -12.400026)
				)
				(xy 147.761452 -12.400026) (xy 147.761452 -11.002518)
				(arc
					(start 147.593812 -11.002518)
					(mid 147.200112 -11.393686)
					(end 146.806412 -11.002518)
				)
				(arc
					(start 146.806412 -10.999978)
					(mid 147.200112 -10.606278)
					(end 147.593812 -10.999978)
				)
			)
		)
	)
	(zone
		(layers "F.Cu" "B.Cu" "In2.Cu")
		(hatch none 0.5)
		(connect_pads
			(clearance 0)
		)
		(min_thickness 0.25)
		(keepout
			(tracks not_allowed)
			(vias allowed)
			(pads allowed)
			(copperpour not_allowed)
			(footprints allowed)
		)
		(placement
			(enabled no)
			(sheetname "")
		)
		(fill yes
			(thermal_gap 0.5)
			(thermal_bridge_width 0.5)
			(island_removal_mode 0)
		)
		(polygon
			(pts
				(arc
					(start 111.761524 -10.999978)
					(mid 111.200184 -10.438638)
					(end 110.638844 -10.999978)
				)
				(arc
					(start 110.638844 -12.399772)
					(mid 111.198787 -12.961364)
					(end 111.761524 -12.402566)
				)
				(arc
					(start 111.593884 -12.402566)
					(mid 111.200184 -12.793734)
					(end 110.806484 -12.402566)
				)
				(arc
					(start 110.806484 -12.400026)
					(mid 111.200184 -12.006326)
					(end 111.593884 -12.400026)
				)
				(xy 111.761524 -12.400026) (xy 111.761524 -11.002518)
				(arc
					(start 111.593884 -11.002518)
					(mid 111.200184 -11.393686)
					(end 110.806484 -11.002518)
				)
				(arc
					(start 110.806484 -10.999978)
					(mid 111.200184 -10.606278)
					(end 111.593884 -10.999978)
				)
			)
		)
	)
	(zone
		(layers "F.Cu" "B.Cu" "In2.Cu")
		(hatch none 0.5)
		(connect_pads
			(clearance 0)
		)
		(min_thickness 0.25)
		(keepout
			(tracks not_allowed)
			(vias allowed)
			(pads allowed)
			(copperpour not_allowed)
			(footprints allowed)
		)
		(placement
			(enabled no)
			(sheetname "")
		)
		(fill yes
			(thermal_gap 0.5)
			(thermal_bridge_width 0.5)
			(island_removal_mode 0)
		)
		(polygon
			(pts
				(arc
					(start 131.561332 -9.800082)
					(mid 130.999992 -9.238742)
					(end 130.438652 -9.800082)
				)
				(arc
					(start 130.438652 -11.199876)
					(mid 130.998595 -11.761468)
					(end 131.561332 -11.20267)
				)
				(arc
					(start 131.393692 -11.20267)
					(mid 130.999992 -11.593838)
					(end 130.606292 -11.20267)
				)
				(arc
					(start 130.606292 -11.20013)
					(mid 130.999992 -10.80643)
					(end 131.393692 -11.20013)
				)
				(xy 131.561332 -11.20013) (xy 131.561332 -9.802622)
				(arc
					(start 131.393692 -9.802622)
					(mid 130.999992 -10.19379)
					(end 130.606292 -9.802622)
				)
				(arc
					(start 130.606292 -9.800082)
					(mid 130.999992 -9.406382)
					(end 131.393692 -9.800082)
				)
			)
		)
	)
	(zone
		(layers "F.Cu" "B.Cu" "In2.Cu")
		(hatch none 0.5)
		(connect_pads
			(clearance 0)
		)
		(min_thickness 0.25)
		(keepout
			(tracks not_allowed)
			(vias allowed)
			(pads allowed)
			(copperpour not_allowed)
			(footprints allowed)
		)
		(placement
			(enabled no)
			(sheetname "")
		)
		(fill yes
			(thermal_gap 0.5)
			(thermal_bridge_width 0.5)
			(island_removal_mode 0)
		)
		(polygon
			(pts
				(arc
					(start 191.361314 -3.800094)
					(mid 190.799974 -3.238754)
					(end 190.238634 -3.800094)
				)
				(arc
					(start 190.238634 -5.199888)
					(mid 190.798577 -5.76148)
					(end 191.361314 -5.202682)
				)
				(arc
					(start 191.193674 -5.202682)
					(mid 190.799974 -5.59385)
					(end 190.406274 -5.202682)
				)
				(arc
					(start 190.406274 -5.200142)
					(mid 190.799974 -4.806442)
					(end 191.193674 -5.200142)
				)
				(xy 191.361314 -5.200142) (xy 191.361314 -3.802634)
				(arc
					(start 191.193674 -3.802634)
					(mid 190.799974 -4.193802)
					(end 190.406274 -3.802634)
				)
				(arc
					(start 190.406274 -3.800094)
					(mid 190.799974 -3.406394)
					(end 191.193674 -3.800094)
				)
			)
		)
	)
	(zone
		(layers "F.Cu" "B.Cu" "In2.Cu")
		(hatch none 0.5)
		(connect_pads
			(clearance 0)
		)
		(min_thickness 0.25)
		(keepout
			(tracks not_allowed)
			(vias allowed)
			(pads allowed)
			(copperpour not_allowed)
			(footprints allowed)
		)
		(placement
			(enabled no)
			(sheetname "")
		)
		(fill yes
			(thermal_gap 0.5)
			(thermal_bridge_width 0.5)
			(island_removal_mode 0)
		)
		(polygon
			(pts
				(arc
					(start 97.361502 -10.999978)
					(mid 96.800162 -10.438638)
					(end 96.238822 -10.999978)
				)
				(arc
					(start 96.238822 -12.399772)
					(mid 96.798765 -12.961364)
					(end 97.361502 -12.402566)
				)
				(arc
					(start 97.193862 -12.402566)
					(mid 96.800162 -12.793734)
					(end 96.406462 -12.402566)
				)
				(arc
					(start 96.406462 -12.400026)
					(mid 96.800162 -12.006326)
					(end 97.193862 -12.400026)
				)
				(xy 97.361502 -12.400026) (xy 97.361502 -11.002518)
				(arc
					(start 97.193862 -11.002518)
					(mid 96.800162 -11.393686)
					(end 96.406462 -11.002518)
				)
				(arc
					(start 96.406462 -10.999978)
					(mid 96.800162 -10.606278)
					(end 97.193862 -10.999978)
				)
			)
		)
	)
	(zone
		(layers "F.Cu" "B.Cu" "In2.Cu")
		(hatch none 0.5)
		(connect_pads
			(clearance 0)
		)
		(min_thickness 0.25)
		(keepout
			(tracks not_allowed)
			(vias allowed)
			(pads allowed)
			(copperpour not_allowed)
			(footprints allowed)
		)
		(placement
			(enabled no)
			(sheetname "")
		)
		(fill yes
			(thermal_gap 0.5)
			(thermal_bridge_width 0.5)
			(island_removal_mode 0)
		)
		(polygon
			(pts
				(arc
					(start 99.161346 -9.800082)
					(mid 98.600006 -9.238742)
					(end 98.038666 -9.800082)
				)
				(arc
					(start 98.038666 -11.199876)
					(mid 98.598609 -11.761468)
					(end 99.161346 -11.20267)
				)
				(arc
					(start 98.993706 -11.20267)
					(mid 98.600006 -11.593838)
					(end 98.206306 -11.20267)
				)
				(arc
					(start 98.206306 -11.20013)
					(mid 98.600006 -10.80643)
					(end 98.993706 -11.20013)
				)
				(xy 99.161346 -11.20013) (xy 99.161346 -9.802622)
				(arc
					(start 98.993706 -9.802622)
					(mid 98.600006 -10.19379)
					(end 98.206306 -9.802622)
				)
				(arc
					(start 98.206306 -9.800082)
					(mid 98.600006 -9.406382)
					(end 98.993706 -9.800082)
				)
			)
		)
	)
	(zone
		(layers "F.Cu" "B.Cu" "In2.Cu")
		(hatch none 0.5)
		(connect_pads
			(clearance 0)
		)
		(min_thickness 0.25)
		(keepout
			(tracks not_allowed)
			(vias allowed)
			(pads allowed)
			(copperpour not_allowed)
			(footprints allowed)
		)
		(placement
			(enabled no)
			(sheetname "")
		)
		(fill yes
			(thermal_gap 0.5)
			(thermal_bridge_width 0.5)
			(island_removal_mode 0)
		)
		(polygon
			(pts
				(arc
					(start 103.996998 -103.450136)
					(mid 103.620914 -102.968008)
					(end 103.06177 -103.21544)
				)
				(xy 103.061008 -103.215186) (xy 102.311454 -104.614726) (xy 102.311454 -104.61498)
				(arc
					(start 102.311962 -104.615234)
					(mid 102.515416 -105.28808)
					(end 103.188262 -105.084626)
				)
				(xy 103.189024 -105.08488) (xy 103.313484 -104.85247)
				(arc
					(start 103.131112 -104.85247)
					(mid 102.750112 -105.230938)
					(end 102.369112 -104.85247)
				)
				(arc
					(start 102.369112 -104.84993)
					(mid 102.750112 -104.46893)
					(end 103.131112 -104.84993)
				)
				(xy 103.314754 -104.84993) (xy 103.938832 -103.685086)
				(arc
					(start 103.93807 -103.684832)
					(mid 103.981709 -103.572354)
					(end 103.996998 -103.452676)
				)
				(arc
					(start 103.88092 -103.452676)
					(mid 103.49992 -103.831144)
					(end 103.11892 -103.452676)
				)
				(arc
					(start 103.11892 -103.450136)
					(mid 103.49992 -103.069136)
					(end 103.88092 -103.450136)
				)
			)
		)
	)
	(zone
		(layers "F.Cu" "B.Cu" "In2.Cu")
		(hatch none 0.5)
		(connect_pads
			(clearance 0)
		)
		(min_thickness 0.25)
		(keepout
			(tracks not_allowed)
			(vias allowed)
			(pads allowed)
			(copperpour not_allowed)
			(footprints allowed)
		)
		(placement
			(enabled no)
			(sheetname "")
		)
		(fill yes
			(thermal_gap 0.5)
			(thermal_bridge_width 0.5)
			(island_removal_mode 0)
		)
		(polygon
			(pts
				(arc
					(start 184.161176 -3.800094)
					(mid 183.599836 -3.238754)
					(end 183.038496 -3.800094)
				)
				(arc
					(start 183.038496 -5.199888)
					(mid 183.598439 -5.76148)
					(end 184.161176 -5.202682)
				)
				(arc
					(start 183.993536 -5.202682)
					(mid 183.599836 -5.59385)
					(end 183.206136 -5.202682)
				)
				(arc
					(start 183.206136 -5.200142)
					(mid 183.599836 -4.806442)
					(end 183.993536 -5.200142)
				)
				(xy 184.161176 -5.200142) (xy 184.161176 -3.802634)
				(arc
					(start 183.993536 -3.802634)
					(mid 183.599836 -4.193802)
					(end 183.206136 -3.802634)
				)
				(arc
					(start 183.206136 -3.800094)
					(mid 183.599836 -3.406394)
					(end 183.993536 -3.800094)
				)
			)
		)
	)
	(zone
		(layers "F.Cu" "B.Cu" "In2.Cu")
		(hatch none 0.5)
		(connect_pads
			(clearance 0)
		)
		(min_thickness 0.25)
		(keepout
			(tracks not_allowed)
			(vias allowed)
			(pads allowed)
			(copperpour not_allowed)
			(footprints allowed)
		)
		(placement
			(enabled no)
			(sheetname "")
		)
		(fill yes
			(thermal_gap 0.5)
			(thermal_bridge_width 0.5)
			(island_removal_mode 0)
		)
		(polygon
			(pts
				(arc
					(start 109.961426 -9.800082)
					(mid 109.400086 -9.238742)
					(end 108.838746 -9.800082)
				)
				(arc
					(start 108.838746 -11.199876)
					(mid 109.398689 -11.761468)
					(end 109.961426 -11.20267)
				)
				(arc
					(start 109.793786 -11.20267)
					(mid 109.400086 -11.593838)
					(end 109.006386 -11.20267)
				)
				(arc
					(start 109.006386 -11.20013)
					(mid 109.400086 -10.80643)
					(end 109.793786 -11.20013)
				)
				(xy 109.961426 -11.20013) (xy 109.961426 -9.802622)
				(arc
					(start 109.793786 -9.802622)
					(mid 109.400086 -10.19379)
					(end 109.006386 -9.802622)
				)
				(arc
					(start 109.006386 -9.800082)
					(mid 109.400086 -9.406382)
					(end 109.793786 -9.800082)
				)
			)
		)
	)
	(zone
		(layers "F.Cu" "B.Cu" "In2.Cu")
		(hatch none 0.5)
		(connect_pads
			(clearance 0)
		)
		(min_thickness 0.25)
		(keepout
			(tracks not_allowed)
			(vias allowed)
			(pads allowed)
			(copperpour not_allowed)
			(footprints allowed)
		)
		(placement
			(enabled no)
			(sheetname "")
		)
		(fill yes
			(thermal_gap 0.5)
			(thermal_bridge_width 0.5)
			(island_removal_mode 0)
		)
		(polygon
			(pts
				(arc
					(start 106.247184 -107.249976)
					(mid 105.8711 -106.767848)
					(end 105.311956 -107.01528)
				)
				(xy 105.311194 -107.014772) (xy 104.561386 -108.41482) (xy 104.561386 -108.415074)
				(arc
					(start 104.561894 -108.415328)
					(mid 104.765348 -109.088174)
					(end 105.438194 -108.88472)
				)
				(xy 105.438956 -108.885228) (xy 105.56367 -108.652564)
				(arc
					(start 105.381044 -108.652564)
					(mid 105.000044 -109.031032)
					(end 104.619044 -108.652564)
				)
				(arc
					(start 104.619044 -108.650024)
					(mid 105.000044 -108.269024)
					(end 105.381044 -108.650024)
				)
				(xy 105.56494 -108.650024) (xy 106.189018 -107.48518)
				(arc
					(start 106.188256 -107.484672)
					(mid 106.231895 -107.372194)
					(end 106.247184 -107.252516)
				)
				(arc
					(start 106.131106 -107.252516)
					(mid 105.750106 -107.630984)
					(end 105.369106 -107.252516)
				)
				(arc
					(start 105.369106 -107.249976)
					(mid 105.750106 -106.868976)
					(end 106.131106 -107.249976)
				)
			)
		)
	)
	(zone
		(layers "F.Cu" "B.Cu" "In2.Cu")
		(hatch none 0.5)
		(connect_pads
			(clearance 0)
		)
		(min_thickness 0.25)
		(keepout
			(tracks not_allowed)
			(vias allowed)
			(pads allowed)
			(copperpour not_allowed)
			(footprints allowed)
		)
		(placement
			(enabled no)
			(sheetname "")
		)
		(fill yes
			(thermal_gap 0.5)
			(thermal_bridge_width 0.5)
			(island_removal_mode 0)
		)
		(polygon
			(pts
				(arc
					(start 138.76147 -9.800082)
					(mid 138.20013 -9.238742)
					(end 137.63879 -9.800082)
				)
				(arc
					(start 137.63879 -11.199876)
					(mid 138.198733 -11.761468)
					(end 138.76147 -11.20267)
				)
				(arc
					(start 138.59383 -11.20267)
					(mid 138.20013 -11.593838)
					(end 137.80643 -11.20267)
				)
				(arc
					(start 137.80643 -11.20013)
					(mid 138.20013 -10.80643)
					(end 138.59383 -11.20013)
				)
				(xy 138.76147 -11.20013) (xy 138.76147 -9.802622)
				(arc
					(start 138.59383 -9.802622)
					(mid 138.20013 -10.19379)
					(end 137.80643 -9.802622)
				)
				(arc
					(start 137.80643 -9.800082)
					(mid 138.20013 -9.406382)
					(end 138.59383 -9.800082)
				)
			)
		)
	)
	(zone
		(layers "F.Cu" "B.Cu" "In2.Cu")
		(hatch none 0.5)
		(connect_pads
			(clearance 0)
		)
		(min_thickness 0.25)
		(keepout
			(tracks not_allowed)
			(vias allowed)
			(pads allowed)
			(copperpour not_allowed)
			(footprints allowed)
		)
		(placement
			(enabled no)
			(sheetname "")
		)
		(fill yes
			(thermal_gap 0.5)
			(thermal_bridge_width 0.5)
			(island_removal_mode 0)
		)
		(polygon
			(pts
				(arc
					(start 102.761542 -9.800082)
					(mid 102.200202 -9.238742)
					(end 101.638862 -9.800082)
				)
				(arc
					(start 101.638862 -11.199876)
					(mid 102.198805 -11.761468)
					(end 102.761542 -11.20267)
				)
				(arc
					(start 102.593902 -11.20267)
					(mid 102.200202 -11.593838)
					(end 101.806502 -11.20267)
				)
				(arc
					(start 101.806502 -11.20013)
					(mid 102.200202 -10.80643)
					(end 102.593902 -11.20013)
				)
				(xy 102.761542 -11.20013) (xy 102.761542 -9.802622)
				(arc
					(start 102.593902 -9.802622)
					(mid 102.200202 -10.19379)
					(end 101.806502 -9.802622)
				)
				(arc
					(start 101.806502 -9.800082)
					(mid 102.200202 -9.406382)
					(end 102.593902 -9.800082)
				)
			)
		)
	)
	(zone
		(layers "F.Cu" "B.Cu" "In2.Cu")
		(hatch none 0.5)
		(connect_pads
			(clearance 0)
		)
		(min_thickness 0.25)
		(keepout
			(tracks not_allowed)
			(vias allowed)
			(pads allowed)
			(copperpour not_allowed)
			(footprints allowed)
		)
		(placement
			(enabled no)
			(sheetname "")
		)
		(fill yes
			(thermal_gap 0.5)
			(thermal_bridge_width 0.5)
			(island_removal_mode 0)
		)
		(polygon
			(pts
				(arc
					(start 182.361332 -2.600198)
					(mid 181.799992 -2.038858)
					(end 181.238652 -2.600198)
				)
				(arc
					(start 181.238652 -3.999738)
					(mid 181.798595 -4.56133)
					(end 182.361332 -4.002532)
				)
				(arc
					(start 182.193692 -4.002532)
					(mid 181.799992 -4.3937)
					(end 181.406292 -4.002532)
				)
				(arc
					(start 181.406292 -3.999992)
					(mid 181.799992 -3.606292)
					(end 182.193692 -3.999992)
				)
				(xy 182.361332 -3.999992) (xy 182.361332 -2.602738)
				(arc
					(start 182.193692 -2.602738)
					(mid 181.799992 -2.993906)
					(end 181.406292 -2.602738)
				)
				(arc
					(start 181.406292 -2.600198)
					(mid 181.799992 -2.206498)
					(end 182.193692 -2.600198)
				)
			)
		)
	)
	(zone
		(net "GND")
		(layers "F.Cu" "B.Cu" "In2.Cu" "In5.Cu")
		(hatch none 0.5)
		(connect_pads
			(clearance 0.5)
		)
		(min_thickness 0.25)
		(fill yes
			(thermal_gap 0.5)
			(thermal_bridge_width 0.5)
			(island_removal_mode 0)
		)
		(polygon
			(pts
				(arc
					(start 1.999996 -0.763016)
					(mid 1.125319 -1.125319)
					(end 0.763016 -1.999996)
				)
				(arc
					(start 0.763016 -142.999968)
					(mid 1.125319 -143.874645)
					(end 1.999996 -144.236948)
				)
				(arc
					(start 83.002882 -144.236948)
					(mid 83.866097 -143.885711)
					(end 84.2391 -143.031718)
				)
				(xy 84.2391 -142.904464) (xy 84.239608 -142.904464)
				(arc
					(start 84.239608 -132.262626)
					(mid 85.617496 -128.523498)
					(end 89.092024 -126.572264)
				)
				(xy 97.43948 -125.236986) (xy 112.560354 -125.236986)
				(arc
					(start 120.91289 -126.573026)
					(mid 124.387646 -128.524285)
					(end 125.76556 -132.263642)
				)
				(arc
					(start 125.76556 -142.999968)
					(mid 126.127863 -143.874645)
					(end 127.00254 -144.236948)
				)
				(arc
					(start 208.000092 -144.236948)
					(mid 208.874769 -143.874645)
					(end 209.237072 -142.999968)
				)
				(arc
					(start 209.237072 -1.999996)
					(mid 208.874769 -1.125319)
					(end 208.000092 -0.763016)
				)
				(xy 42.692828 -0.763016) (xy 42.692828 -2.032) (xy 207.968088 -2.032) (xy 207.968088 -142.967964)
				(xy 127.034544 -142.967964)
				(arc
					(start 127.034544 -132.263642)
					(mid 125.353147 -127.700998)
					(end 121.113296 -125.320044)
				)
				(xy 112.661192 -123.968002) (xy 97.338642 -123.968002)
				(arc
					(start 88.891618 -125.319282)
					(mid 84.651982 -127.70014)
					(end 82.970624 -132.262626)
				)
				(xy 82.970624 -143.031464) (xy 2.005584 -143.031464) (xy 1.9685 -142.99438) (xy 1.9685 -142.941548)
				(xy 2.005584 -142.904464) (xy 2.032 -142.904464) (xy 2.032 -2.032) (xy 26.16073 -2.032) (xy 26.16073 -0.763016)
			)
		)
	)
	(zone
		(layers "F.Cu" "In2.Cu" "In5.Cu")
		(hatch none 0.5)
		(connect_pads
			(clearance 0)
		)
		(min_thickness 0.25)
		(keepout
			(tracks not_allowed)
			(vias allowed)
			(pads allowed)
			(copperpour not_allowed)
			(footprints allowed)
		)
		(placement
			(enabled no)
			(sheetname "")
		)
		(fill yes
			(thermal_gap 0.5)
			(thermal_bridge_width 0.5)
			(island_removal_mode 0)
		)
		(polygon
			(pts
				(arc
					(start 117.16131 -2.600198)
					(mid 116.59997 -2.038858)
					(end 116.03863 -2.600198)
				)
				(arc
					(start 116.03863 -3.999738)
					(mid 116.598573 -4.56133)
					(end 117.16131 -4.002532)
				)
				(arc
					(start 116.99367 -4.002532)
					(mid 116.59997 -4.3937)
					(end 116.20627 -4.002532)
				)
				(arc
					(start 116.20627 -3.999992)
					(mid 116.59997 -3.606292)
					(end 116.99367 -3.999992)
				)
				(xy 117.16131 -3.999992) (xy 117.16131 -2.602738)
				(arc
					(start 116.99367 -2.602738)
					(mid 116.59997 -2.993906)
					(end 116.20627 -2.602738)
				)
				(arc
					(start 116.20627 -2.600198)
					(mid 116.59997 -2.206498)
					(end 116.99367 -2.600198)
				)
			)
		)
	)
	(zone
		(layers "F.Cu" "In2.Cu" "In5.Cu")
		(hatch none 0.5)
		(connect_pads
			(clearance 0)
		)
		(min_thickness 0.25)
		(keepout
			(tracks not_allowed)
			(vias allowed)
			(pads allowed)
			(copperpour not_allowed)
			(footprints allowed)
		)
		(placement
			(enabled no)
			(sheetname "")
		)
		(fill yes
			(thermal_gap 0.5)
			(thermal_bridge_width 0.5)
			(island_removal_mode 0)
		)
		(polygon
			(pts
				(arc
					(start 184.161176 -10.999978)
					(mid 183.599836 -10.438638)
					(end 183.038496 -10.999978)
				)
				(arc
					(start 183.038496 -12.399772)
					(mid 183.598439 -12.961364)
					(end 184.161176 -12.402566)
				)
				(arc
					(start 183.993536 -12.402566)
					(mid 183.599836 -12.793734)
					(end 183.206136 -12.402566)
				)
				(arc
					(start 183.206136 -12.400026)
					(mid 183.599836 -12.006326)
					(end 183.993536 -12.400026)
				)
				(xy 184.161176 -12.400026) (xy 184.161176 -11.002518)
				(arc
					(start 183.993536 -11.002518)
					(mid 183.599836 -11.393686)
					(end 183.206136 -11.002518)
				)
				(arc
					(start 183.206136 -10.999978)
					(mid 183.599836 -10.606278)
					(end 183.993536 -10.999978)
				)
			)
		)
	)
	(zone
		(layers "F.Cu" "In2.Cu" "In5.Cu")
		(hatch none 0.5)
		(connect_pads
			(clearance 0)
		)
		(min_thickness 0.25)
		(keepout
			(tracks not_allowed)
			(vias allowed)
			(pads allowed)
			(copperpour not_allowed)
			(footprints allowed)
		)
		(placement
			(enabled no)
			(sheetname "")
		)
		(fill yes
			(thermal_gap 0.5)
			(thermal_bridge_width 0.5)
			(island_removal_mode 0)
		)
		(polygon
			(pts
				(arc
					(start 97.361502 -3.800094)
					(mid 96.800162 -3.238754)
					(end 96.238822 -3.800094)
				)
				(arc
					(start 96.238822 -5.199888)
					(mid 96.798765 -5.76148)
					(end 97.361502 -5.202682)
				)
				(arc
					(start 97.193862 -5.202682)
					(mid 96.800162 -5.59385)
					(end 96.406462 -5.202682)
				)
				(arc
					(start 96.406462 -5.200142)
					(mid 96.800162 -4.806442)
					(end 97.193862 -5.200142)
				)
				(xy 97.361502 -5.200142) (xy 97.361502 -3.802634)
				(arc
					(start 97.193862 -3.802634)
					(mid 96.800162 -4.193802)
					(end 96.406462 -3.802634)
				)
				(arc
					(start 96.406462 -3.800094)
					(mid 96.800162 -3.406394)
					(end 97.193862 -3.800094)
				)
			)
		)
	)
	(zone
		(layers "F.Cu" "In2.Cu" "In5.Cu")
		(hatch none 0.5)
		(connect_pads
			(clearance 0)
		)
		(min_thickness 0.25)
		(keepout
			(tracks not_allowed)
			(vias allowed)
			(pads allowed)
			(copperpour not_allowed)
			(footprints allowed)
		)
		(placement
			(enabled no)
			(sheetname "")
		)
		(fill yes
			(thermal_gap 0.5)
			(thermal_bridge_width 0.5)
			(island_removal_mode 0)
		)
		(polygon
			(pts
				(arc
					(start 113.561368 -2.600198)
					(mid 113.000028 -2.038858)
					(end 112.438688 -2.600198)
				)
				(arc
					(start 112.438688 -3.999738)
					(mid 112.998631 -4.56133)
					(end 113.561368 -4.002532)
				)
				(arc
					(start 113.393728 -4.002532)
					(mid 113.000028 -4.3937)
					(end 112.606328 -4.002532)
				)
				(arc
					(start 112.606328 -3.999992)
					(mid 113.000028 -3.606292)
					(end 113.393728 -3.999992)
				)
				(xy 113.561368 -3.999992) (xy 113.561368 -2.602738)
				(arc
					(start 113.393728 -2.602738)
					(mid 113.000028 -2.993906)
					(end 112.606328 -2.602738)
				)
				(arc
					(start 112.606328 -2.600198)
					(mid 113.000028 -2.206498)
					(end 113.393728 -2.600198)
				)
			)
		)
	)
	(zone
		(layers "F.Cu" "In2.Cu" "In5.Cu")
		(hatch none 0.5)
		(connect_pads
			(clearance 0)
		)
		(min_thickness 0.25)
		(keepout
			(tracks not_allowed)
			(vias allowed)
			(pads allowed)
			(copperpour not_allowed)
			(footprints allowed)
		)
		(placement
			(enabled no)
			(sheetname "")
		)
		(fill yes
			(thermal_gap 0.5)
			(thermal_bridge_width 0.5)
			(island_removal_mode 0)
		)
		(polygon
			(pts
				(arc
					(start 131.561332 -2.600198)
					(mid 130.999992 -2.038858)
					(end 130.438652 -2.600198)
				)
				(arc
					(start 130.438652 -3.999738)
					(mid 130.998595 -4.56133)
					(end 131.561332 -4.002532)
				)
				(arc
					(start 131.393692 -4.002532)
					(mid 130.999992 -4.3937)
					(end 130.606292 -4.002532)
				)
				(arc
					(start 130.606292 -3.999992)
					(mid 130.999992 -3.606292)
					(end 131.393692 -3.999992)
				)
				(xy 131.561332 -3.999992) (xy 131.561332 -2.602738)
				(arc
					(start 131.393692 -2.602738)
					(mid 130.999992 -2.993906)
					(end 130.606292 -2.602738)
				)
				(arc
					(start 130.606292 -2.600198)
					(mid 130.999992 -2.206498)
					(end 131.393692 -2.600198)
				)
			)
		)
	)
	(zone
		(layers "F.Cu" "In2.Cu" "In5.Cu")
		(hatch none 0.5)
		(connect_pads
			(clearance 0)
		)
		(min_thickness 0.25)
		(keepout
			(tracks not_allowed)
			(vias allowed)
			(pads allowed)
			(copperpour not_allowed)
			(footprints allowed)
		)
		(placement
			(enabled no)
			(sheetname "")
		)
		(fill yes
			(thermal_gap 0.5)
			(thermal_bridge_width 0.5)
			(island_removal_mode 0)
		)
		(polygon
			(pts
				(arc
					(start 111.761524 -3.800094)
					(mid 111.200184 -3.238754)
					(end 110.638844 -3.800094)
				)
				(arc
					(start 110.638844 -5.199888)
					(mid 111.198787 -5.76148)
					(end 111.761524 -5.202682)
				)
				(arc
					(start 111.593884 -5.202682)
					(mid 111.200184 -5.59385)
					(end 110.806484 -5.202682)
				)
				(arc
					(start 110.806484 -5.200142)
					(mid 111.200184 -4.806442)
					(end 111.593884 -5.200142)
				)
				(xy 111.761524 -5.200142) (xy 111.761524 -3.802634)
				(arc
					(start 111.593884 -3.802634)
					(mid 111.200184 -4.193802)
					(end 110.806484 -3.802634)
				)
				(arc
					(start 110.806484 -3.800094)
					(mid 111.200184 -3.406394)
					(end 111.593884 -3.800094)
				)
			)
		)
	)
	(zone
		(layers "F.Cu" "In2.Cu" "In5.Cu")
		(hatch none 0.5)
		(connect_pads
			(clearance 0)
		)
		(min_thickness 0.25)
		(keepout
			(tracks not_allowed)
			(vias allowed)
			(pads allowed)
			(copperpour not_allowed)
			(footprints allowed)
		)
		(placement
			(enabled no)
			(sheetname "")
		)
		(fill yes
			(thermal_gap 0.5)
			(thermal_bridge_width 0.5)
			(island_removal_mode 0)
		)
		(polygon
			(pts
				(arc
					(start 104.04856 -114.84991)
					(mid 103.633478 -114.317774)
					(end 103.016304 -114.59083)
				)
				(xy 102.266496 -115.990624)
				(arc
					(start 102.266496 -115.990878)
					(mid 102.491032 -116.733574)
					(end 103.233728 -116.509038)
				)
				(xy 103.371142 -116.252498)
				(arc
					(start 103.131112 -116.252498)
					(mid 102.750112 -116.630966)
					(end 102.369112 -116.252498)
				)
				(arc
					(start 102.369112 -116.249958)
					(mid 102.750112 -115.868958)
					(end 103.131112 -116.249958)
				)
				(xy 103.372412 -116.249958)
				(arc
					(start 103.983536 -115.10899)
					(mid 104.031746 -114.984699)
					(end 104.04856 -114.85245)
				)
				(arc
					(start 103.88092 -114.85245)
					(mid 103.49992 -115.230918)
					(end 103.11892 -114.85245)
				)
				(arc
					(start 103.11892 -114.84991)
					(mid 103.49992 -114.46891)
					(end 103.88092 -114.84991)
				)
			)
		)
	)
	(zone
		(layers "F.Cu" "In2.Cu" "In5.Cu")
		(hatch none 0.5)
		(connect_pads
			(clearance 0)
		)
		(min_thickness 0.25)
		(keepout
			(tracks not_allowed)
			(vias allowed)
			(pads allowed)
			(copperpour not_allowed)
			(footprints allowed)
		)
		(placement
			(enabled no)
			(sheetname "")
		)
		(fill yes
			(thermal_gap 0.5)
			(thermal_bridge_width 0.5)
			(island_removal_mode 0)
		)
		(polygon
			(pts
				(arc
					(start 145.961354 -2.600198)
					(mid 145.400014 -2.038858)
					(end 144.838674 -2.600198)
				)
				(arc
					(start 144.838674 -3.999738)
					(mid 145.398617 -4.56133)
					(end 145.961354 -4.002532)
				)
				(arc
					(start 145.793714 -4.002532)
					(mid 145.400014 -4.3937)
					(end 145.006314 -4.002532)
				)
				(arc
					(start 145.006314 -3.999992)
					(mid 145.400014 -3.606292)
					(end 145.793714 -3.999992)
				)
				(xy 145.961354 -3.999992) (xy 145.961354 -2.602738)
				(arc
					(start 145.793714 -2.602738)
					(mid 145.400014 -2.993906)
					(end 145.006314 -2.602738)
				)
				(arc
					(start 145.006314 -2.600198)
					(mid 145.400014 -2.206498)
					(end 145.793714 -2.600198)
				)
			)
		)
	)
	(zone
		(layers "F.Cu" "In2.Cu" "In5.Cu")
		(hatch none 0.5)
		(connect_pads
			(clearance 0)
		)
		(min_thickness 0.25)
		(keepout
			(tracks not_allowed)
			(vias allowed)
			(pads allowed)
			(copperpour not_allowed)
			(footprints allowed)
		)
		(placement
			(enabled no)
			(sheetname "")
		)
		(fill yes
			(thermal_gap 0.5)
			(thermal_bridge_width 0.5)
			(island_removal_mode 0)
		)
		(polygon
			(pts
				(arc
					(start 191.361314 -10.999978)
					(mid 190.799974 -10.438638)
					(end 190.238634 -10.999978)
				)
				(arc
					(start 190.238634 -12.399772)
					(mid 190.798577 -12.961364)
					(end 191.361314 -12.402566)
				)
				(arc
					(start 191.193674 -12.402566)
					(mid 190.799974 -12.793734)
					(end 190.406274 -12.402566)
				)
				(arc
					(start 190.406274 -12.400026)
					(mid 190.799974 -12.006326)
					(end 191.193674 -12.400026)
				)
				(xy 191.361314 -12.400026) (xy 191.361314 -11.002518)
				(arc
					(start 191.193674 -11.002518)
					(mid 190.799974 -11.393686)
					(end 190.406274 -11.002518)
				)
				(arc
					(start 190.406274 -10.999978)
					(mid 190.799974 -10.606278)
					(end 191.193674 -10.999978)
				)
			)
		)
	)
	(zone
		(layers "F.Cu" "In2.Cu" "In5.Cu")
		(hatch none 0.5)
		(connect_pads
			(clearance 0)
		)
		(min_thickness 0.25)
		(keepout
			(tracks not_allowed)
			(vias allowed)
			(pads allowed)
			(copperpour not_allowed)
			(footprints allowed)
		)
		(placement
			(enabled no)
			(sheetname "")
		)
		(fill yes
			(thermal_gap 0.5)
			(thermal_bridge_width 0.5)
			(island_removal_mode 0)
		)
		(polygon
			(pts
				(arc
					(start 120.761506 -2.600198)
					(mid 120.200166 -2.038858)
					(end 119.638826 -2.600198)
				)
				(arc
					(start 119.638826 -3.999738)
					(mid 120.198769 -4.56133)
					(end 120.761506 -4.002532)
				)
				(arc
					(start 120.593866 -4.002532)
					(mid 120.200166 -4.3937)
					(end 119.806466 -4.002532)
				)
				(arc
					(start 119.806466 -3.999992)
					(mid 120.200166 -3.606292)
					(end 120.593866 -3.999992)
				)
				(xy 120.761506 -3.999992) (xy 120.761506 -2.602738)
				(arc
					(start 120.593866 -2.602738)
					(mid 120.200166 -2.993906)
					(end 119.806466 -2.602738)
				)
				(arc
					(start 119.806466 -2.600198)
					(mid 120.200166 -2.206498)
					(end 120.593866 -2.600198)
				)
			)
		)
	)
	(zone
		(layers "F.Cu" "In2.Cu" "In5.Cu")
		(hatch none 0.5)
		(connect_pads
			(clearance 0)
		)
		(min_thickness 0.25)
		(keepout
			(tracks not_allowed)
			(vias allowed)
			(pads allowed)
			(copperpour not_allowed)
			(footprints allowed)
		)
		(placement
			(enabled no)
			(sheetname "")
		)
		(fill yes
			(thermal_gap 0.5)
			(thermal_bridge_width 0.5)
			(island_removal_mode 0)
		)
		(polygon
			(pts
				(arc
					(start 144.16151 -3.800094)
					(mid 143.60017 -3.238754)
					(end 143.03883 -3.800094)
				)
				(arc
					(start 143.03883 -5.199888)
					(mid 143.598773 -5.76148)
					(end 144.16151 -5.202682)
				)
				(arc
					(start 143.99387 -5.202682)
					(mid 143.60017 -5.59385)
					(end 143.20647 -5.202682)
				)
				(arc
					(start 143.20647 -5.200142)
					(mid 143.60017 -4.806442)
					(end 143.99387 -5.200142)
				)
				(xy 144.16151 -5.200142) (xy 144.16151 -3.802634)
				(arc
					(start 143.99387 -3.802634)
					(mid 143.60017 -4.193802)
					(end 143.20647 -3.802634)
				)
				(arc
					(start 143.20647 -3.800094)
					(mid 143.60017 -3.406394)
					(end 143.99387 -3.800094)
				)
			)
		)
	)
	(zone
		(layers "F.Cu" "In2.Cu" "In5.Cu")
		(hatch none 0.5)
		(connect_pads
			(clearance 0)
		)
		(min_thickness 0.25)
		(keepout
			(tracks not_allowed)
			(vias allowed)
			(pads allowed)
			(copperpour not_allowed)
			(footprints allowed)
		)
		(placement
			(enabled no)
			(sheetname "")
		)
		(fill yes
			(thermal_gap 0.5)
			(thermal_bridge_width 0.5)
			(island_removal_mode 0)
		)
		(polygon
			(pts
				(arc
					(start 126.161546 -3.800094)
					(mid 125.600206 -3.238754)
					(end 125.038866 -3.800094)
				)
				(arc
					(start 125.038866 -5.199888)
					(mid 125.598809 -5.76148)
					(end 126.161546 -5.202682)
				)
				(arc
					(start 125.993906 -5.202682)
					(mid 125.600206 -5.59385)
					(end 125.206506 -5.202682)
				)
				(arc
					(start 125.206506 -5.200142)
					(mid 125.600206 -4.806442)
					(end 125.993906 -5.200142)
				)
				(xy 126.161546 -5.200142) (xy 126.161546 -3.802634)
				(arc
					(start 125.993906 -3.802634)
					(mid 125.600206 -4.193802)
					(end 125.206506 -3.802634)
				)
				(arc
					(start 125.206506 -3.800094)
					(mid 125.600206 -3.406394)
					(end 125.993906 -3.800094)
				)
			)
		)
	)
	(zone
		(layers "F.Cu" "In2.Cu" "In5.Cu")
		(hatch none 0.5)
		(connect_pads
			(clearance 0)
		)
		(min_thickness 0.25)
		(keepout
			(tracks not_allowed)
			(vias allowed)
			(pads allowed)
			(copperpour not_allowed)
			(footprints allowed)
		)
		(placement
			(enabled no)
			(sheetname "")
		)
		(fill yes
			(thermal_gap 0.5)
			(thermal_bridge_width 0.5)
			(island_removal_mode 0)
		)
		(polygon
			(pts
				(arc
					(start 90.161364 -3.800094)
					(mid 89.600024 -3.238754)
					(end 89.038684 -3.800094)
				)
				(arc
					(start 89.038684 -5.199888)
					(mid 89.598627 -5.76148)
					(end 90.161364 -5.202682)
				)
				(arc
					(start 89.993724 -5.202682)
					(mid 89.600024 -5.59385)
					(end 89.206324 -5.202682)
				)
				(arc
					(start 89.206324 -5.200142)
					(mid 89.600024 -4.806442)
					(end 89.993724 -5.200142)
				)
				(xy 90.161364 -5.200142) (xy 90.161364 -3.802634)
				(arc
					(start 89.993724 -3.802634)
					(mid 89.600024 -4.193802)
					(end 89.206324 -3.802634)
				)
				(arc
					(start 89.206324 -3.800094)
					(mid 89.600024 -3.406394)
					(end 89.993724 -3.800094)
				)
			)
		)
	)
	(zone
		(layers "F.Cu" "In2.Cu" "In5.Cu")
		(hatch none 0.5)
		(connect_pads
			(clearance 0)
		)
		(min_thickness 0.25)
		(keepout
			(tracks not_allowed)
			(vias allowed)
			(pads allowed)
			(copperpour not_allowed)
			(footprints allowed)
		)
		(placement
			(enabled no)
			(sheetname "")
		)
		(fill yes
			(thermal_gap 0.5)
			(thermal_bridge_width 0.5)
			(island_removal_mode 0)
		)
		(polygon
			(pts
				(arc
					(start 185.961274 -9.800082)
					(mid 185.399934 -9.238742)
					(end 184.838594 -9.800082)
				)
				(arc
					(start 184.838594 -11.199876)
					(mid 185.398537 -11.761468)
					(end 185.961274 -11.20267)
				)
				(arc
					(start 185.793634 -11.20267)
					(mid 185.399934 -11.593838)
					(end 185.006234 -11.20267)
				)
				(arc
					(start 185.006234 -11.20013)
					(mid 185.399934 -10.80643)
					(end 185.793634 -11.20013)
				)
				(xy 185.961274 -11.20013) (xy 185.961274 -9.802622)
				(arc
					(start 185.793634 -9.802622)
					(mid 185.399934 -10.19379)
					(end 185.006234 -9.802622)
				)
				(arc
					(start 185.006234 -9.800082)
					(mid 185.399934 -9.406382)
					(end 185.793634 -9.800082)
				)
			)
		)
	)
	(zone
		(layers "F.Cu" "In2.Cu" "In5.Cu")
		(hatch none 0.5)
		(connect_pads
			(clearance 0)
		)
		(min_thickness 0.25)
		(keepout
			(tracks not_allowed)
			(vias allowed)
			(pads allowed)
			(copperpour not_allowed)
			(footprints allowed)
		)
		(placement
			(enabled no)
			(sheetname "")
		)
		(fill yes
			(thermal_gap 0.5)
			(thermal_bridge_width 0.5)
			(island_removal_mode 0)
		)
		(polygon
			(pts
				(arc
					(start 129.761488 -3.800094)
					(mid 129.200148 -3.238754)
					(end 128.638808 -3.800094)
				)
				(arc
					(start 128.638808 -5.199888)
					(mid 129.198751 -5.76148)
					(end 129.761488 -5.202682)
				)
				(arc
					(start 129.593848 -5.202682)
					(mid 129.200148 -5.59385)
					(end 128.806448 -5.202682)
				)
				(arc
					(start 128.806448 -5.200142)
					(mid 129.200148 -4.806442)
					(end 129.593848 -5.200142)
				)
				(xy 129.761488 -5.200142) (xy 129.761488 -3.802634)
				(arc
					(start 129.593848 -3.802634)
					(mid 129.200148 -4.193802)
					(end 128.806448 -3.802634)
				)
				(arc
					(start 128.806448 -3.800094)
					(mid 129.200148 -3.406394)
					(end 129.593848 -3.800094)
				)
			)
		)
	)
	(zone
		(layers "F.Cu" "In2.Cu" "In5.Cu")
		(hatch none 0.5)
		(connect_pads
			(clearance 0)
		)
		(min_thickness 0.25)
		(keepout
			(tracks not_allowed)
			(vias allowed)
			(pads allowed)
			(copperpour not_allowed)
			(footprints allowed)
		)
		(placement
			(enabled no)
			(sheetname "")
		)
		(fill yes
			(thermal_gap 0.5)
			(thermal_bridge_width 0.5)
			(island_removal_mode 0)
		)
		(polygon
			(pts
				(arc
					(start 95.561404 -2.600198)
					(mid 95.000064 -2.038858)
					(end 94.438724 -2.600198)
				)
				(arc
					(start 94.438724 -3.999738)
					(mid 94.998667 -4.56133)
					(end 95.561404 -4.002532)
				)
				(arc
					(start 95.393764 -4.002532)
					(mid 95.000064 -4.3937)
					(end 94.606364 -4.002532)
				)
				(arc
					(start 94.606364 -3.999992)
					(mid 95.000064 -3.606292)
					(end 95.393764 -3.999992)
				)
				(xy 95.561404 -3.999992) (xy 95.561404 -2.602738)
				(arc
					(start 95.393764 -2.602738)
					(mid 95.000064 -2.993906)
					(end 94.606364 -2.602738)
				)
				(arc
					(start 94.606364 -2.600198)
					(mid 95.000064 -2.206498)
					(end 95.393764 -2.600198)
				)
			)
		)
	)
	(zone
		(layers "F.Cu" "In2.Cu" "In5.Cu")
		(hatch none 0.5)
		(connect_pads
			(clearance 0)
		)
		(min_thickness 0.25)
		(keepout
			(tracks not_allowed)
			(vias allowed)
			(pads allowed)
			(copperpour not_allowed)
			(footprints allowed)
		)
		(placement
			(enabled no)
			(sheetname "")
		)
		(fill yes
			(thermal_gap 0.5)
			(thermal_bridge_width 0.5)
			(island_removal_mode 0)
		)
		(polygon
			(pts
				(arc
					(start 91.961462 -2.600198)
					(mid 91.400122 -2.038858)
					(end 90.838782 -2.600198)
				)
				(arc
					(start 90.838782 -3.999738)
					(mid 91.398725 -4.56133)
					(end 91.961462 -4.002532)
				)
				(arc
					(start 91.793822 -4.002532)
					(mid 91.400122 -4.3937)
					(end 91.006422 -4.002532)
				)
				(arc
					(start 91.006422 -3.999992)
					(mid 91.400122 -3.606292)
					(end 91.793822 -3.999992)
				)
				(xy 91.961462 -3.999992) (xy 91.961462 -2.602738)
				(arc
					(start 91.793822 -2.602738)
					(mid 91.400122 -2.993906)
					(end 91.006422 -2.602738)
				)
				(arc
					(start 91.006422 -2.600198)
					(mid 91.400122 -2.206498)
					(end 91.793822 -2.600198)
				)
			)
		)
	)
	(zone
		(layers "F.Cu" "In2.Cu" "In5.Cu")
		(hatch none 0.5)
		(connect_pads
			(clearance 0)
		)
		(min_thickness 0.25)
		(keepout
			(tracks not_allowed)
			(vias allowed)
			(pads allowed)
			(copperpour not_allowed)
			(footprints allowed)
		)
		(placement
			(enabled no)
			(sheetname "")
		)
		(fill yes
			(thermal_gap 0.5)
			(thermal_bridge_width 0.5)
			(island_removal_mode 0)
		)
		(polygon
			(pts
				(arc
					(start 99.161346 -2.600198)
					(mid 98.600006 -2.038858)
					(end 98.038666 -2.600198)
				)
				(arc
					(start 98.038666 -3.999738)
					(mid 98.598609 -4.56133)
					(end 99.161346 -4.002532)
				)
				(arc
					(start 98.993706 -4.002532)
					(mid 98.600006 -4.3937)
					(end 98.206306 -4.002532)
				)
				(arc
					(start 98.206306 -3.999992)
					(mid 98.600006 -3.606292)
					(end 98.993706 -3.999992)
				)
				(xy 99.161346 -3.999992) (xy 99.161346 -2.602738)
				(arc
					(start 98.993706 -2.602738)
					(mid 98.600006 -2.993906)
					(end 98.206306 -2.602738)
				)
				(arc
					(start 98.206306 -2.600198)
					(mid 98.600006 -2.206498)
					(end 98.993706 -2.600198)
				)
			)
		)
	)
	(zone
		(layers "F.Cu" "In2.Cu" "In5.Cu")
		(hatch none 0.5)
		(connect_pads
			(clearance 0)
		)
		(min_thickness 0.25)
		(keepout
			(tracks not_allowed)
			(vias allowed)
			(pads allowed)
			(copperpour not_allowed)
			(footprints allowed)
		)
		(placement
			(enabled no)
			(sheetname "")
		)
		(fill yes
			(thermal_gap 0.5)
			(thermal_bridge_width 0.5)
			(island_removal_mode 0)
		)
		(polygon
			(pts
				(arc
					(start 104.561386 -3.800094)
					(mid 104.000046 -3.238754)
					(end 103.438706 -3.800094)
				)
				(arc
					(start 103.438706 -5.199888)
					(mid 103.998649 -5.76148)
					(end 104.561386 -5.202682)
				)
				(arc
					(start 104.393746 -5.202682)
					(mid 104.000046 -5.59385)
					(end 103.606346 -5.202682)
				)
				(arc
					(start 103.606346 -5.200142)
					(mid 104.000046 -4.806442)
					(end 104.393746 -5.200142)
				)
				(xy 104.561386 -5.200142) (xy 104.561386 -3.802634)
				(arc
					(start 104.393746 -3.802634)
					(mid 104.000046 -4.193802)
					(end 103.606346 -3.802634)
				)
				(arc
					(start 103.606346 -3.800094)
					(mid 104.000046 -3.406394)
					(end 104.393746 -3.800094)
				)
			)
		)
	)
	(zone
		(layers "F.Cu" "In2.Cu" "In5.Cu")
		(hatch none 0.5)
		(connect_pads
			(clearance 0)
		)
		(min_thickness 0.25)
		(keepout
			(tracks not_allowed)
			(vias allowed)
			(pads allowed)
			(copperpour not_allowed)
			(footprints allowed)
		)
		(placement
			(enabled no)
			(sheetname "")
		)
		(fill yes
			(thermal_gap 0.5)
			(thermal_bridge_width 0.5)
			(island_removal_mode 0)
		)
		(polygon
			(pts
				(arc
					(start 109.961426 -2.600198)
					(mid 109.400086 -2.038858)
					(end 108.838746 -2.600198)
				)
				(arc
					(start 108.838746 -3.999738)
					(mid 109.398689 -4.56133)
					(end 109.961426 -4.002532)
				)
				(arc
					(start 109.793786 -4.002532)
					(mid 109.400086 -4.3937)
					(end 109.006386 -4.002532)
				)
				(arc
					(start 109.006386 -3.999992)
					(mid 109.400086 -3.606292)
					(end 109.793786 -3.999992)
				)
				(xy 109.961426 -3.999992) (xy 109.961426 -2.602738)
				(arc
					(start 109.793786 -2.602738)
					(mid 109.400086 -2.993906)
					(end 109.006386 -2.602738)
				)
				(arc
					(start 109.006386 -2.600198)
					(mid 109.400086 -2.206498)
					(end 109.793786 -2.600198)
				)
			)
		)
	)
	(zone
		(layers "F.Cu" "In2.Cu" "In5.Cu")
		(hatch none 0.5)
		(connect_pads
			(clearance 0)
		)
		(min_thickness 0.25)
		(keepout
			(tracks not_allowed)
			(vias allowed)
			(pads allowed)
			(copperpour not_allowed)
			(footprints allowed)
		)
		(placement
			(enabled no)
			(sheetname "")
		)
		(fill yes
			(thermal_gap 0.5)
			(thermal_bridge_width 0.5)
			(island_removal_mode 0)
		)
		(polygon
			(pts
				(arc
					(start 180.561234 -10.999978)
					(mid 179.999894 -10.438638)
					(end 179.438554 -10.999978)
				)
				(arc
					(start 179.438554 -12.399772)
					(mid 179.998497 -12.961364)
					(end 180.561234 -12.402566)
				)
				(arc
					(start 180.393594 -12.402566)
					(mid 179.999894 -12.793734)
					(end 179.606194 -12.402566)
				)
				(arc
					(start 179.606194 -12.400026)
					(mid 179.999894 -12.006326)
					(end 180.393594 -12.400026)
				)
				(xy 180.561234 -12.400026) (xy 180.561234 -11.002518)
				(arc
					(start 180.393594 -11.002518)
					(mid 179.999894 -11.393686)
					(end 179.606194 -11.002518)
				)
				(arc
					(start 179.606194 -10.999978)
					(mid 179.999894 -10.606278)
					(end 180.393594 -10.999978)
				)
			)
		)
	)
	(zone
		(layers "F.Cu" "In2.Cu" "In5.Cu")
		(hatch none 0.5)
		(connect_pads
			(clearance 0)
		)
		(min_thickness 0.25)
		(keepout
			(tracks not_allowed)
			(vias allowed)
			(pads allowed)
			(copperpour not_allowed)
			(footprints allowed)
		)
		(placement
			(enabled no)
			(sheetname "")
		)
		(fill yes
			(thermal_gap 0.5)
			(thermal_bridge_width 0.5)
			(island_removal_mode 0)
		)
		(polygon
			(pts
				(arc
					(start 189.561216 -9.800082)
					(mid 188.999876 -9.238742)
					(end 188.438536 -9.800082)
				)
				(arc
					(start 188.438536 -11.199876)
					(mid 188.998479 -11.761468)
					(end 189.561216 -11.20267)
				)
				(arc
					(start 189.393576 -11.20267)
					(mid 188.999876 -11.593838)
					(end 188.606176 -11.20267)
				)
				(arc
					(start 188.606176 -11.20013)
					(mid 188.999876 -10.80643)
					(end 189.393576 -11.20013)
				)
				(xy 189.561216 -11.20013) (xy 189.561216 -9.802622)
				(arc
					(start 189.393576 -9.802622)
					(mid 188.999876 -10.19379)
					(end 188.606176 -9.802622)
				)
				(arc
					(start 188.606176 -9.800082)
					(mid 188.999876 -9.406382)
					(end 189.393576 -9.800082)
				)
			)
		)
	)
	(zone
		(layers "F.Cu" "In2.Cu" "In5.Cu")
		(hatch none 0.5)
		(connect_pads
			(clearance 0)
		)
		(min_thickness 0.25)
		(keepout
			(tracks not_allowed)
			(vias allowed)
			(pads allowed)
			(copperpour not_allowed)
			(footprints allowed)
		)
		(placement
			(enabled no)
			(sheetname "")
		)
		(fill yes
			(thermal_gap 0.5)
			(thermal_bridge_width 0.5)
			(island_removal_mode 0)
		)
		(polygon
			(pts
				(arc
					(start 193.161158 -9.800082)
					(mid 192.599818 -9.238742)
					(end 192.038478 -9.800082)
				)
				(arc
					(start 192.038478 -11.199876)
					(mid 192.598421 -11.761468)
					(end 193.161158 -11.20267)
				)
				(arc
					(start 192.993518 -11.20267)
					(mid 192.599818 -11.593838)
					(end 192.206118 -11.20267)
				)
				(arc
					(start 192.206118 -11.20013)
					(mid 192.599818 -10.80643)
					(end 192.993518 -11.20013)
				)
				(xy 193.161158 -11.20013) (xy 193.161158 -9.802622)
				(arc
					(start 192.993518 -9.802622)
					(mid 192.599818 -10.19379)
					(end 192.206118 -9.802622)
				)
				(arc
					(start 192.206118 -9.800082)
					(mid 192.599818 -9.406382)
					(end 192.993518 -9.800082)
				)
			)
		)
	)
	(zone
		(layers "F.Cu" "In2.Cu" "In5.Cu")
		(hatch none 0.5)
		(connect_pads
			(clearance 0)
		)
		(min_thickness 0.25)
		(keepout
			(tracks not_allowed)
			(vias allowed)
			(pads allowed)
			(copperpour not_allowed)
			(footprints allowed)
		)
		(placement
			(enabled no)
			(sheetname "")
		)
		(fill yes
			(thermal_gap 0.5)
			(thermal_bridge_width 0.5)
			(island_removal_mode 0)
		)
		(polygon
			(pts
				(arc
					(start 108.161328 -3.800094)
					(mid 107.599988 -3.238754)
					(end 107.038648 -3.800094)
				)
				(arc
					(start 107.038648 -5.199888)
					(mid 107.598591 -5.76148)
					(end 108.161328 -5.202682)
				)
				(arc
					(start 107.993688 -5.202682)
					(mid 107.599988 -5.59385)
					(end 107.206288 -5.202682)
				)
				(arc
					(start 107.206288 -5.200142)
					(mid 107.599988 -4.806442)
					(end 107.993688 -5.200142)
				)
				(xy 108.161328 -5.200142) (xy 108.161328 -3.802634)
				(arc
					(start 107.993688 -3.802634)
					(mid 107.599988 -4.193802)
					(end 107.206288 -3.802634)
				)
				(arc
					(start 107.206288 -3.800094)
					(mid 107.599988 -3.406394)
					(end 107.993688 -3.800094)
				)
			)
		)
	)
	(zone
		(layers "F.Cu" "In2.Cu" "In5.Cu")
		(hatch none 0.5)
		(connect_pads
			(clearance 0)
		)
		(min_thickness 0.25)
		(keepout
			(tracks not_allowed)
			(vias allowed)
			(pads allowed)
			(copperpour not_allowed)
			(footprints allowed)
		)
		(placement
			(enabled no)
			(sheetname "")
		)
		(fill yes
			(thermal_gap 0.5)
			(thermal_bridge_width 0.5)
			(island_removal_mode 0)
		)
		(polygon
			(pts
				(arc
					(start 149.561296 -2.600198)
					(mid 148.999956 -2.038858)
					(end 148.438616 -2.600198)
				)
				(arc
					(start 148.438616 -3.999738)
					(mid 148.998559 -4.56133)
					(end 149.561296 -4.002532)
				)
				(arc
					(start 149.393656 -4.002532)
					(mid 148.999956 -4.3937)
					(end 148.606256 -4.002532)
				)
				(arc
					(start 148.606256 -3.999992)
					(mid 148.999956 -3.606292)
					(end 149.393656 -3.999992)
				)
				(xy 149.561296 -3.999992) (xy 149.561296 -2.602738)
				(arc
					(start 149.393656 -2.602738)
					(mid 148.999956 -2.993906)
					(end 148.606256 -2.602738)
				)
				(arc
					(start 148.606256 -2.600198)
					(mid 148.999956 -2.206498)
					(end 149.393656 -2.600198)
				)
			)
		)
	)
	(zone
		(layers "F.Cu" "In2.Cu" "In5.Cu")
		(hatch none 0.5)
		(connect_pads
			(clearance 0)
		)
		(min_thickness 0.25)
		(keepout
			(tracks not_allowed)
			(vias allowed)
			(pads allowed)
			(copperpour not_allowed)
			(footprints allowed)
		)
		(placement
			(enabled no)
			(sheetname "")
		)
		(fill yes
			(thermal_gap 0.5)
			(thermal_bridge_width 0.5)
			(island_removal_mode 0)
		)
		(polygon
			(pts
				(arc
					(start 106.298746 -111.05007)
					(mid 105.883664 -110.517934)
					(end 105.26649 -110.79099)
				)
				(arc
					(start 104.516428 -112.190784)
					(mid 104.740809 -112.933787)
					(end 105.48366 -112.709198)
				)
				(xy 105.621074 -112.452658)
				(arc
					(start 105.381044 -112.452658)
					(mid 105.000044 -112.831126)
					(end 104.619044 -112.452658)
				)
				(arc
					(start 104.619044 -112.450118)
					(mid 105.000044 -112.069118)
					(end 105.381044 -112.450118)
				)
				(xy 105.622344 -112.450118)
				(arc
					(start 106.233722 -111.30915)
					(mid 106.281932 -111.184859)
					(end 106.298746 -111.05261)
				)
				(arc
					(start 106.131106 -111.05261)
					(mid 105.750106 -111.431078)
					(end 105.369106 -111.05261)
				)
				(arc
					(start 105.369106 -111.05007)
					(mid 105.750106 -110.66907)
					(end 106.131106 -111.05007)
				)
			)
		)
	)
	(zone
		(layers "F.Cu" "In2.Cu" "In5.Cu")
		(hatch none 0.5)
		(connect_pads
			(clearance 0)
		)
		(min_thickness 0.25)
		(keepout
			(tracks not_allowed)
			(vias allowed)
			(pads allowed)
			(copperpour not_allowed)
			(footprints allowed)
		)
		(placement
			(enabled no)
			(sheetname "")
		)
		(fill yes
			(thermal_gap 0.5)
			(thermal_bridge_width 0.5)
			(island_removal_mode 0)
		)
		(polygon
			(pts
				(arc
					(start 138.76147 -2.600198)
					(mid 138.20013 -2.038858)
					(end 137.63879 -2.600198)
				)
				(arc
					(start 137.63879 -3.999738)
					(mid 138.198733 -4.56133)
					(end 138.76147 -4.002532)
				)
				(arc
					(start 138.59383 -4.002532)
					(mid 138.20013 -4.3937)
					(end 137.80643 -4.002532)
				)
				(arc
					(start 137.80643 -3.999992)
					(mid 138.20013 -3.606292)
					(end 138.59383 -3.999992)
				)
				(xy 138.76147 -3.999992) (xy 138.76147 -2.602738)
				(arc
					(start 138.59383 -2.602738)
					(mid 138.20013 -2.993906)
					(end 137.80643 -2.602738)
				)
				(arc
					(start 137.80643 -2.600198)
					(mid 138.20013 -2.206498)
					(end 138.59383 -2.600198)
				)
			)
		)
	)
	(zone
		(layers "F.Cu" "In2.Cu" "In5.Cu")
		(hatch none 0.5)
		(connect_pads
			(clearance 0)
		)
		(min_thickness 0.25)
		(keepout
			(tracks not_allowed)
			(vias allowed)
			(pads allowed)
			(copperpour not_allowed)
			(footprints allowed)
		)
		(placement
			(enabled no)
			(sheetname "")
		)
		(fill yes
			(thermal_gap 0.5)
			(thermal_bridge_width 0.5)
			(island_removal_mode 0)
		)
		(polygon
			(pts
				(arc
					(start 106.298746 -114.84991)
					(mid 105.883664 -114.317774)
					(end 105.26649 -114.59083)
				)
				(arc
					(start 104.516428 -115.990624)
					(mid 104.740809 -116.733627)
					(end 105.48366 -116.509038)
				)
				(xy 105.621074 -116.252498)
				(arc
					(start 105.381044 -116.252498)
					(mid 105.000044 -116.630966)
					(end 104.619044 -116.252498)
				)
				(arc
					(start 104.619044 -116.249958)
					(mid 105.000044 -115.868958)
					(end 105.381044 -116.249958)
				)
				(xy 105.622344 -116.249958)
				(arc
					(start 106.233722 -115.10899)
					(mid 106.281932 -114.984699)
					(end 106.298746 -114.85245)
				)
				(arc
					(start 106.131106 -114.85245)
					(mid 105.750106 -115.230918)
					(end 105.369106 -114.85245)
				)
				(arc
					(start 105.369106 -114.84991)
					(mid 105.750106 -114.46891)
					(end 106.131106 -114.84991)
				)
			)
		)
	)
	(zone
		(layers "F.Cu" "In2.Cu" "In5.Cu")
		(hatch none 0.5)
		(connect_pads
			(clearance 0)
		)
		(min_thickness 0.25)
		(keepout
			(tracks not_allowed)
			(vias allowed)
			(pads allowed)
			(copperpour not_allowed)
			(footprints allowed)
		)
		(placement
			(enabled no)
			(sheetname "")
		)
		(fill yes
			(thermal_gap 0.5)
			(thermal_bridge_width 0.5)
			(island_removal_mode 0)
		)
		(polygon
			(pts
				(arc
					(start 88.36152 -2.600198)
					(mid 87.80018 -2.038858)
					(end 87.23884 -2.600198)
				)
				(arc
					(start 87.23884 -3.999738)
					(mid 87.798783 -4.56133)
					(end 88.36152 -4.002532)
				)
				(arc
					(start 88.19388 -4.002532)
					(mid 87.80018 -4.3937)
					(end 87.40648 -4.002532)
				)
				(arc
					(start 87.40648 -3.999992)
					(mid 87.80018 -3.606292)
					(end 88.19388 -3.999992)
				)
				(xy 88.36152 -3.999992) (xy 88.36152 -2.602738)
				(arc
					(start 88.19388 -2.602738)
					(mid 87.80018 -2.993906)
					(end 87.40648 -2.602738)
				)
				(arc
					(start 87.40648 -2.600198)
					(mid 87.80018 -2.206498)
					(end 88.19388 -2.600198)
				)
			)
		)
	)
	(zone
		(layers "F.Cu" "In2.Cu" "In5.Cu")
		(hatch none 0.5)
		(connect_pads
			(clearance 0)
		)
		(min_thickness 0.25)
		(keepout
			(tracks not_allowed)
			(vias allowed)
			(pads allowed)
			(copperpour not_allowed)
			(footprints allowed)
		)
		(placement
			(enabled no)
			(sheetname "")
		)
		(fill yes
			(thermal_gap 0.5)
			(thermal_bridge_width 0.5)
			(island_removal_mode 0)
		)
		(polygon
			(pts
				(arc
					(start 187.761118 -10.999978)
					(mid 187.199778 -10.438638)
					(end 186.638438 -10.999978)
				)
				(arc
					(start 186.638438 -12.399772)
					(mid 187.198381 -12.961364)
					(end 187.761118 -12.402566)
				)
				(arc
					(start 187.593478 -12.402566)
					(mid 187.199778 -12.793734)
					(end 186.806078 -12.402566)
				)
				(arc
					(start 186.806078 -12.400026)
					(mid 187.199778 -12.006326)
					(end 187.593478 -12.400026)
				)
				(xy 187.761118 -12.400026) (xy 187.761118 -11.002518)
				(arc
					(start 187.593478 -11.002518)
					(mid 187.199778 -11.393686)
					(end 186.806078 -11.002518)
				)
				(arc
					(start 186.806078 -10.999978)
					(mid 187.199778 -10.606278)
					(end 187.593478 -10.999978)
				)
			)
		)
	)
	(zone
		(layers "F.Cu" "In2.Cu" "In5.Cu")
		(hatch none 0.5)
		(connect_pads
			(clearance 0)
		)
		(min_thickness 0.25)
		(keepout
			(tracks not_allowed)
			(vias allowed)
			(pads allowed)
			(copperpour not_allowed)
			(footprints allowed)
		)
		(placement
			(enabled no)
			(sheetname "")
		)
		(fill yes
			(thermal_gap 0.5)
			(thermal_bridge_width 0.5)
			(island_removal_mode 0)
		)
		(polygon
			(pts
				(arc
					(start 140.561314 -3.800094)
					(mid 139.999974 -3.238754)
					(end 139.438634 -3.800094)
				)
				(arc
					(start 139.438634 -5.199888)
					(mid 139.998577 -5.76148)
					(end 140.561314 -5.202682)
				)
				(arc
					(start 140.393674 -5.202682)
					(mid 139.999974 -5.59385)
					(end 139.606274 -5.202682)
				)
				(arc
					(start 139.606274 -5.200142)
					(mid 139.999974 -4.806442)
					(end 140.393674 -5.200142)
				)
				(xy 140.561314 -5.200142) (xy 140.561314 -3.802634)
				(arc
					(start 140.393674 -3.802634)
					(mid 139.999974 -4.193802)
					(end 139.606274 -3.802634)
				)
				(arc
					(start 139.606274 -3.800094)
					(mid 139.999974 -3.406394)
					(end 140.393674 -3.800094)
				)
			)
		)
	)
	(zone
		(layers "F.Cu" "In2.Cu" "In5.Cu")
		(hatch none 0.5)
		(connect_pads
			(clearance 0)
		)
		(min_thickness 0.25)
		(keepout
			(tracks not_allowed)
			(vias allowed)
			(pads allowed)
			(copperpour not_allowed)
			(footprints allowed)
		)
		(placement
			(enabled no)
			(sheetname "")
		)
		(fill yes
			(thermal_gap 0.5)
			(thermal_bridge_width 0.5)
			(island_removal_mode 0)
		)
		(polygon
			(pts
				(arc
					(start 93.761306 -3.800094)
					(mid 93.199966 -3.238754)
					(end 92.638626 -3.800094)
				)
				(arc
					(start 92.638626 -5.199888)
					(mid 93.198569 -5.76148)
					(end 93.761306 -5.202682)
				)
				(arc
					(start 93.593666 -5.202682)
					(mid 93.199966 -5.59385)
					(end 92.806266 -5.202682)
				)
				(arc
					(start 92.806266 -5.200142)
					(mid 93.199966 -4.806442)
					(end 93.593666 -5.200142)
				)
				(xy 93.761306 -5.200142) (xy 93.761306 -3.802634)
				(arc
					(start 93.593666 -3.802634)
					(mid 93.199966 -4.193802)
					(end 92.806266 -3.802634)
				)
				(arc
					(start 92.806266 -3.800094)
					(mid 93.199966 -3.406394)
					(end 93.593666 -3.800094)
				)
			)
		)
	)
	(zone
		(layers "F.Cu" "In2.Cu" "In5.Cu")
		(hatch none 0.5)
		(connect_pads
			(clearance 0)
		)
		(min_thickness 0.25)
		(keepout
			(tracks not_allowed)
			(vias allowed)
			(pads allowed)
			(copperpour not_allowed)
			(footprints allowed)
		)
		(placement
			(enabled no)
			(sheetname "")
		)
		(fill yes
			(thermal_gap 0.5)
			(thermal_bridge_width 0.5)
			(island_removal_mode 0)
		)
		(polygon
			(pts
				(arc
					(start 100.961444 -3.800094)
					(mid 100.400104 -3.238754)
					(end 99.838764 -3.800094)
				)
				(arc
					(start 99.838764 -5.199888)
					(mid 100.398707 -5.76148)
					(end 100.961444 -5.202682)
				)
				(arc
					(start 100.793804 -5.202682)
					(mid 100.400104 -5.59385)
					(end 100.006404 -5.202682)
				)
				(arc
					(start 100.006404 -5.200142)
					(mid 100.400104 -4.806442)
					(end 100.793804 -5.200142)
				)
				(xy 100.961444 -5.200142) (xy 100.961444 -3.802634)
				(arc
					(start 100.793804 -3.802634)
					(mid 100.400104 -4.193802)
					(end 100.006404 -3.802634)
				)
				(arc
					(start 100.006404 -3.800094)
					(mid 100.400104 -3.406394)
					(end 100.793804 -3.800094)
				)
			)
		)
	)
	(zone
		(layers "F.Cu" "In2.Cu" "In5.Cu")
		(hatch none 0.5)
		(connect_pads
			(clearance 0)
		)
		(min_thickness 0.25)
		(keepout
			(tracks not_allowed)
			(vias allowed)
			(pads allowed)
			(copperpour not_allowed)
			(footprints allowed)
		)
		(placement
			(enabled no)
			(sheetname "")
		)
		(fill yes
			(thermal_gap 0.5)
			(thermal_bridge_width 0.5)
			(island_removal_mode 0)
		)
		(polygon
			(pts
				(arc
					(start 104.04856 -111.05007)
					(mid 103.633478 -110.517934)
					(end 103.016304 -110.79099)
				)
				(xy 102.266496 -112.190784)
				(arc
					(start 102.266496 -112.191038)
					(mid 102.491032 -112.933734)
					(end 103.233728 -112.709198)
				)
				(xy 103.371142 -112.452658)
				(arc
					(start 103.131112 -112.452658)
					(mid 102.750112 -112.831126)
					(end 102.369112 -112.452658)
				)
				(arc
					(start 102.369112 -112.450118)
					(mid 102.750112 -112.069118)
					(end 103.131112 -112.450118)
				)
				(xy 103.372412 -112.450118)
				(arc
					(start 103.983536 -111.30915)
					(mid 104.031746 -111.184859)
					(end 104.04856 -111.05261)
				)
				(arc
					(start 103.88092 -111.05261)
					(mid 103.49992 -111.431078)
					(end 103.11892 -111.05261)
				)
				(arc
					(start 103.11892 -111.05007)
					(mid 103.49992 -110.66907)
					(end 103.88092 -111.05007)
				)
			)
		)
	)
	(zone
		(layers "F.Cu" "In2.Cu" "In5.Cu")
		(hatch none 0.5)
		(connect_pads
			(clearance 0)
		)
		(min_thickness 0.25)
		(keepout
			(tracks not_allowed)
			(vias allowed)
			(pads allowed)
			(copperpour not_allowed)
			(footprints allowed)
		)
		(placement
			(enabled no)
			(sheetname "")
		)
		(fill yes
			(thermal_gap 0.5)
			(thermal_bridge_width 0.5)
			(island_removal_mode 0)
		)
		(polygon
			(pts
				(arc
					(start 106.361484 -2.600198)
					(mid 105.800144 -2.038858)
					(end 105.238804 -2.600198)
				)
				(arc
					(start 105.238804 -3.999738)
					(mid 105.798747 -4.56133)
					(end 106.361484 -4.002532)
				)
				(arc
					(start 106.193844 -4.002532)
					(mid 105.800144 -4.3937)
					(end 105.406444 -4.002532)
				)
				(arc
					(start 105.406444 -3.999992)
					(mid 105.800144 -3.606292)
					(end 106.193844 -3.999992)
				)
				(xy 106.361484 -3.999992) (xy 106.361484 -2.602738)
				(arc
					(start 106.193844 -2.602738)
					(mid 105.800144 -2.993906)
					(end 105.406444 -2.602738)
				)
				(arc
					(start 105.406444 -2.600198)
					(mid 105.800144 -2.206498)
					(end 106.193844 -2.600198)
				)
			)
		)
	)
	(zone
		(layers "F.Cu" "In2.Cu" "In5.Cu")
		(hatch none 0.5)
		(connect_pads
			(clearance 0)
		)
		(min_thickness 0.25)
		(keepout
			(tracks not_allowed)
			(vias allowed)
			(pads allowed)
			(copperpour not_allowed)
			(footprints allowed)
		)
		(placement
			(enabled no)
			(sheetname "")
		)
		(fill yes
			(thermal_gap 0.5)
			(thermal_bridge_width 0.5)
			(island_removal_mode 0)
		)
		(polygon
			(pts
				(arc
					(start 115.361466 -3.800094)
					(mid 114.800126 -3.238754)
					(end 114.238786 -3.800094)
				)
				(arc
					(start 114.238786 -5.199888)
					(mid 114.798729 -5.76148)
					(end 115.361466 -5.202682)
				)
				(arc
					(start 115.193826 -5.202682)
					(mid 114.800126 -5.59385)
					(end 114.406426 -5.202682)
				)
				(arc
					(start 114.406426 -5.200142)
					(mid 114.800126 -4.806442)
					(end 115.193826 -5.200142)
				)
				(xy 115.361466 -5.200142) (xy 115.361466 -3.802634)
				(arc
					(start 115.193826 -3.802634)
					(mid 114.800126 -4.193802)
					(end 114.406426 -3.802634)
				)
				(arc
					(start 114.406426 -3.800094)
					(mid 114.800126 -3.406394)
					(end 115.193826 -3.800094)
				)
			)
		)
	)
	(zone
		(layers "F.Cu" "In2.Cu" "In5.Cu")
		(hatch none 0.5)
		(connect_pads
			(clearance 0)
		)
		(min_thickness 0.25)
		(keepout
			(tracks not_allowed)
			(vias allowed)
			(pads allowed)
			(copperpour not_allowed)
			(footprints allowed)
		)
		(placement
			(enabled no)
			(sheetname "")
		)
		(fill yes
			(thermal_gap 0.5)
			(thermal_bridge_width 0.5)
			(island_removal_mode 0)
		)
		(polygon
			(pts
				(arc
					(start 135.161528 -2.600198)
					(mid 134.600188 -2.038858)
					(end 134.038848 -2.600198)
				)
				(arc
					(start 134.038848 -3.999738)
					(mid 134.598791 -4.56133)
					(end 135.161528 -4.002532)
				)
				(arc
					(start 134.993888 -4.002532)
					(mid 134.600188 -4.3937)
					(end 134.206488 -4.002532)
				)
				(arc
					(start 134.206488 -3.999992)
					(mid 134.600188 -3.606292)
					(end 134.993888 -3.999992)
				)
				(xy 135.161528 -3.999992) (xy 135.161528 -2.602738)
				(arc
					(start 134.993888 -2.602738)
					(mid 134.600188 -2.993906)
					(end 134.206488 -2.602738)
				)
				(arc
					(start 134.206488 -2.600198)
					(mid 134.600188 -2.206498)
					(end 134.993888 -2.600198)
				)
			)
		)
	)
	(zone
		(layers "F.Cu" "In2.Cu" "In5.Cu")
		(hatch none 0.5)
		(connect_pads
			(clearance 0)
		)
		(min_thickness 0.25)
		(keepout
			(tracks not_allowed)
			(vias allowed)
			(pads allowed)
			(copperpour not_allowed)
			(footprints allowed)
		)
		(placement
			(enabled no)
			(sheetname "")
		)
		(fill yes
			(thermal_gap 0.5)
			(thermal_bridge_width 0.5)
			(island_removal_mode 0)
		)
		(polygon
			(pts
				(arc
					(start 182.361332 -9.800082)
					(mid 181.799992 -9.238742)
					(end 181.238652 -9.800082)
				)
				(arc
					(start 181.238652 -11.199876)
					(mid 181.798595 -11.761468)
					(end 182.361332 -11.20267)
				)
				(arc
					(start 182.193692 -11.20267)
					(mid 181.799992 -11.593838)
					(end 181.406292 -11.20267)
				)
				(arc
					(start 181.406292 -11.20013)
					(mid 181.799992 -10.80643)
					(end 182.193692 -11.20013)
				)
				(xy 182.361332 -11.20013) (xy 182.361332 -9.802622)
				(arc
					(start 182.193692 -9.802622)
					(mid 181.799992 -10.19379)
					(end 181.406292 -9.802622)
				)
				(arc
					(start 181.406292 -9.800082)
					(mid 181.799992 -9.406382)
					(end 182.193692 -9.800082)
				)
			)
		)
	)
	(zone
		(layers "F.Cu" "In2.Cu" "In5.Cu")
		(hatch none 0.5)
		(connect_pads
			(clearance 0)
		)
		(min_thickness 0.25)
		(keepout
			(tracks not_allowed)
			(vias allowed)
			(pads allowed)
			(copperpour not_allowed)
			(footprints allowed)
		)
		(placement
			(enabled no)
			(sheetname "")
		)
		(fill yes
			(thermal_gap 0.5)
			(thermal_bridge_width 0.5)
			(island_removal_mode 0)
		)
		(polygon
			(pts
				(arc
					(start 136.961372 -3.800094)
					(mid 136.400032 -3.238754)
					(end 135.838692 -3.800094)
				)
				(arc
					(start 135.838692 -5.199888)
					(mid 136.398635 -5.76148)
					(end 136.961372 -5.202682)
				)
				(arc
					(start 136.793732 -5.202682)
					(mid 136.400032 -5.59385)
					(end 136.006332 -5.202682)
				)
				(arc
					(start 136.006332 -5.200142)
					(mid 136.400032 -4.806442)
					(end 136.793732 -5.200142)
				)
				(xy 136.961372 -5.200142) (xy 136.961372 -3.802634)
				(arc
					(start 136.793732 -3.802634)
					(mid 136.400032 -4.193802)
					(end 136.006332 -3.802634)
				)
				(arc
					(start 136.006332 -3.800094)
					(mid 136.400032 -3.406394)
					(end 136.793732 -3.800094)
				)
			)
		)
	)
	(zone
		(layers "F.Cu" "In2.Cu" "In5.Cu")
		(hatch none 0.5)
		(connect_pads
			(clearance 0)
		)
		(min_thickness 0.25)
		(keepout
			(tracks not_allowed)
			(vias allowed)
			(pads allowed)
			(copperpour not_allowed)
			(footprints allowed)
		)
		(placement
			(enabled no)
			(sheetname "")
		)
		(fill yes
			(thermal_gap 0.5)
			(thermal_bridge_width 0.5)
			(island_removal_mode 0)
		)
		(polygon
			(pts
				(arc
					(start 102.761542 -2.600198)
					(mid 102.200202 -2.038858)
					(end 101.638862 -2.600198)
				)
				(arc
					(start 101.638862 -3.999738)
					(mid 102.198805 -4.56133)
					(end 102.761542 -4.002532)
				)
				(arc
					(start 102.593902 -4.002532)
					(mid 102.200202 -4.3937)
					(end 101.806502 -4.002532)
				)
				(arc
					(start 101.806502 -3.999992)
					(mid 102.200202 -3.606292)
					(end 102.593902 -3.999992)
				)
				(xy 102.761542 -3.999992) (xy 102.761542 -2.602738)
				(arc
					(start 102.593902 -2.602738)
					(mid 102.200202 -2.993906)
					(end 101.806502 -2.602738)
				)
				(arc
					(start 101.806502 -2.600198)
					(mid 102.200202 -2.206498)
					(end 102.593902 -2.600198)
				)
			)
		)
	)
	(zone
		(layers "F.Cu" "In2.Cu" "In5.Cu")
		(hatch none 0.5)
		(connect_pads
			(clearance 0)
		)
		(min_thickness 0.25)
		(keepout
			(tracks not_allowed)
			(vias allowed)
			(pads allowed)
			(copperpour not_allowed)
			(footprints allowed)
		)
		(placement
			(enabled no)
			(sheetname "")
		)
		(fill yes
			(thermal_gap 0.5)
			(thermal_bridge_width 0.5)
			(island_removal_mode 0)
		)
		(polygon
			(pts
				(arc
					(start 147.761452 -3.800094)
					(mid 147.200112 -3.238754)
					(end 146.638772 -3.800094)
				)
				(arc
					(start 146.638772 -5.199888)
					(mid 147.198715 -5.76148)
					(end 147.761452 -5.202682)
				)
				(arc
					(start 147.593812 -5.202682)
					(mid 147.200112 -5.59385)
					(end 146.806412 -5.202682)
				)
				(arc
					(start 146.806412 -5.200142)
					(mid 147.200112 -4.806442)
					(end 147.593812 -5.200142)
				)
				(xy 147.761452 -5.200142) (xy 147.761452 -3.802634)
				(arc
					(start 147.593812 -3.802634)
					(mid 147.200112 -4.193802)
					(end 146.806412 -3.802634)
				)
				(arc
					(start 146.806412 -3.800094)
					(mid 147.200112 -3.406394)
					(end 147.593812 -3.800094)
				)
			)
		)
	)
	(zone
		(layers "F.Cu" "In2.Cu" "In5.Cu")
		(hatch none 0.5)
		(connect_pads
			(clearance 0)
		)
		(min_thickness 0.25)
		(keepout
			(tracks not_allowed)
			(vias allowed)
			(pads allowed)
			(copperpour not_allowed)
			(footprints allowed)
		)
		(placement
			(enabled no)
			(sheetname "")
		)
		(fill yes
			(thermal_gap 0.5)
			(thermal_bridge_width 0.5)
			(island_removal_mode 0)
		)
		(polygon
			(pts
				(arc
					(start 142.361412 -2.600198)
					(mid 141.800072 -2.038858)
					(end 141.238732 -2.600198)
				)
				(arc
					(start 141.238732 -3.999738)
					(mid 141.798675 -4.56133)
					(end 142.361412 -4.002532)
				)
				(arc
					(start 142.193772 -4.002532)
					(mid 141.800072 -4.3937)
					(end 141.406372 -4.002532)
				)
				(arc
					(start 141.406372 -3.999992)
					(mid 141.800072 -3.606292)
					(end 142.193772 -3.999992)
				)
				(xy 142.361412 -3.999992) (xy 142.361412 -2.602738)
				(arc
					(start 142.193772 -2.602738)
					(mid 141.800072 -2.993906)
					(end 141.406372 -2.602738)
				)
				(arc
					(start 141.406372 -2.600198)
					(mid 141.800072 -2.206498)
					(end 142.193772 -2.600198)
				)
			)
		)
	)
	(zone
		(layers "F.Cu" "In2.Cu" "In5.Cu")
		(hatch none 0.5)
		(connect_pads
			(clearance 0)
		)
		(min_thickness 0.25)
		(keepout
			(tracks not_allowed)
			(vias allowed)
			(pads allowed)
			(copperpour not_allowed)
			(footprints allowed)
		)
		(placement
			(enabled no)
			(sheetname "")
		)
		(fill yes
			(thermal_gap 0.5)
			(thermal_bridge_width 0.5)
			(island_removal_mode 0)
		)
		(polygon
			(pts
				(arc
					(start 124.361448 -2.600198)
					(mid 123.800108 -2.038858)
					(end 123.238768 -2.600198)
				)
				(arc
					(start 123.238768 -3.999738)
					(mid 123.798711 -4.56133)
					(end 124.361448 -4.002532)
				)
				(arc
					(start 124.193808 -4.002532)
					(mid 123.800108 -4.3937)
					(end 123.406408 -4.002532)
				)
				(arc
					(start 123.406408 -3.999992)
					(mid 123.800108 -3.606292)
					(end 124.193808 -3.999992)
				)
				(xy 124.361448 -3.999992) (xy 124.361448 -2.602738)
				(arc
					(start 124.193808 -2.602738)
					(mid 123.800108 -2.993906)
					(end 123.406408 -2.602738)
				)
				(arc
					(start 123.406408 -2.600198)
					(mid 123.800108 -2.206498)
					(end 124.193808 -2.600198)
				)
			)
		)
	)
	(zone
		(layers "F.Cu" "In2.Cu" "In5.Cu")
		(hatch none 0.5)
		(connect_pads
			(clearance 0)
		)
		(min_thickness 0.25)
		(keepout
			(tracks not_allowed)
			(vias allowed)
			(pads allowed)
			(copperpour not_allowed)
			(footprints allowed)
		)
		(placement
			(enabled no)
			(sheetname "")
		)
		(fill yes
			(thermal_gap 0.5)
			(thermal_bridge_width 0.5)
			(island_removal_mode 0)
		)
		(polygon
			(pts
				(arc
					(start 118.961408 -3.800094)
					(mid 118.400068 -3.238754)
					(end 117.838728 -3.800094)
				)
				(arc
					(start 117.838728 -5.199888)
					(mid 118.398671 -5.76148)
					(end 118.961408 -5.202682)
				)
				(arc
					(start 118.793768 -5.202682)
					(mid 118.400068 -5.59385)
					(end 118.006368 -5.202682)
				)
				(arc
					(start 118.006368 -5.200142)
					(mid 118.400068 -4.806442)
					(end 118.793768 -5.200142)
				)
				(xy 118.961408 -5.200142) (xy 118.961408 -3.802634)
				(arc
					(start 118.793768 -3.802634)
					(mid 118.400068 -4.193802)
					(end 118.006368 -3.802634)
				)
				(arc
					(start 118.006368 -3.800094)
					(mid 118.400068 -3.406394)
					(end 118.793768 -3.800094)
				)
			)
		)
	)
	(zone
		(layers "F.Cu" "In2.Cu" "In5.Cu")
		(hatch none 0.5)
		(connect_pads
			(clearance 0)
		)
		(min_thickness 0.25)
		(keepout
			(tracks not_allowed)
			(vias allowed)
			(pads allowed)
			(copperpour not_allowed)
			(footprints allowed)
		)
		(placement
			(enabled no)
			(sheetname "")
		)
		(fill yes
			(thermal_gap 0.5)
			(thermal_bridge_width 0.5)
			(island_removal_mode 0)
		)
		(polygon
			(pts
				(arc
					(start 127.96139 -2.600198)
					(mid 127.40005 -2.038858)
					(end 126.83871 -2.600198)
				)
				(arc
					(start 126.83871 -3.999738)
					(mid 127.398653 -4.56133)
					(end 127.96139 -4.002532)
				)
				(arc
					(start 127.79375 -4.002532)
					(mid 127.40005 -4.3937)
					(end 127.00635 -4.002532)
				)
				(arc
					(start 127.00635 -3.999992)
					(mid 127.40005 -3.606292)
					(end 127.79375 -3.999992)
				)
				(xy 127.96139 -3.999992) (xy 127.96139 -2.602738)
				(arc
					(start 127.79375 -2.602738)
					(mid 127.40005 -2.993906)
					(end 127.00635 -2.602738)
				)
				(arc
					(start 127.00635 -2.600198)
					(mid 127.40005 -2.206498)
					(end 127.79375 -2.600198)
				)
			)
		)
	)
	(zone
		(layers "F.Cu" "In2.Cu" "In5.Cu")
		(hatch none 0.5)
		(connect_pads
			(clearance 0)
		)
		(min_thickness 0.25)
		(keepout
			(tracks not_allowed)
			(vias allowed)
			(pads allowed)
			(copperpour not_allowed)
			(footprints allowed)
		)
		(placement
			(enabled no)
			(sheetname "")
		)
		(fill yes
			(thermal_gap 0.5)
			(thermal_bridge_width 0.5)
			(island_removal_mode 0)
		)
		(polygon
			(pts
				(arc
					(start 133.36143 -3.800094)
					(mid 132.80009 -3.238754)
					(end 132.23875 -3.800094)
				)
				(arc
					(start 132.23875 -5.199888)
					(mid 132.798693 -5.76148)
					(end 133.36143 -5.202682)
				)
				(arc
					(start 133.19379 -5.202682)
					(mid 132.80009 -5.59385)
					(end 132.40639 -5.202682)
				)
				(arc
					(start 132.40639 -5.200142)
					(mid 132.80009 -4.806442)
					(end 133.19379 -5.200142)
				)
				(xy 133.36143 -5.200142) (xy 133.36143 -3.802634)
				(arc
					(start 133.19379 -3.802634)
					(mid 132.80009 -4.193802)
					(end 132.40639 -3.802634)
				)
				(arc
					(start 132.40639 -3.800094)
					(mid 132.80009 -3.406394)
					(end 133.19379 -3.800094)
				)
			)
		)
	)
	(zone
		(layers "F.Cu" "In2.Cu" "In5.Cu")
		(hatch none 0.5)
		(connect_pads
			(clearance 0)
		)
		(min_thickness 0.25)
		(keepout
			(tracks not_allowed)
			(vias allowed)
			(pads allowed)
			(copperpour not_allowed)
			(footprints allowed)
		)
		(placement
			(enabled no)
			(sheetname "")
		)
		(fill yes
			(thermal_gap 0.5)
			(thermal_bridge_width 0.5)
			(island_removal_mode 0)
		)
		(polygon
			(pts
				(arc
					(start 122.56135 -3.800094)
					(mid 122.00001 -3.238754)
					(end 121.43867 -3.800094)
				)
				(arc
					(start 121.43867 -5.199888)
					(mid 121.998613 -5.76148)
					(end 122.56135 -5.202682)
				)
				(arc
					(start 122.39371 -5.202682)
					(mid 122.00001 -5.59385)
					(end 121.60631 -5.202682)
				)
				(arc
					(start 121.60631 -5.200142)
					(mid 122.00001 -4.806442)
					(end 122.39371 -5.200142)
				)
				(xy 122.56135 -5.200142) (xy 122.56135 -3.802634)
				(arc
					(start 122.39371 -3.802634)
					(mid 122.00001 -4.193802)
					(end 121.60631 -3.802634)
				)
				(arc
					(start 121.60631 -3.800094)
					(mid 122.00001 -3.406394)
					(end 122.39371 -3.800094)
				)
			)
		)
	)
	(zone
		(layers "F.Cu" "In2.Cu" "In5.Cu")
		(hatch none 0.5)
		(connect_pads
			(clearance 0)
		)
		(min_thickness 0.25)
		(keepout
			(tracks not_allowed)
			(vias allowed)
			(pads allowed)
			(copperpour not_allowed)
			(footprints allowed)
		)
		(placement
			(enabled no)
			(sheetname "")
		)
		(fill yes
			(thermal_gap 0.5)
			(thermal_bridge_width 0.5)
			(island_removal_mode 0)
		)
		(polygon
			(pts
				(arc
					(start 86.561422 -3.800094)
					(mid 86.000082 -3.238754)
					(end 85.438742 -3.800094)
				)
				(arc
					(start 85.438742 -5.199888)
					(mid 85.998685 -5.76148)
					(end 86.561422 -5.202682)
				)
				(arc
					(start 86.393782 -5.202682)
					(mid 86.000082 -5.59385)
					(end 85.606382 -5.202682)
				)
				(arc
					(start 85.606382 -5.200142)
					(mid 86.000082 -4.806442)
					(end 86.393782 -5.200142)
				)
				(xy 86.561422 -5.200142) (xy 86.561422 -3.802634)
				(arc
					(start 86.393782 -3.802634)
					(mid 86.000082 -4.193802)
					(end 85.606382 -3.802634)
				)
				(arc
					(start 85.606382 -3.800094)
					(mid 86.000082 -3.406394)
					(end 86.393782 -3.800094)
				)
			)
		)
	)
	(zone
		(layer "B.Cu")
		(hatch none 0.5)
		(connect_pads
			(clearance 0)
		)
		(min_thickness 0.25)
		(keepout
			(tracks not_allowed)
			(vias allowed)
			(pads allowed)
			(copperpour not_allowed)
			(footprints allowed)
		)
		(placement
			(enabled no)
			(sheetname "")
		)
		(fill
			(thermal_gap 0.5)
			(thermal_bridge_width 0.5)
			(island_removal_mode 0)
		)
		(polygon
			(pts
				(arc
					(start 136.961372 -3.800094)
					(mid 136.400032 -3.238754)
					(end 135.838692 -3.800094)
				)
				(arc
					(start 135.838692 -4.228592)
					(mid 135.871644 -4.224901)
					(end 135.904732 -4.22275)
				)
				(xy 135.905494 -4.221988)
				(arc
					(start 136.280906 -4.221988)
					(mid 136.297819 -4.218624)
					(end 136.312148 -4.209034)
				)
				(arc
					(start 136.312148 -4.209034)
					(mid 136.319914 -4.198635)
					(end 136.32434 -4.186428)
				)
				(arc
					(start 136.32434 -4.186428)
					(mid 136.400934 -3.406367)
					(end 136.474962 -4.186682)
				)
				(xy 136.474962 -4.20878)
				(arc
					(start 136.471914 -4.211828)
					(mid 136.452983 -4.267359)
					(end 136.41832 -4.314698)
				)
				(arc
					(start 136.41832 -4.314698)
					(mid 136.370804 -4.349728)
					(end 136.314942 -4.3688)
				)
				(xy 136.311894 -4.371848)
				(arc
					(start 135.936482 -4.371848)
					(mid 135.887398 -4.37403)
					(end 135.838692 -4.380484)
				)
				(arc
					(start 135.838692 -4.64439)
					(mid 135.870817 -4.635509)
					(end 135.903716 -4.630166)
				)
				(xy 135.905494 -4.628388) (xy 136.311894 -4.628388)
				(arc
					(start 136.314942 -4.631436)
					(mid 136.370791 -4.650533)
					(end 136.41832 -4.685538)
				)
				(arc
					(start 136.41832 -4.685538)
					(mid 136.453008 -4.732864)
					(end 136.471914 -4.788408)
				)
				(xy 136.474962 -4.791456)
				(arc
					(start 136.474962 -4.813554)
					(mid 136.400934 -5.593876)
					(end 136.32434 -4.813808)
				)
				(arc
					(start 136.32434 -4.813808)
					(mid 136.319942 -4.801586)
					(end 136.312148 -4.791202)
				)
				(arc
					(start 136.312148 -4.791202)
					(mid 136.297814 -4.781624)
					(end 136.280906 -4.778248)
				)
				(arc
					(start 135.936482 -4.778248)
					(mid 135.884749 -4.786928)
					(end 135.838692 -4.81203)
				)
				(arc
					(start 135.838692 -5.199888)
					(mid 136.399905 -5.761482)
					(end 136.961372 -5.200142)
				)
			)
		)
	)
	(zone
		(net "GND")
		(layer "B.Cu")
		(hatch none 0.5)
		(connect_pads
			(clearance 0.5)
		)
		(min_thickness 0.25)
		(fill yes
			(thermal_gap 0.5)
			(thermal_bridge_width 0.5)
			(island_removal_mode 0)
		)
		(polygon
			(pts
				(xy 163.309046 -9.9187) (xy 163.188904 -10.038842) (xy 163.188904 -11.440414) (xy 163.30549 -11.557)
				(xy 165.958774 -11.557) (xy 166.239952 -11.275822) (xy 166.886636 -11.275822) (xy 166.9542 -11.208258)
				(xy 166.9542 -10.205974) (xy 166.666926 -9.9187)
			)
		)
		(polygon
			(pts
				(xy 166.077392 -10.84453) (xy 165.874192 -10.84453) (xy 165.874192 -11.04773) (xy 166.077392 -11.04773)
			)
		)
		(polygon
			(pts
				(xy 165.467792 -10.84453) (xy 164.985192 -10.84453) (xy 164.985192 -11.04773) (xy 165.467792 -11.04773)
			)
		)
		(polygon
			(pts
				(xy 164.578792 -10.84453) (xy 164.096192 -10.84453) (xy 164.096192 -11.04773) (xy 164.578792 -11.04773)
			)
		)
		(polygon
			(pts
				(xy 163.689792 -10.84453) (xy 163.486592 -10.84453) (xy 163.486592 -11.04773) (xy 163.689792 -11.04773)
			)
		)
		(polygon
			(pts
				(xy 166.433754 -10.564622) (xy 166.230554 -10.564622) (xy 166.230554 -10.767822) (xy 166.433754 -10.767822)
			)
		)
		(polygon
			(pts
				(xy 164.2237 -10.4394) (xy 164.0205 -10.4394) (xy 164.0205 -10.6426) (xy 164.2237 -10.6426)
			)
		)
		(polygon
			(pts
				(xy 163.6141 -10.4394) (xy 163.4109 -10.4394) (xy 163.4109 -10.6426) (xy 163.6141 -10.6426)
			)
		)
	)
	(zone
		(layer "B.Cu")
		(hatch none 0.5)
		(connect_pads
			(clearance 0)
		)
		(min_thickness 0.25)
		(keepout
			(tracks not_allowed)
			(vias allowed)
			(pads allowed)
			(copperpour not_allowed)
			(footprints allowed)
		)
		(placement
			(enabled no)
			(sheetname "")
		)
		(fill
			(thermal_gap 0.5)
			(thermal_bridge_width 0.5)
			(island_removal_mode 0)
		)
		(polygon
			(pts
				(arc
					(start 105.358184 -55.000144)
					(mid 105.04056 -54.644303)
					(end 104.651048 -54.919626)
				)
				(arc
					(start 104.651048 -55.237634)
					(mid 104.659424 -55.279834)
					(end 104.683306 -55.315612)
				)
				(arc
					(start 104.683306 -55.315612)
					(mid 104.719097 -55.339464)
					(end 104.761284 -55.34787)
				)
				(arc
					(start 104.911144 -55.34787)
					(mid 104.933595 -55.338571)
					(end 104.942894 -55.31612)
				)
				(arc
					(start 104.942894 -55.234586)
					(mid 105.000044 -54.758837)
					(end 105.057194 -55.234586)
				)
				(xy 105.057194 -55.339742)
				(arc
					(start 105.054908 -55.342028)
					(mid 105.014438 -55.419414)
					(end 104.937052 -55.459884)
				)
				(xy 104.934766 -55.46217) (xy 104.737662 -55.46217)
				(arc
					(start 104.736138 -55.460646)
					(mid 104.687186 -55.449546)
					(end 104.641904 -55.42788)
				)
				(arc
					(start 104.641904 -55.513732)
					(mid 104.700086 -55.532094)
					(end 104.760776 -55.53837)
				)
				(xy 104.934766 -55.53837)
				(arc
					(start 104.937052 -55.540656)
					(mid 105.014438 -55.581126)
					(end 105.054908 -55.658512)
				)
				(xy 105.057194 -55.660798)
				(arc
					(start 105.057194 -55.7657)
					(mid 105.000044 -56.241449)
					(end 104.942894 -55.7657)
				)
				(arc
					(start 104.942894 -55.68442)
					(mid 104.933595 -55.661969)
					(end 104.911144 -55.65267)
				)
				(xy 104.737662 -55.65267)
				(arc
					(start 104.7369 -55.651908)
					(mid 104.688912 -55.646299)
					(end 104.641904 -55.635144)
				)
				(arc
					(start 104.641904 -55.999888)
					(mid 104.999917 -56.358282)
					(end 105.358184 -56.000142)
				)
			)
		)
	)
	(zone
		(layer "B.Cu")
		(hatch none 0.5)
		(connect_pads
			(clearance 0)
		)
		(min_thickness 0.25)
		(keepout
			(tracks not_allowed)
			(vias allowed)
			(pads allowed)
			(copperpour not_allowed)
			(footprints allowed)
		)
		(placement
			(enabled no)
			(sheetname "")
		)
		(fill
			(thermal_gap 0.5)
			(thermal_bridge_width 0.5)
			(island_removal_mode 0)
		)
		(polygon
			(pts
				(arc
					(start 90.161364 -3.800094)
					(mid 89.600024 -3.238754)
					(end 89.038684 -3.800094)
				)
				(xy 89.038684 -4.221988)
				(arc
					(start 89.480898 -4.221988)
					(mid 89.497811 -4.218624)
					(end 89.51214 -4.209034)
				)
				(arc
					(start 89.51214 -4.209034)
					(mid 89.519906 -4.198635)
					(end 89.524332 -4.186428)
				)
				(arc
					(start 89.524332 -4.186428)
					(mid 89.600926 -3.406367)
					(end 89.674954 -4.186682)
				)
				(xy 89.674954 -4.20878)
				(arc
					(start 89.671906 -4.211828)
					(mid 89.652975 -4.267359)
					(end 89.618312 -4.314698)
				)
				(arc
					(start 89.618312 -4.314698)
					(mid 89.570796 -4.349728)
					(end 89.514934 -4.3688)
				)
				(xy 89.511886 -4.371848) (xy 89.06129 -4.371848) (xy 89.038684 -4.372356) (xy 89.038684 -4.628388)
				(xy 89.511886 -4.628388)
				(arc
					(start 89.514934 -4.631436)
					(mid 89.570783 -4.650533)
					(end 89.618312 -4.685538)
				)
				(arc
					(start 89.618312 -4.685538)
					(mid 89.653 -4.732864)
					(end 89.671906 -4.788408)
				)
				(xy 89.674954 -4.791456)
				(arc
					(start 89.674954 -4.813554)
					(mid 89.600926 -5.593876)
					(end 89.524332 -4.813808)
				)
				(arc
					(start 89.524332 -4.813808)
					(mid 89.519934 -4.801586)
					(end 89.51214 -4.791202)
				)
				(arc
					(start 89.51214 -4.791202)
					(mid 89.497806 -4.781624)
					(end 89.480898 -4.778248)
				)
				(arc
					(start 89.06129 -4.778248)
					(mid 89.049883 -4.779)
					(end 89.038684 -4.781296)
				)
				(arc
					(start 89.038684 -5.199888)
					(mid 89.599897 -5.761482)
					(end 90.161364 -5.200142)
				)
			)
		)
	)
	(zone
		(layer "B.Cu")
		(hatch none 0.5)
		(connect_pads
			(clearance 0)
		)
		(min_thickness 0.25)
		(keepout
			(tracks not_allowed)
			(vias allowed)
			(pads allowed)
			(copperpour not_allowed)
			(footprints allowed)
		)
		(placement
			(enabled no)
			(sheetname "")
		)
		(fill
			(thermal_gap 0.5)
			(thermal_bridge_width 0.5)
			(island_removal_mode 0)
		)
		(polygon
			(pts
				(arc
					(start 168.741852 -30.07106)
					(mid 168.436076 -30.081356)
					(end 168.249854 -30.324044)
				)
				(xy 168.249854 -30.566614) (xy 168.241726 -30.574742)
				(arc
					(start 168.241726 -31.199582)
					(mid 168.599739 -31.557976)
					(end 168.958006 -31.199836)
				)
				(xy 168.958006 -30.731968)
				(arc
					(start 168.773602 -31.03245)
					(mid 168.473549 -31.405375)
					(end 168.670732 -30.969204)
				)
				(xy 168.925748 -30.553914)
				(arc
					(start 168.925748 -30.251654)
					(mid 168.897843 -30.201464)
					(end 168.862248 -30.156404)
				)
				(xy 168.862248 -30.222698)
				(arc
					(start 168.807638 -30.277562)
					(mid 168.429341 -30.570515)
					(end 168.722294 -30.192218)
				)
				(xy 168.741852 -30.172914)
			)
		)
	)
	(zone
		(net "GND")
		(layer "B.Cu")
		(hatch none 0.5)
		(connect_pads
			(clearance 0.5)
		)
		(min_thickness 0.25)
		(fill yes
			(thermal_gap 0.5)
			(thermal_bridge_width 0.5)
			(island_removal_mode 0)
		)
		(polygon
			(pts
				(xy 91.903804 -67.803268) (xy 91.701874 -68.005198) (xy 91.701874 -70.83298) (xy 91.900502 -71.031608)
				(xy 95.3389 -71.031608) (xy 95.637604 -70.732904) (xy 95.637604 -68.1228) (xy 95.318072 -67.803268)
			)
		)
		(polygon
			(pts
				(xy 93.768672 -70.329298) (xy 93.565472 -70.329298) (xy 93.565472 -70.532498) (xy 93.768672 -70.532498)
			)
		)
		(polygon
			(pts
				(xy 93.057472 -70.329298) (xy 92.854272 -70.329298) (xy 92.854272 -70.532498) (xy 93.057472 -70.532498)
			)
		)
		(polygon
			(pts
				(xy 92.701872 -69.948298) (xy 92.498672 -69.948298) (xy 92.498672 -70.151498) (xy 92.701872 -70.151498)
			)
		)
		(polygon
			(pts
				(xy 92.701872 -68.666614) (xy 92.498672 -68.666614) (xy 92.498672 -68.869814) (xy 92.701872 -68.869814)
			)
		)
		(polygon
			(pts
				(xy 93.768672 -68.285614) (xy 93.565472 -68.285614) (xy 93.565472 -68.488814) (xy 93.768672 -68.488814)
			)
		)
		(polygon
			(pts
				(xy 93.057472 -68.285614) (xy 92.854272 -68.285614) (xy 92.854272 -68.488814) (xy 93.057472 -68.488814)
			)
		)
	)
	(zone
		(net "GND")
		(layer "B.Cu")
		(hatch none 0.5)
		(connect_pads
			(clearance 0.5)
		)
		(min_thickness 0.25)
		(fill yes
			(thermal_gap 0.5)
			(thermal_bridge_width 0.5)
			(island_removal_mode 0)
		)
		(polygon
			(pts
				(xy 70.8914 -29.2354) (xy 70.7644 -29.3624) (xy 70.7644 -32.131) (xy 72.263 -33.6296) (xy 72.263 -35.306)
				(xy 72.644 -35.687) (xy 76.726542 -35.687) (xy 76.835 -35.578542) (xy 76.835 -33.147) (xy 76.831444 -33.143444)
				(xy 76.831444 -32.940244) (xy 73.1266 -29.2354)
			)
		)
		(polygon
			(pts
				(xy 75.9968 -34.6964) (xy 75.7936 -34.6964) (xy 75.7936 -34.8996) (xy 75.9968 -34.8996)
			)
		)
	)
	(zone
		(net "GB_VDDA")
		(layer "B.Cu")
		(hatch none 0.5)
		(connect_pads
			(clearance 0.5)
		)
		(min_thickness 0.25)
		(fill yes
			(thermal_gap 0.5)
			(thermal_bridge_width 0.5)
			(island_removal_mode 0)
		)
		(polygon
			(pts
				(xy 106.734356 -57.575196) (xy 106.698796 -57.610756) (xy 106.698796 -57.932066) (xy 107.088686 -58.321956)
				(xy 107.80141 -58.321956) (xy 107.918504 -58.43905) (xy 107.918504 -59.571382) (xy 107.764072 -59.725814)
				(xy 107.764072 -60.073032) (xy 107.921044 -60.230004) (xy 121.507504 -60.230004) (xy 121.651776 -60.085732)
				(xy 122.522234 -60.085732) (xy 122.5804 -60.143898) (xy 122.5804 -71.882) (xy 122.682 -71.9836)
				(xy 122.682 -72.619616) (xy 122.706384 -72.644) (xy 124.1552 -72.644) (xy 124.6124 -73.1012) (xy 124.6124 -73.5838)
				(xy 124.6632 -73.6346) (xy 125.17628 -73.6346) (xy 125.291088 -73.749408) (xy 125.641862 -73.749408)
				(xy 125.72746 -73.66381) (xy 125.72746 -73.291192) (xy 125.6284 -73.192132) (xy 125.6284 -61.6204)
				(xy 125.3998 -61.3918) (xy 124.8918 -61.3918) (xy 124.463302 -60.963302) (xy 124.463302 -57.6326)
				(xy 124.405898 -57.575196)
			)
		)
		(polygon
			(pts
				(xy 125.1204 -73.2028) (xy 124.9172 -73.2028) (xy 124.9172 -73.406) (xy 125.1204 -73.406) (xy 125.222 -73.4568)
				(xy 125.4252 -73.4568) (xy 125.4252 -73.2536) (xy 125.222 -73.2536)
			)
		)
		(polygon
			(pts
				(xy 124.3457 -72.2249) (xy 124.1425 -72.2249) (xy 124.1425 -72.4281) (xy 124.3457 -72.4281)
			)
		)
		(polygon
			(pts
				(xy 123.7869 -72.1487) (xy 123.5837 -72.1487) (xy 123.5837 -72.3519) (xy 123.7869 -72.3519)
			)
		)
		(polygon
			(pts
				(xy 123.4313 -72.1487) (xy 123.2281 -72.1487) (xy 123.1646 -72.1614) (xy 122.9614 -72.1614) (xy 122.9614 -72.3646)
				(xy 123.1646 -72.3646) (xy 123.2281 -72.3519) (xy 123.4313 -72.3519)
			)
		)
		(polygon
			(pts
				(xy 123.063 -71.5899) (xy 122.8598 -71.5899) (xy 122.8598 -71.7931) (xy 123.063 -71.7931)
			)
		)
		(polygon
			(pts
				(xy 123.063 -71.2343) (xy 122.8598 -71.2343) (xy 122.8598 -71.4375) (xy 123.063 -71.4375)
			)
		)
		(polygon
			(pts
				(xy 124.8283 -71.2216) (xy 124.6251 -71.2216) (xy 124.6251 -71.4248) (xy 124.8283 -71.4248)
			)
		)
		(polygon
			(pts
				(xy 123.063 -70.5866) (xy 122.8598 -70.5866) (xy 122.8598 -70.7898) (xy 123.063 -70.7898)
			)
		)
		(polygon
			(pts
				(xy 123.063 -70.231) (xy 122.8598 -70.231) (xy 122.8598 -70.4342) (xy 123.063 -70.4342)
			)
		)
		(polygon
			(pts
				(xy 124.3457 -70.2056) (xy 124.1425 -70.2056) (xy 124.1425 -70.4088) (xy 124.3457 -70.4088)
			)
		)
		(polygon
			(pts
				(xy 124.333 -69.5833) (xy 124.1298 -69.5833) (xy 124.1298 -69.7865) (xy 124.333 -69.7865)
			)
		)
		(polygon
			(pts
				(xy 123.063 -69.5706) (xy 122.8598 -69.5706) (xy 122.8598 -69.7738) (xy 123.063 -69.7738)
			)
		)
		(polygon
			(pts
				(xy 123.063 -69.215) (xy 122.8598 -69.215) (xy 122.8598 -69.4182) (xy 123.063 -69.4182)
			)
		)
		(polygon
			(pts
				(xy 124.8664 -68.58) (xy 124.6632 -68.58) (xy 124.6632 -68.7832) (xy 124.8664 -68.7832)
			)
		)
		(polygon
			(pts
				(xy 123.063 -68.5673) (xy 122.8598 -68.5673) (xy 122.8598 -68.7705) (xy 123.063 -68.7705)
			)
		)
		(polygon
			(pts
				(xy 123.063 -68.2117) (xy 122.8598 -68.2117) (xy 122.8598 -68.4149) (xy 123.063 -68.4149)
			)
		)
		(polygon
			(pts
				(xy 124.333 -67.5386) (xy 124.1298 -67.5386) (xy 124.1298 -67.7418) (xy 124.333 -67.7418)
			)
		)
		(polygon
			(pts
				(xy 123.058428 -67.43573) (xy 122.855228 -67.43573) (xy 122.855228 -67.63893) (xy 123.058428 -67.63893)
			)
		)
		(polygon
			(pts
				(xy 124.333 -67.183) (xy 124.1298 -67.183) (xy 124.1298 -67.3862) (xy 124.333 -67.3862)
			)
		)
		(polygon
			(pts
				(xy 123.058428 -66.80073) (xy 122.855228 -66.80073) (xy 122.855228 -67.28333) (xy 123.058428 -67.28333)
			)
		)
		(polygon
			(pts
				(xy 124.8664 -66.6115) (xy 124.6632 -66.6115) (xy 124.6632 -66.8147) (xy 124.8664 -66.8147)
			)
		)
		(polygon
			(pts
				(xy 123.058428 -66.44513) (xy 122.855228 -66.44513) (xy 122.855228 -66.64833) (xy 123.058428 -66.64833)
			)
		)
		(polygon
			(pts
				(xy 124.8664 -66.2559) (xy 124.6632 -66.2559) (xy 124.6632 -66.4591) (xy 124.8664 -66.4591)
			)
		)
		(polygon
			(pts
				(xy 124.8664 -65.5828) (xy 124.6632 -65.5828) (xy 124.6632 -65.786) (xy 124.8664 -65.786)
			)
		)
		(polygon
			(pts
				(xy 123.063 -65.5574) (xy 122.8598 -65.5574) (xy 122.8598 -65.7606) (xy 123.063 -65.7606)
			)
		)
		(polygon
			(pts
				(xy 124.8664 -65.2272) (xy 124.6632 -65.2272) (xy 124.6632 -65.4304) (xy 124.8664 -65.4304)
			)
		)
		(polygon
			(pts
				(xy 123.063 -65.2018) (xy 122.8598 -65.2018) (xy 122.8598 -65.405) (xy 123.063 -65.405)
			)
		)
		(polygon
			(pts
				(xy 124.8664 -64.5668) (xy 124.6632 -64.5668) (xy 124.6632 -64.77) (xy 124.8664 -64.77)
			)
		)
		(polygon
			(pts
				(xy 123.063 -64.5668) (xy 122.8598 -64.5668) (xy 122.8598 -64.77) (xy 123.063 -64.77)
			)
		)
		(polygon
			(pts
				(xy 124.8664 -64.2112) (xy 124.6632 -64.2112) (xy 124.6632 -64.4144) (xy 124.8664 -64.4144)
			)
		)
		(polygon
			(pts
				(xy 123.063 -64.2112) (xy 122.8598 -64.2112) (xy 122.8598 -64.4144) (xy 123.063 -64.4144)
			)
		)
		(polygon
			(pts
				(xy 124.8664 -63.5762) (xy 124.6632 -63.5762) (xy 124.6632 -63.7794) (xy 124.8664 -63.7794)
			)
		)
		(polygon
			(pts
				(xy 123.063 -63.5635) (xy 122.8598 -63.5635) (xy 122.8598 -63.7667) (xy 123.063 -63.7667)
			)
		)
		(polygon
			(pts
				(xy 123.063 -63.2079) (xy 122.8598 -63.2079) (xy 122.8598 -63.4111) (xy 123.063 -63.4111)
			)
		)
		(polygon
			(pts
				(xy 123.063 -62.5602) (xy 122.8598 -62.5602) (xy 122.8598 -62.7634) (xy 123.063 -62.7634)
			)
		)
		(polygon
			(pts
				(xy 124.8664 -62.2046) (xy 124.6632 -62.2046) (xy 124.6632 -62.4078) (xy 124.8664 -62.4078)
			)
		)
		(polygon
			(pts
				(xy 123.063 -62.2046) (xy 122.8598 -62.2046) (xy 122.8598 -62.4078) (xy 123.063 -62.4078)
			)
		)
		(polygon
			(pts
				(xy 124.8537 -61.5823) (xy 124.6505 -61.5823) (xy 124.6505 -61.7855) (xy 124.8537 -61.7855)
			)
		)
		(polygon
			(pts
				(xy 123.063 -61.5696) (xy 122.8598 -61.5696) (xy 122.8598 -61.7728) (xy 123.063 -61.7728)
			)
		)
		(polygon
			(pts
				(xy 123.063 -61.214) (xy 122.8598 -61.214) (xy 122.8598 -61.4172) (xy 123.063 -61.4172)
			)
		)
		(polygon
			(pts
				(xy 123.063 -60.5536) (xy 122.8598 -60.5536) (xy 122.8598 -60.7568) (xy 123.063 -60.7568)
			)
		)
		(polygon
			(pts
				(xy 124.1171 -60.2234) (xy 123.9139 -60.2234) (xy 123.9139 -60.4266) (xy 124.1171 -60.4266)
			)
		)
		(polygon
			(pts
				(xy 123.063 -60.198) (xy 122.8598 -60.198) (xy 122.8598 -60.4012) (xy 123.063 -60.4012)
			)
		)
		(polygon
			(pts
				(xy 121.3104 -59.8297) (xy 120.8278 -59.8297) (xy 120.8278 -60.0329) (xy 121.3104 -60.0329)
			)
		)
		(polygon
			(pts
				(xy 120.6754 -59.8297) (xy 120.4722 -59.8297) (xy 120.4722 -60.0329) (xy 120.6754 -60.0329)
			)
		)
		(polygon
			(pts
				(xy 119.6848 -59.8297) (xy 119.4816 -59.8297) (xy 119.4816 -60.0329) (xy 119.6848 -60.0329)
			)
		)
		(polygon
			(pts
				(xy 119.3292 -59.8297) (xy 118.8466 -59.8297) (xy 118.8466 -60.0329) (xy 119.3292 -60.0329)
			)
		)
		(polygon
			(pts
				(xy 118.6942 -59.8297) (xy 118.491 -59.8297) (xy 118.491 -60.0329) (xy 118.6942 -60.0329)
			)
		)
		(polygon
			(pts
				(xy 117.6782 -59.8297) (xy 117.475 -59.8297) (xy 117.475 -60.0329) (xy 117.6782 -60.0329)
			)
		)
		(polygon
			(pts
				(xy 117.3226 -59.8297) (xy 116.84 -59.8297) (xy 116.84 -60.0329) (xy 117.3226 -60.0329)
			)
		)
		(polygon
			(pts
				(xy 116.6876 -59.8297) (xy 116.4844 -59.8297) (xy 116.4844 -60.0329) (xy 116.6876 -60.0329)
			)
		)
		(polygon
			(pts
				(xy 115.68176 -59.8297) (xy 115.47856 -59.8297) (xy 115.47856 -60.0329) (xy 115.68176 -60.0329)
			)
		)
		(polygon
			(pts
				(xy 115.32616 -59.8297) (xy 114.84356 -59.8297) (xy 114.84356 -60.0329) (xy 115.32616 -60.0329)
			)
		)
		(polygon
			(pts
				(xy 114.69116 -59.8297) (xy 114.48796 -59.8297) (xy 114.48796 -60.0329) (xy 114.69116 -60.0329)
			)
		)
		(polygon
			(pts
				(xy 113.665 -59.8297) (xy 113.4618 -59.8297) (xy 113.4618 -60.0329) (xy 113.665 -60.0329)
			)
		)
		(polygon
			(pts
				(xy 113.3094 -59.8297) (xy 112.8268 -59.8297) (xy 112.8268 -60.0329) (xy 113.3094 -60.0329)
			)
		)
		(polygon
			(pts
				(xy 112.6744 -59.8297) (xy 112.4712 -59.8297) (xy 112.4712 -60.0329) (xy 112.6744 -60.0329)
			)
		)
		(polygon
			(pts
				(xy 111.6584 -59.8297) (xy 111.4552 -59.8297) (xy 111.4552 -60.0329) (xy 111.6584 -60.0329)
			)
		)
		(polygon
			(pts
				(xy 111.3028 -59.8297) (xy 110.8202 -59.8297) (xy 110.8202 -60.0329) (xy 111.3028 -60.0329)
			)
		)
		(polygon
			(pts
				(xy 110.6678 -59.8297) (xy 110.4646 -59.8297) (xy 110.4646 -60.0329) (xy 110.6678 -60.0329)
			)
		)
		(polygon
			(pts
				(xy 109.7661 -59.8297) (xy 109.5629 -59.8297) (xy 109.5629 -60.0329) (xy 109.7661 -60.0329)
			)
		)
		(polygon
			(pts
				(xy 109.4105 -59.8297) (xy 108.9279 -59.8297) (xy 108.9279 -60.0329) (xy 109.4105 -60.0329)
			)
		)
		(polygon
			(pts
				(xy 108.7755 -59.8297) (xy 108.5723 -59.8297) (xy 108.5723 -60.0329) (xy 108.7755 -60.0329)
			)
		)
		(polygon
			(pts
				(xy 124.134118 -59.565032) (xy 123.930918 -59.565032) (xy 123.930918 -59.768232) (xy 124.134118 -59.768232)
			)
		)
		(polygon
			(pts
				(xy 124.134118 -59.209432) (xy 123.930918 -59.209432) (xy 123.930918 -59.412632) (xy 124.134118 -59.412632)
			)
		)
		(polygon
			(pts
				(xy 122.453908 -58.871612) (xy 122.250708 -58.871612) (xy 122.250708 -59.074812) (xy 122.453908 -59.074812)
			)
		)
		(polygon
			(pts
				(xy 121.666 -58.8645) (xy 121.4628 -58.8645) (xy 121.4628 -59.0677) (xy 121.666 -59.0677)
			)
		)
		(polygon
			(pts
				(xy 121.3104 -58.8645) (xy 120.8278 -58.8645) (xy 120.8278 -59.0677) (xy 121.3104 -59.0677)
			)
		)
		(polygon
			(pts
				(xy 120.6754 -58.8645) (xy 120.4722 -58.8645) (xy 120.4722 -59.0677) (xy 120.6754 -59.0677)
			)
		)
		(polygon
			(pts
				(xy 119.6848 -58.8645) (xy 119.4816 -58.8645) (xy 119.4816 -59.0677) (xy 119.6848 -59.0677)
			)
		)
		(polygon
			(pts
				(xy 119.3292 -58.8645) (xy 118.8466 -58.8645) (xy 118.8466 -59.0677) (xy 119.3292 -59.0677)
			)
		)
		(polygon
			(pts
				(xy 118.6942 -58.8645) (xy 118.491 -58.8645) (xy 118.491 -59.0677) (xy 118.6942 -59.0677)
			)
		)
		(polygon
			(pts
				(xy 117.6782 -58.8645) (xy 117.475 -58.8645) (xy 117.475 -59.0677) (xy 117.6782 -59.0677)
			)
		)
		(polygon
			(pts
				(xy 117.3226 -58.8645) (xy 116.84 -58.8645) (xy 116.84 -59.0677) (xy 117.3226 -59.0677)
			)
		)
		(polygon
			(pts
				(xy 116.6876 -58.8645) (xy 116.4844 -58.8645) (xy 116.4844 -59.0677) (xy 116.6876 -59.0677)
			)
		)
		(polygon
			(pts
				(xy 115.68176 -58.8645) (xy 115.47856 -58.8645) (xy 115.47856 -59.0677) (xy 115.68176 -59.0677)
			)
		)
		(polygon
			(pts
				(xy 115.32616 -58.8645) (xy 114.84356 -58.8645) (xy 114.84356 -59.0677) (xy 115.32616 -59.0677)
			)
		)
		(polygon
			(pts
				(xy 114.69116 -58.8645) (xy 114.48796 -58.8645) (xy 114.48796 -59.0677) (xy 114.69116 -59.0677)
			)
		)
		(polygon
			(pts
				(xy 113.665 -58.8645) (xy 113.4618 -58.8645) (xy 113.4618 -59.0677) (xy 113.665 -59.0677)
			)
		)
		(polygon
			(pts
				(xy 113.3094 -58.8645) (xy 112.8268 -58.8645) (xy 112.8268 -59.0677) (xy 113.3094 -59.0677)
			)
		)
		(polygon
			(pts
				(xy 112.6744 -58.8645) (xy 112.4712 -58.8645) (xy 112.4712 -59.0677) (xy 112.6744 -59.0677)
			)
		)
		(polygon
			(pts
				(xy 111.6584 -58.8645) (xy 111.4552 -58.8645) (xy 111.4552 -59.0677) (xy 111.6584 -59.0677)
			)
		)
		(polygon
			(pts
				(xy 111.3028 -58.8645) (xy 110.8202 -58.8645) (xy 110.8202 -59.0677) (xy 111.3028 -59.0677)
			)
		)
		(polygon
			(pts
				(xy 110.6678 -58.8645) (xy 110.4646 -58.8645) (xy 110.4646 -59.0677) (xy 110.6678 -59.0677)
			)
		)
		(polygon
			(pts
				(xy 109.7661 -58.8645) (xy 109.5629 -58.8645) (xy 109.5629 -59.0677) (xy 109.7661 -59.0677)
			)
		)
		(polygon
			(pts
				(xy 109.4105 -58.8645) (xy 108.9279 -58.8645) (xy 108.9279 -59.0677) (xy 109.4105 -59.0677)
			)
		)
		(polygon
			(pts
				(xy 124.1298 -58.4708) (xy 123.9266 -58.4708) (xy 123.9266 -58.674) (xy 124.1298 -58.674)
			)
		)
		(polygon
			(pts
				(xy 123.5329 -57.8612) (xy 123.3297 -57.8612) (xy 123.3297 -58.0644) (xy 123.5329 -58.0644)
			)
		)
		(polygon
			(pts
				(xy 123.1773 -57.8612) (xy 122.6947 -57.8612) (xy 122.6947 -58.0644) (xy 123.1773 -58.0644)
			)
		)
		(polygon
			(pts
				(xy 122.5423 -57.8612) (xy 122.3391 -57.8612) (xy 122.3391 -58.0644) (xy 122.5423 -58.0644)
			)
		)
		(polygon
			(pts
				(xy 121.539 -57.8612) (xy 121.3358 -57.8612) (xy 121.3358 -58.0644) (xy 121.539 -58.0644)
			)
		)
		(polygon
			(pts
				(xy 121.1834 -57.8612) (xy 120.7008 -57.8612) (xy 120.7008 -58.0644) (xy 121.1834 -58.0644)
			)
		)
		(polygon
			(pts
				(xy 120.5484 -57.8612) (xy 120.3452 -57.8612) (xy 120.3452 -58.0644) (xy 120.5484 -58.0644)
			)
		)
		(polygon
			(pts
				(xy 119.5451 -57.8612) (xy 119.3419 -57.8612) (xy 119.3419 -58.0644) (xy 119.5451 -58.0644)
			)
		)
		(polygon
			(pts
				(xy 119.1895 -57.8612) (xy 118.7069 -57.8612) (xy 118.7069 -58.0644) (xy 119.1895 -58.0644)
			)
		)
		(polygon
			(pts
				(xy 118.5545 -57.8612) (xy 118.3513 -57.8612) (xy 118.3513 -58.0644) (xy 118.5545 -58.0644)
			)
		)
		(polygon
			(pts
				(xy 117.5385 -57.8612) (xy 117.3353 -57.8612) (xy 117.3353 -58.0644) (xy 117.5385 -58.0644)
			)
		)
		(polygon
			(pts
				(xy 117.1829 -57.8612) (xy 116.7003 -57.8612) (xy 116.7003 -58.0644) (xy 117.1829 -58.0644)
			)
		)
		(polygon
			(pts
				(xy 116.5479 -57.8612) (xy 116.3447 -57.8612) (xy 116.3447 -58.0644) (xy 116.5479 -58.0644)
			)
		)
		(polygon
			(pts
				(xy 115.6335 -57.8612) (xy 115.4303 -57.8612) (xy 115.4303 -58.0644) (xy 115.6335 -58.0644)
			)
		)
		(polygon
			(pts
				(xy 115.2779 -57.8612) (xy 114.7953 -57.8612) (xy 114.7953 -58.0644) (xy 115.2779 -58.0644)
			)
		)
		(polygon
			(pts
				(xy 114.6429 -57.8612) (xy 114.4397 -57.8612) (xy 114.4397 -58.0644) (xy 114.6429 -58.0644)
			)
		)
		(polygon
			(pts
				(xy 113.538 -57.8612) (xy 113.3348 -57.8612) (xy 113.3348 -58.0644) (xy 113.538 -58.0644)
			)
		)
		(polygon
			(pts
				(xy 113.1824 -57.8612) (xy 112.6998 -57.8612) (xy 112.6998 -58.0644) (xy 113.1824 -58.0644)
			)
		)
		(polygon
			(pts
				(xy 112.5474 -57.8612) (xy 112.3442 -57.8612) (xy 112.3442 -58.0644) (xy 112.5474 -58.0644)
			)
		)
		(polygon
			(pts
				(xy 111.5568 -57.8612) (xy 111.3536 -57.8612) (xy 111.3536 -58.0644) (xy 111.5568 -58.0644)
			)
		)
		(polygon
			(pts
				(xy 111.2012 -57.8612) (xy 110.7186 -57.8612) (xy 110.7186 -58.0644) (xy 111.2012 -58.0644)
			)
		)
		(polygon
			(pts
				(xy 110.5662 -57.8612) (xy 110.363 -57.8612) (xy 110.363 -58.0644) (xy 110.5662 -58.0644)
			)
		)
		(polygon
			(pts
				(xy 109.5502 -57.8612) (xy 109.347 -57.8612) (xy 109.347 -58.0644) (xy 109.5502 -58.0644)
			)
		)
		(polygon
			(pts
				(xy 109.1946 -57.8612) (xy 108.712 -57.8612) (xy 108.712 -58.0644) (xy 109.1946 -58.0644)
			)
		)
		(polygon
			(pts
				(xy 108.5596 -57.8612) (xy 108.3564 -57.8612) (xy 108.3564 -58.0644) (xy 108.5596 -58.0644)
			)
		)
		(polygon
			(pts
				(xy 107.7722 -57.8612) (xy 107.569 -57.8612) (xy 107.569 -58.0644) (xy 107.7722 -58.0644)
			)
		)
		(polygon
			(pts
				(xy 107.4166 -57.8612) (xy 107.2134 -57.8612) (xy 107.2134 -58.0644) (xy 107.4166 -58.0644)
			)
		)
		(polygon
			(pts
				(xy 124.1298 -57.8358) (xy 123.9266 -57.8358) (xy 123.9266 -58.3184) (xy 124.1298 -58.3184)
			)
		)
	)
	(zone
		(net "P1V8_E")
		(layer "B.Cu")
		(hatch none 0.5)
		(connect_pads
			(clearance 0.5)
		)
		(min_thickness 0.25)
		(fill yes
			(thermal_gap 0.5)
			(thermal_bridge_width 0.5)
			(island_removal_mode 0)
		)
		(polygon
			(pts
				(xy 111.875316 -71.741284) (xy 111.601504 -72.015096) (xy 110.36935 -72.015096) (xy 110.109 -71.755)
				(xy 109.91215 -71.755) (xy 109.55655 -72.1106) (xy 108.593128 -72.1106) (xy 108.008928 -72.6948)
				(xy 105.8672 -72.6948) (xy 105.753408 -72.808592) (xy 105.753408 -73.506076) (xy 105.833926 -73.586594)
				(xy 114.322606 -73.586594) (xy 115.0874 -72.8218) (xy 115.189 -72.8218) (xy 115.2906 -72.9234) (xy 115.2906 -73.025)
				(xy 115.5954 -73.3298) (xy 116.3828 -73.3298) (xy 116.463826 -73.248774) (xy 116.461286 -73.246234)
				(xy 116.461286 -72.781922) (xy 116.785136 -72.458072) (xy 118.32844 -72.458072) (xy 118.561358 -72.69099)
				(xy 118.561358 -73.124822) (xy 118.754652 -73.318116) (xy 119.518684 -73.318116) (xy 119.66702 -73.16978)
				(xy 119.66702 -72.32142) (xy 119.6594 -72.3138) (xy 119.6594 -72.0852) (xy 119.634 -72.0598) (xy 119.2784 -72.0598)
				(xy 119.2276 -72.009) (xy 119.2276 -71.919084) (xy 119.0498 -71.741284) (xy 118.874286 -71.741284)
				(xy 118.599712 -72.016112) (xy 117.362732 -72.016112) (xy 117.087904 -71.741284) (xy 116.904516 -71.741284)
				(xy 116.9035 -71.7423) (xy 116.8019 -71.7423) (xy 116.5606 -71.9836) (xy 114.307874 -71.9836) (xy 114.065558 -71.741284)
				(xy 113.92916 -71.741284) (xy 113.661444 -72.009) (xy 112.3696 -72.009) (xy 112.10163 -71.741284)
			)
		)
		(polygon
			(pts
				(xy 107.727242 -73.265792) (xy 107.524042 -73.265792) (xy 107.524042 -73.468992) (xy 107.727242 -73.468992)
			)
		)
		(polygon
			(pts
				(xy 107.016042 -73.265792) (xy 106.508042 -73.265792) (xy 106.508042 -73.468992) (xy 107.016042 -73.468992)
			)
		)
		(polygon
			(pts
				(xy 109.5756 -72.39) (xy 109.3724 -72.39) (xy 109.3724 -72.5932) (xy 109.5756 -72.5932)
			)
		)
		(polygon
			(pts
				(xy 119.42826 -72.3392) (xy 119.22506 -72.3392) (xy 119.22506 -72.5424) (xy 119.42826 -72.5424)
			)
		)
		(polygon
			(pts
				(xy 113.6904 -72.2884) (xy 113.4872 -72.2884) (xy 113.4872 -72.4916) (xy 113.6904 -72.4916)
			)
		)
		(polygon
			(pts
				(xy 113.3348 -72.2884) (xy 113.1316 -72.2884) (xy 113.1316 -72.4916) (xy 113.3348 -72.4916)
			)
		)
		(polygon
			(pts
				(xy 112.9792 -72.2884) (xy 112.776 -72.2884) (xy 112.776 -72.4916) (xy 112.9792 -72.4916)
			)
		)
		(polygon
			(pts
				(xy 112.6236 -72.2884) (xy 112.4204 -72.2884) (xy 112.4204 -72.4916) (xy 112.6236 -72.4916)
			)
		)
		(polygon
			(pts
				(xy 111.506 -72.2884) (xy 111.3028 -72.2884) (xy 111.3028 -72.4916) (xy 111.506 -72.4916)
			)
		)
		(polygon
			(pts
				(xy 111.1504 -72.2884) (xy 110.6678 -72.2884) (xy 110.6678 -72.4916) (xy 111.1504 -72.4916)
			)
		)
		(polygon
			(pts
				(xy 110.5154 -72.2884) (xy 110.3122 -72.2884) (xy 110.3122 -72.4916) (xy 110.5154 -72.4916)
			)
		)
		(polygon
			(pts
				(xy 116.2812 -72.263) (xy 116.078 -72.263) (xy 116.0526 -72.263508) (xy 115.8494 -72.263508) (xy 115.8494 -72.466708)
				(xy 116.0526 -72.466708) (xy 116.078 -72.4662) (xy 116.2812 -72.4662)
			)
		)
		(polygon
			(pts
				(xy 115.4684 -72.263) (xy 115.2652 -72.263) (xy 115.2652 -72.4662) (xy 115.4684 -72.4662) (xy 115.4938 -72.466708)
				(xy 115.697 -72.466708) (xy 115.697 -72.263508) (xy 115.4938 -72.263508)
			)
		)
		(polygon
			(pts
				(xy 115.1128 -72.263) (xy 114.681 -72.263) (xy 114.681 -72.4662) (xy 115.1128 -72.4662)
			)
		)
		(polygon
			(pts
				(xy 114.5286 -72.263) (xy 114.3254 -72.263) (xy 114.3254 -72.4662) (xy 114.5286 -72.4662)
			)
		)
	)
	(zone
		(layer "B.Cu")
		(hatch none 0.5)
		(connect_pads
			(clearance 0)
		)
		(min_thickness 0.25)
		(keepout
			(tracks not_allowed)
			(vias allowed)
			(pads allowed)
			(copperpour not_allowed)
			(footprints allowed)
		)
		(placement
			(enabled no)
			(sheetname "")
		)
		(fill
			(thermal_gap 0.5)
			(thermal_bridge_width 0.5)
			(island_removal_mode 0)
		)
		(polygon
			(pts
				(arc
					(start 126.000256 -63.641986)
					(mid 125.641862 -63.999999)
					(end 126.000002 -64.358266)
				)
				(arc
					(start 127 -64.358266)
					(mid 127.355721 -64.041683)
					(end 127.08255 -63.651638)
				)
				(arc
					(start 126.750572 -63.651638)
					(mid 126.681065 -63.680429)
					(end 126.652274 -63.749936)
				)
				(arc
					(start 126.652274 -63.90005)
					(mid 126.664847 -63.930403)
					(end 126.6952 -63.942976)
				)
				(arc
					(start 126.765558 -63.942976)
					(mid 127.241307 -64.000126)
					(end 126.765558 -64.057276)
				)
				(xy 126.671578 -64.057276)
				(arc
					(start 126.669292 -64.055244)
					(mid 126.583943 -64.011307)
					(end 126.540006 -63.925958)
				)
				(xy 126.537974 -63.923672) (xy 126.537974 -63.726314)
				(arc
					(start 126.539498 -63.72479)
					(mid 126.549174 -63.68194)
					(end 126.567438 -63.641986)
				)
				(arc
					(start 126.482602 -63.641986)
					(mid 126.467002 -63.694961)
					(end 126.461774 -63.749936)
				)
				(xy 126.461774 -63.923926)
				(arc
					(start 126.459742 -63.926212)
					(mid 126.415882 -64.011384)
					(end 126.33071 -64.055244)
				)
				(xy 126.328424 -64.057276)
				(arc
					(start 126.234444 -64.057276)
					(mid 125.758695 -64.000126)
					(end 126.234444 -63.942976)
				)
				(arc
					(start 126.304802 -63.942976)
					(mid 126.334976 -63.930478)
					(end 126.347474 -63.900304)
				)
				(xy 126.347474 -63.726314)
				(arc
					(start 126.348236 -63.725552)
					(mid 126.353027 -63.683403)
					(end 126.362206 -63.641986)
				)
			)
		)
	)
	(zone
		(layer "B.Cu")
		(hatch none 0.5)
		(connect_pads
			(clearance 0)
		)
		(min_thickness 0.25)
		(keepout
			(tracks not_allowed)
			(vias allowed)
			(pads allowed)
			(copperpour not_allowed)
			(footprints allowed)
		)
		(placement
			(enabled no)
			(sheetname "")
		)
		(fill
			(thermal_gap 0.5)
			(thermal_bridge_width 0.5)
			(island_removal_mode 0)
		)
		(polygon
			(pts
				(arc
					(start 182.361332 -9.800082)
					(mid 181.799992 -9.238742)
					(end 181.238652 -9.800082)
				)
				(xy 181.238652 -10.26414) (xy 181.289452 -10.259568) (xy 181.290214 -10.258552) (xy 181.31282 -10.258552)
				(xy 181.325774 -10.258552) (xy 181.330346 -10.258552) (xy 181.619398 -10.258552)
				(arc
					(start 181.62397 -10.258552)
					(mid 181.681999 -10.237399)
					(end 181.71287 -10.183876)
				)
				(arc
					(start 181.71287 -10.183876)
					(mid 181.801671 -9.406413)
					(end 181.885844 -10.184384)
				)
				(xy 181.885844 -10.203942)
				(arc
					(start 181.88305 -10.206482)
					(mid 181.809138 -10.35355)
					(end 181.66207 -10.427462)
				)
				(xy 181.65953 -10.430256) (xy 181.632098 -10.430256) (xy 181.62397 -10.430256) (xy 181.619398 -10.430256)
				(xy 181.330346 -10.430256)
				(arc
					(start 181.325774 -10.430256)
					(mid 181.282045 -10.432144)
					(end 181.238652 -10.437876)
				)
				(arc
					(start 181.238652 -10.580624)
					(mid 181.263385 -10.575291)
					(end 181.288436 -10.571734)
				)
				(xy 181.290214 -10.569956) (xy 181.316376 -10.569956) (xy 181.325774 -10.569702) (xy 181.330346 -10.569956)
				(xy 181.619144 -10.569956) (xy 181.623716 -10.569702) (xy 181.631844 -10.569956) (xy 181.659276 -10.569956)
				(arc
					(start 181.661816 -10.572496)
					(mid 181.809061 -10.646485)
					(end 181.88305 -10.79373)
				)
				(xy 181.885844 -10.79627)
				(arc
					(start 181.885844 -10.815828)
					(mid 181.801671 -11.593793)
					(end 181.71287 -10.816336)
				)
				(arc
					(start 181.71287 -10.816336)
					(mid 181.681967 -10.762582)
					(end 181.623716 -10.741406)
				)
				(xy 181.619144 -10.741152) (xy 181.330346 -10.741152)
				(arc
					(start 181.325774 -10.741406)
					(mid 181.280865 -10.74695)
					(end 181.238652 -10.76325)
				)
				(arc
					(start 181.238652 -11.199876)
					(mid 181.799865 -11.76147)
					(end 182.361332 -11.20013)
				)
			)
		)
	)
	(zone
		(layer "B.Cu")
		(hatch none 0.5)
		(connect_pads
			(clearance 0)
		)
		(min_thickness 0.25)
		(keepout
			(tracks not_allowed)
			(vias allowed)
			(pads allowed)
			(copperpour not_allowed)
			(footprints allowed)
		)
		(placement
			(enabled no)
			(sheetname "")
		)
		(fill
			(thermal_gap 0.5)
			(thermal_bridge_width 0.5)
			(island_removal_mode 0)
		)
		(polygon
			(pts
				(arc
					(start 124.361448 -2.600198)
					(mid 123.800108 -2.038858)
					(end 123.238768 -2.600198)
				)
				(arc
					(start 123.238768 -3.028442)
					(mid 123.27172 -3.024751)
					(end 123.304808 -3.0226)
				)
				(xy 123.30557 -3.021838)
				(arc
					(start 123.680982 -3.021838)
					(mid 123.697895 -3.018474)
					(end 123.712224 -3.008884)
				)
				(arc
					(start 123.712224 -3.008884)
					(mid 123.719821 -2.99858)
					(end 123.724162 -2.986532)
				)
				(arc
					(start 123.724162 -2.986532)
					(mid 123.801134 -2.206422)
					(end 123.875038 -2.986786)
				)
				(xy 123.875038 -3.00863)
				(arc
					(start 123.87199 -3.011678)
					(mid 123.853059 -3.067209)
					(end 123.818396 -3.114548)
				)
				(arc
					(start 123.818396 -3.114548)
					(mid 123.77088 -3.149578)
					(end 123.715018 -3.16865)
				)
				(xy 123.71197 -3.171698)
				(arc
					(start 123.336558 -3.171698)
					(mid 123.287474 -3.17388)
					(end 123.238768 -3.180334)
				)
				(arc
					(start 123.238768 -3.44424)
					(mid 123.270893 -3.435359)
					(end 123.303792 -3.430016)
				)
				(xy 123.30557 -3.428238) (xy 123.71197 -3.428238)
				(arc
					(start 123.715018 -3.431286)
					(mid 123.770867 -3.450383)
					(end 123.818396 -3.485388)
				)
				(arc
					(start 123.818396 -3.485388)
					(mid 123.853084 -3.532714)
					(end 123.87199 -3.588258)
				)
				(xy 123.875038 -3.591306)
				(arc
					(start 123.875038 -3.613404)
					(mid 123.80101 -4.393726)
					(end 123.724416 -3.613658)
				)
				(arc
					(start 123.724416 -3.613658)
					(mid 123.720018 -3.601436)
					(end 123.712224 -3.591052)
				)
				(arc
					(start 123.712224 -3.591052)
					(mid 123.69789 -3.581474)
					(end 123.680982 -3.578098)
				)
				(arc
					(start 123.336558 -3.578098)
					(mid 123.284825 -3.586778)
					(end 123.238768 -3.61188)
				)
				(arc
					(start 123.238768 -3.999738)
					(mid 123.799981 -4.561332)
					(end 124.361448 -3.999992)
				)
			)
		)
	)
	(zone
		(net "GND")
		(layer "B.Cu")
		(hatch none 0.5)
		(connect_pads
			(clearance 0.5)
		)
		(min_thickness 0.25)
		(fill yes
			(thermal_gap 0.5)
			(thermal_bridge_width 0.5)
			(island_removal_mode 0)
		)
		(polygon
			(pts
				(xy 73.025 -62.23) (xy 72.263 -62.992) (xy 72.263 -65.405) (xy 72.39 -65.532) (xy 75.576176 -65.532)
				(xy 76.962 -64.146176) (xy 76.962 -62.357) (xy 76.835 -62.23)
			)
		)
		(polygon
			(pts
				(xy 75.9968 -63.1444) (xy 75.7936 -63.1444) (xy 75.7936 -63.3476) (xy 75.9968 -63.3476)
			)
		)
	)
	(zone
		(net "GB_VDDA")
		(layer "B.Cu")
		(hatch none 0.5)
		(connect_pads
			(clearance 0.5)
		)
		(min_thickness 0.25)
		(fill yes
			(thermal_gap 0.5)
			(thermal_bridge_width 0.5)
			(island_removal_mode 0)
		)
		(polygon
			(pts
				(xy 128.370076 -53.684424) (xy 128.3462 -53.7083) (xy 128.3462 -54.229) (xy 127.762 -54.8132) (xy 127.762 -55.1688)
				(xy 128.3716 -55.7784) (xy 128.3716 -56.1721) (xy 127.762 -56.7817) (xy 127.762 -57.2262) (xy 128.3589 -57.8231)
				(xy 128.3589 -58.2295) (xy 127.762 -58.8264) (xy 127.762 -59.126882) (xy 128.776222 -60.141104)
				(xy 129.077212 -60.141104) (xy 129.25171 -59.966606) (xy 129.25171 -53.75021) (xy 129.185924 -53.684424)
			)
		)
		(polygon
			(pts
				(xy 129.016252 -59.448192) (xy 128.813052 -59.448192) (xy 128.813052 -59.651392) (xy 129.016252 -59.651392)
			)
		)
		(polygon
			(pts
				(xy 128.554988 -59.212226) (xy 128.351788 -59.212226) (xy 128.351788 -59.415426) (xy 128.554988 -59.415426)
			)
		)
		(polygon
			(pts
				(xy 129.016252 -59.092592) (xy 128.813052 -59.092592) (xy 128.813052 -59.295792) (xy 129.016252 -59.295792)
			)
		)
		(polygon
			(pts
				(xy 129.016252 -58.772806) (xy 128.813052 -58.772806) (xy 128.813052 -58.976006) (xy 129.016252 -58.976006)
			)
		)
		(polygon
			(pts
				(xy 128.554988 -58.570114) (xy 128.351788 -58.570114) (xy 128.351788 -58.773314) (xy 128.554988 -58.773314)
			)
		)
		(polygon
			(pts
				(xy 129.016252 -58.417206) (xy 128.813052 -58.417206) (xy 128.813052 -58.620406) (xy 129.016252 -58.620406)
			)
		)
		(polygon
			(pts
				(xy 129.016252 -57.42686) (xy 128.813052 -57.42686) (xy 128.813052 -57.63006) (xy 129.016252 -57.63006)
			)
		)
		(polygon
			(pts
				(xy 128.554988 -57.2135) (xy 128.351788 -57.2135) (xy 128.351788 -57.4167) (xy 128.554988 -57.4167)
			)
		)
		(polygon
			(pts
				(xy 129.016252 -56.79186) (xy 128.813052 -56.79186) (xy 128.813052 -57.27446) (xy 129.016252 -57.27446)
			)
		)
		(polygon
			(pts
				(xy 128.554988 -56.5785) (xy 128.351788 -56.5785) (xy 128.351788 -56.7817) (xy 128.554988 -56.7817)
			)
		)
		(polygon
			(pts
				(xy 129.016252 -56.43626) (xy 128.813052 -56.43626) (xy 128.813052 -56.63946) (xy 129.016252 -56.63946)
			)
		)
		(polygon
			(pts
				(xy 129.016252 -55.310024) (xy 128.813052 -55.310024) (xy 128.813052 -55.513224) (xy 129.016252 -55.513224)
			)
		)
		(polygon
			(pts
				(xy 128.554988 -55.2196) (xy 128.351788 -55.2196) (xy 128.351788 -55.4228) (xy 128.554988 -55.4228)
			)
		)
		(polygon
			(pts
				(xy 129.016252 -54.678834) (xy 128.813052 -54.678834) (xy 128.813052 -55.157624) (xy 129.016252 -55.157624)
			)
		)
		(polygon
			(pts
				(xy 128.554988 -54.578504) (xy 128.351788 -54.578504) (xy 128.351788 -54.781704) (xy 128.554988 -54.781704)
			)
		)
		(polygon
			(pts
				(xy 129.016252 -54.323234) (xy 128.813052 -54.323234) (xy 128.813052 -54.526434) (xy 129.016252 -54.526434)
			)
		)
	)
	(zone
		(layer "B.Cu")
		(hatch none 0.5)
		(connect_pads
			(clearance 0)
		)
		(min_thickness 0.25)
		(keepout
			(tracks not_allowed)
			(vias allowed)
			(pads allowed)
			(copperpour not_allowed)
			(footprints allowed)
		)
		(placement
			(enabled no)
			(sheetname "")
		)
		(fill
			(thermal_gap 0.5)
			(thermal_bridge_width 0.5)
			(island_removal_mode 0)
		)
		(polygon
			(pts
				(arc
					(start 135.161528 -2.600198)
					(mid 134.600188 -2.038858)
					(end 134.038848 -2.600198)
				)
				(arc
					(start 134.038848 -3.028442)
					(mid 134.0718 -3.024751)
					(end 134.104888 -3.0226)
				)
				(xy 134.10565 -3.021838)
				(arc
					(start 134.481062 -3.021838)
					(mid 134.497975 -3.018474)
					(end 134.512304 -3.008884)
				)
				(arc
					(start 134.512304 -3.008884)
					(mid 134.519901 -2.99858)
					(end 134.524242 -2.986532)
				)
				(arc
					(start 134.524242 -2.986532)
					(mid 134.601214 -2.206422)
					(end 134.675118 -2.986786)
				)
				(xy 134.675118 -3.00863)
				(arc
					(start 134.67207 -3.011678)
					(mid 134.653139 -3.067209)
					(end 134.618476 -3.114548)
				)
				(arc
					(start 134.618476 -3.114548)
					(mid 134.57096 -3.149578)
					(end 134.515098 -3.16865)
				)
				(xy 134.51205 -3.171698)
				(arc
					(start 134.136638 -3.171698)
					(mid 134.087554 -3.17388)
					(end 134.038848 -3.180334)
				)
				(arc
					(start 134.038848 -3.44424)
					(mid 134.070973 -3.435359)
					(end 134.103872 -3.430016)
				)
				(xy 134.10565 -3.428238) (xy 134.51205 -3.428238)
				(arc
					(start 134.515098 -3.431286)
					(mid 134.570947 -3.450383)
					(end 134.618476 -3.485388)
				)
				(arc
					(start 134.618476 -3.485388)
					(mid 134.653164 -3.532714)
					(end 134.67207 -3.588258)
				)
				(xy 134.675118 -3.591306)
				(arc
					(start 134.675118 -3.613404)
					(mid 134.60109 -4.393726)
					(end 134.524496 -3.613658)
				)
				(arc
					(start 134.524496 -3.613658)
					(mid 134.520098 -3.601436)
					(end 134.512304 -3.591052)
				)
				(arc
					(start 134.512304 -3.591052)
					(mid 134.49797 -3.581474)
					(end 134.481062 -3.578098)
				)
				(arc
					(start 134.136638 -3.578098)
					(mid 134.084905 -3.586778)
					(end 134.038848 -3.61188)
				)
				(arc
					(start 134.038848 -3.999738)
					(mid 134.600061 -4.561332)
					(end 135.161528 -3.999992)
				)
			)
		)
	)
	(zone
		(layer "B.Cu")
		(hatch none 0.5)
		(connect_pads
			(clearance 0)
		)
		(min_thickness 0.25)
		(keepout
			(tracks allowed)
			(vias allowed)
			(pads allowed)
			(copperpour allowed)
			(footprints not_allowed)
		)
		(placement
			(enabled no)
			(sheetname "")
		)
		(fill
			(thermal_gap 0.5)
			(thermal_bridge_width 0.5)
			(island_removal_mode 0)
		)
		(polygon
			(pts
				(arc
					(start 25.980898 -9.92505)
					(mid 29.481018 -13.42517)
					(end 32.980884 -9.92505)
				)
				(arc
					(start 32.980884 -9.92505)
					(mid 29.481018 -6.425184)
					(end 25.980898 -9.92505)
				)
			)
		)
	)
	(zone
		(layer "B.Cu")
		(hatch none 0.5)
		(connect_pads
			(clearance 0)
		)
		(min_thickness 0.25)
		(keepout
			(tracks not_allowed)
			(vias allowed)
			(pads allowed)
			(copperpour not_allowed)
			(footprints allowed)
		)
		(placement
			(enabled no)
			(sheetname "")
		)
		(fill
			(thermal_gap 0.5)
			(thermal_bridge_width 0.5)
			(island_removal_mode 0)
		)
		(polygon
			(pts
				(arc
					(start 4.99999 -139.224258)
					(mid 18.50018 -131.430014)
					(end 4.99999 -123.63577)
				)
			)
		)
	)
	(zone
		(net "GND")
		(layer "B.Cu")
		(hatch none 0.5)
		(connect_pads
			(clearance 0.5)
		)
		(min_thickness 0.25)
		(fill yes
			(thermal_gap 0.5)
			(thermal_bridge_width 0.5)
			(island_removal_mode 0)
		)
		(polygon
			(pts
				(xy 177.914808 -36.8554) (xy 177.876708 -36.8935) (xy 177.876708 -44.055792) (xy 177.938938 -44.118276)
				(xy 178.082702 -44.26204) (xy 178.297078 -44.26204) (xy 178.564032 -43.994832) (xy 178.564032 -43.812968)
				(xy 178.60645 -43.77055) (xy 178.60645 -36.957) (xy 178.50485 -36.8554)
			)
		)
		(polygon
			(pts
				(xy 178.390042 -41.964356) (xy 178.186842 -41.964356) (xy 178.186842 -42.167556) (xy 178.390042 -42.167556)
			)
		)
		(polygon
			(pts
				(xy 178.390042 -41.405556) (xy 178.186842 -41.405556) (xy 178.186842 -41.811956) (xy 178.390042 -41.811956)
			)
		)
		(polygon
			(pts
				(xy 178.390042 -41.049956) (xy 178.186842 -41.049956) (xy 178.186842 -41.253156) (xy 178.390042 -41.253156)
			)
		)
		(polygon
			(pts
				(xy 178.395376 -40.346122) (xy 178.192176 -40.346122) (xy 178.192176 -40.549322) (xy 178.395376 -40.549322)
			)
		)
		(polygon
			(pts
				(xy 178.395376 -39.787322) (xy 178.192176 -39.787322) (xy 178.192176 -40.193722) (xy 178.395376 -40.193722)
			)
		)
		(polygon
			(pts
				(xy 178.395376 -39.431722) (xy 178.192176 -39.431722) (xy 178.192176 -39.634922) (xy 178.395376 -39.634922)
			)
		)
		(polygon
			(pts
				(xy 178.3969 -38.74516) (xy 178.1937 -38.74516) (xy 178.1937 -38.94836) (xy 178.3969 -38.94836)
			)
		)
		(polygon
			(pts
				(xy 178.3969 -38.18636) (xy 178.1937 -38.18636) (xy 178.1937 -38.59276) (xy 178.3969 -38.59276)
			)
		)
		(polygon
			(pts
				(xy 178.3969 -37.83076) (xy 178.1937 -37.83076) (xy 178.1937 -38.03396) (xy 178.3969 -38.03396)
			)
		)
		(polygon
			(pts
				(xy 178.397408 -37.12591) (xy 178.194208 -37.12591) (xy 178.194208 -37.32911) (xy 178.397408 -37.32911)
			)
		)
	)
	(zone
		(layer "B.Cu")
		(hatch none 0.5)
		(connect_pads
			(clearance 0)
		)
		(min_thickness 0.25)
		(keepout
			(tracks not_allowed)
			(vias allowed)
			(pads allowed)
			(copperpour not_allowed)
			(footprints allowed)
		)
		(placement
			(enabled no)
			(sheetname "")
		)
		(fill
			(thermal_gap 0.5)
			(thermal_bridge_width 0.5)
			(island_removal_mode 0)
		)
		(polygon
			(pts
				(arc
					(start 103.983536 -111.30915)
					(mid 103.759 -110.566454)
					(end 103.016304 -110.79099)
				)
				(xy 102.86365 -111.075978) (xy 103.065072 -111.385604) (xy 103.095298 -111.41583) (xy 103.103426 -111.42218)
				(xy 103.11765 -111.4298) (xy 103.121714 -111.429038) (xy 103.125778 -111.431578) (xy 103.126286 -111.431578)
				(xy 103.146606 -111.44504)
				(arc
					(start 103.153718 -111.448596)
					(mid 103.188049 -111.448112)
					(end 103.213916 -111.425482)
				)
				(arc
					(start 103.257604 -111.343948)
					(mid 103.680223 -110.714709)
					(end 103.389684 -111.414814)
				)
				(xy 103.331264 -111.523526)
				(arc
					(start 103.327454 -111.524796)
					(mid 103.227857 -111.592942)
					(end 103.107236 -111.59109)
				)
				(xy 103.104696 -111.592106) (xy 103.100886 -111.590074) (xy 103.095552 -111.59109) (xy 103.09225 -111.589058)
				(xy 103.091742 -111.589058) (xy 103.069898 -111.57458) (xy 103.046276 -111.562642) (xy 103.046022 -111.562388)
				(xy 103.041704 -111.560102) (xy 103.041196 -111.558832) (xy 103.030528 -111.553244) (xy 103.013764 -111.5441)
				(xy 103.011732 -111.5441) (xy 103.009446 -111.541814) (xy 103.00335 -111.538512) (xy 103.00208 -111.534448)
				(xy 102.969314 -111.501682) (xy 102.960678 -111.499904) (xy 102.948232 -111.4806) (xy 102.931722 -111.46409)
				(xy 102.931722 -111.455454) (xy 102.782878 -111.2266) (xy 102.644702 -111.484664) (xy 102.747826 -111.642906)
				(arc
					(start 102.80777 -111.703358)
					(mid 102.851481 -111.741727)
					(end 102.899718 -111.774224)
				)
				(xy 102.9081 -111.778796) (xy 102.920292 -111.785146) (xy 102.9208 -111.784892) (xy 102.924356 -111.786924)
				(xy 102.925372 -111.78667) (xy 102.939596 -111.795306) (xy 102.950772 -111.795306) (xy 102.963726 -111.80826)
				(xy 102.971854 -111.812324) (xy 102.974648 -111.813848) (xy 102.974902 -111.814102) (xy 102.980744 -111.81715)
				(arc
					(start 102.982268 -111.821722)
					(mid 103.051547 -111.921499)
					(end 103.050086 -112.042956)
				)
				(xy 103.051356 -112.04702) (xy 103.036624 -112.074198)
				(arc
					(start 102.992682 -112.15624)
					(mid 102.570074 -112.785961)
					(end 102.860602 -112.085374)
				)
				(arc
					(start 102.904544 -112.003332)
					(mid 102.909892 -111.972879)
					(end 102.896162 -111.945166)
				)
				(xy 102.888542 -111.945166) (xy 102.87508 -111.931704) (xy 102.855268 -111.921798) (xy 102.855014 -111.921544)
				(xy 102.851204 -111.919512) (xy 102.84841 -111.917988) (xy 102.847902 -111.916718) (xy 102.837996 -111.911384)
				(xy 102.804468 -111.893858)
				(arc
					(start 102.803706 -111.891318)
					(mid 102.762971 -111.862843)
					(end 102.724712 -111.83112)
				)
				(xy 102.723442 -111.83112) (xy 102.651814 -111.758984) (xy 102.643178 -111.757206) (xy 102.630478 -111.737902)
				(xy 102.614222 -111.721392) (xy 102.614222 -111.712502) (xy 102.56393 -111.63554) (xy 102.266496 -112.190784)
				(arc
					(start 102.266496 -112.191038)
					(mid 102.491032 -112.933734)
					(end 103.233728 -112.709198)
				)
			)
		)
	)
	(zone
		(layer "B.Cu")
		(hatch none 0.5)
		(connect_pads
			(clearance 0)
		)
		(min_thickness 0.25)
		(keepout
			(tracks not_allowed)
			(vias allowed)
			(pads allowed)
			(copperpour not_allowed)
			(footprints allowed)
		)
		(placement
			(enabled no)
			(sheetname "")
		)
		(fill
			(thermal_gap 0.5)
			(thermal_bridge_width 0.5)
			(island_removal_mode 0)
		)
		(polygon
			(pts
				(arc
					(start 172.747432 -30.0736)
					(mid 172.405526 -30.099086)
					(end 172.241718 -30.400244)
				)
				(arc
					(start 172.241972 -31.199836)
					(mid 172.600112 -31.55823)
					(end 172.958252 -31.199836)
				)
				(xy 172.958252 -31.029402) (xy 172.957998 -30.711648)
				(arc
					(start 172.7708 -31.029402)
					(mid 172.477471 -31.408004)
					(end 172.666914 -30.968188)
				)
				(xy 172.939456 -30.5054)
				(arc
					(start 172.939456 -30.286706)
					(mid 172.909933 -30.220974)
					(end 172.867828 -30.1625)
				)
				(xy 172.867828 -30.21711)
				(arc
					(start 172.80763 -30.277562)
					(mid 172.429333 -30.570515)
					(end 172.722286 -30.192218)
				)
				(xy 172.747432 -30.167326)
			)
		)
	)
	(zone
		(layer "B.Cu")
		(hatch none 0.5)
		(connect_pads
			(clearance 0)
		)
		(min_thickness 0.25)
		(keepout
			(tracks allowed)
			(vias allowed)
			(pads allowed)
			(copperpour allowed)
			(footprints allowed)
		)
		(placement
			(enabled no)
			(sheetname "")
		)
		(fill
			(thermal_gap 0.5)
			(thermal_bridge_width 0.5)
			(island_removal_mode 0)
		)
		(polygon
			(pts
				(xy 104.7496 -114.6048) (xy 104.7496 -113.7412) (xy 110.109 -113.7412) (xy 110.109 -114.6048)
			)
		)
	)
	(zone
		(net "GB_VDDH")
		(layer "B.Cu")
		(hatch none 0.5)
		(connect_pads
			(clearance 0.5)
		)
		(min_thickness 0.25)
		(fill yes
			(thermal_gap 0.5)
			(thermal_bridge_width 0.5)
			(island_removal_mode 0)
		)
		(polygon
			(pts
				(xy 108.96854 -61.638434) (xy 108.630974 -61.976) (xy 107.873546 -61.976) (xy 107.811316 -62.03823)
				(xy 107.811316 -62.626494) (xy 107.904534 -62.719712) (xy 108.522262 -62.719712) (xy 108.780072 -62.461902)
				(xy 120.159272 -62.461902) (xy 120.556782 -62.859412) (xy 120.556782 -71.146416) (xy 120.697498 -71.287132)
				(xy 121.212356 -71.287132) (xy 121.346214 -71.153274) (xy 121.346214 -61.86043) (xy 121.124218 -61.638434)
			)
		)
		(polygon
			(pts
				(xy 121.1834 -62.148466) (xy 120.9802 -62.148466) (xy 120.9802 -62.351666) (xy 121.1834 -62.351666)
			)
		)
		(polygon
			(pts
				(xy 120.5738 -62.148466) (xy 120.3706 -62.148466) (xy 120.3706 -62.351666) (xy 120.5738 -62.351666)
			)
		)
		(polygon
			(pts
				(xy 119.1768 -62.148466) (xy 118.9736 -62.148466) (xy 118.9736 -62.351666) (xy 119.1768 -62.351666)
			)
		)
		(polygon
			(pts
				(xy 118.5672 -62.148466) (xy 118.364 -62.148466) (xy 118.364 -62.351666) (xy 118.5672 -62.351666)
			)
		)
		(polygon
			(pts
				(xy 117.1194 -62.148466) (xy 116.9162 -62.148466) (xy 116.9162 -62.351666) (xy 117.1194 -62.351666)
			)
		)
		(polygon
			(pts
				(xy 116.5098 -62.148466) (xy 116.3066 -62.148466) (xy 116.3066 -62.351666) (xy 116.5098 -62.351666)
			)
		)
		(polygon
			(pts
				(xy 115.0874 -62.148466) (xy 114.8842 -62.148466) (xy 114.8842 -62.351666) (xy 115.0874 -62.351666)
			)
		)
		(polygon
			(pts
				(xy 114.4778 -62.148466) (xy 114.2746 -62.148466) (xy 114.2746 -62.351666) (xy 114.4778 -62.351666)
			)
		)
		(polygon
			(pts
				(xy 113.3983 -62.148466) (xy 113.1951 -62.148466) (xy 113.1951 -62.351666) (xy 113.3983 -62.351666)
			)
		)
		(polygon
			(pts
				(xy 112.7887 -62.148466) (xy 112.5855 -62.148466) (xy 112.5855 -62.351666) (xy 112.7887 -62.351666)
			)
		)
		(polygon
			(pts
				(xy 111.6584 -62.148466) (xy 111.4552 -62.148466) (xy 111.4552 -62.351666) (xy 111.6584 -62.351666)
			)
		)
		(polygon
			(pts
				(xy 111.0488 -62.148466) (xy 110.8456 -62.148466) (xy 110.8456 -62.351666) (xy 111.0488 -62.351666)
			)
		)
		(polygon
			(pts
				(xy 109.74578 -62.148466) (xy 109.54258 -62.148466) (xy 109.54258 -62.351666) (xy 109.74578 -62.351666)
			)
		)
		(polygon
			(pts
				(xy 109.13618 -62.148466) (xy 108.93298 -62.148466) (xy 108.93298 -62.351666) (xy 109.13618 -62.351666)
			)
		)
	)
	(zone
		(net "P12V_STBY_SCC")
		(layer "B.Cu")
		(hatch none 0.5)
		(connect_pads
			(clearance 0.5)
		)
		(min_thickness 0.25)
		(fill yes
			(thermal_gap 0.5)
			(thermal_bridge_width 0.5)
			(island_removal_mode 0)
		)
		(polygon
			(pts
				(xy 43.348402 -104.955086) (xy 42.943018 -105.36047) (xy 42.943018 -110.808008) (xy 42.586402 -111.164624)
				(xy 42.586402 -114.002058) (xy 42.76471 -114.180366) (xy 44.791376 -114.180366) (xy 45.439838 -113.531904)
				(xy 45.439838 -105.311702) (xy 45.083222 -104.955086)
			)
		)
		(polygon
			(pts
				(xy 44.154852 -110.27918) (xy 43.951652 -110.27918) (xy 43.951652 -110.48238) (xy 44.154852 -110.48238)
			)
		)
		(polygon
			(pts
				(xy 43.291252 -110.27918) (xy 43.088052 -110.27918) (xy 43.088052 -110.48238) (xy 43.291252 -110.48238)
			)
		)
		(polygon
			(pts
				(xy 44.154852 -109.41558) (xy 43.951652 -109.41558) (xy 43.951652 -109.61878) (xy 44.154852 -109.61878)
			)
		)
		(polygon
			(pts
				(xy 43.291252 -109.41558) (xy 43.088052 -109.41558) (xy 43.088052 -109.61878) (xy 43.291252 -109.61878)
			)
		)
	)
	(zone
		(layer "B.Cu")
		(hatch none 0.5)
		(connect_pads
			(clearance 0)
		)
		(min_thickness 0.25)
		(keepout
			(tracks not_allowed)
			(vias allowed)
			(pads allowed)
			(copperpour not_allowed)
			(footprints allowed)
		)
		(placement
			(enabled no)
			(sheetname "")
		)
		(fill
			(thermal_gap 0.5)
			(thermal_bridge_width 0.5)
			(island_removal_mode 0)
		)
		(polygon
			(pts
				(arc
					(start 93.761306 -3.800094)
					(mid 93.199966 -3.238754)
					(end 92.638626 -3.800094)
				)
				(arc
					(start 92.638626 -4.228592)
					(mid 92.671578 -4.224901)
					(end 92.704666 -4.22275)
				)
				(xy 92.705428 -4.221988)
				(arc
					(start 93.08084 -4.221988)
					(mid 93.097753 -4.218624)
					(end 93.112082 -4.209034)
				)
				(arc
					(start 93.112082 -4.209034)
					(mid 93.119848 -4.198635)
					(end 93.124274 -4.186428)
				)
				(arc
					(start 93.124274 -4.186428)
					(mid 93.200868 -3.406367)
					(end 93.274896 -4.186682)
				)
				(xy 93.274896 -4.20878)
				(arc
					(start 93.271848 -4.211828)
					(mid 93.252917 -4.267359)
					(end 93.218254 -4.314698)
				)
				(arc
					(start 93.218254 -4.314698)
					(mid 93.170738 -4.349728)
					(end 93.114876 -4.3688)
				)
				(xy 93.111828 -4.371848)
				(arc
					(start 92.736416 -4.371848)
					(mid 92.687332 -4.37403)
					(end 92.638626 -4.380484)
				)
				(arc
					(start 92.638626 -4.64439)
					(mid 92.670751 -4.635509)
					(end 92.70365 -4.630166)
				)
				(xy 92.705428 -4.628388) (xy 93.111828 -4.628388)
				(arc
					(start 93.114876 -4.631436)
					(mid 93.170725 -4.650533)
					(end 93.218254 -4.685538)
				)
				(arc
					(start 93.218254 -4.685538)
					(mid 93.252942 -4.732864)
					(end 93.271848 -4.788408)
				)
				(xy 93.274896 -4.791456)
				(arc
					(start 93.274896 -4.813554)
					(mid 93.200868 -5.593876)
					(end 93.124274 -4.813808)
				)
				(arc
					(start 93.124274 -4.813808)
					(mid 93.119876 -4.801586)
					(end 93.112082 -4.791202)
				)
				(arc
					(start 93.112082 -4.791202)
					(mid 93.097748 -4.781624)
					(end 93.08084 -4.778248)
				)
				(arc
					(start 92.736416 -4.778248)
					(mid 92.684683 -4.786928)
					(end 92.638626 -4.81203)
				)
				(arc
					(start 92.638626 -5.199888)
					(mid 93.199839 -5.761482)
					(end 93.761306 -5.200142)
				)
			)
		)
	)
	(zone
		(layer "B.Cu")
		(hatch none 0.5)
		(connect_pads
			(clearance 0)
		)
		(min_thickness 0.25)
		(keepout
			(tracks not_allowed)
			(vias allowed)
			(pads allowed)
			(copperpour not_allowed)
			(footprints allowed)
		)
		(placement
			(enabled no)
			(sheetname "")
		)
		(fill
			(thermal_gap 0.5)
			(thermal_bridge_width 0.5)
			(island_removal_mode 0)
		)
		(polygon
			(pts
				(arc
					(start 123.358148 -55.000144)
					(mid 123.043247 -54.644624)
					(end 122.652282 -54.914292)
				)
				(arc
					(start 122.652282 -55.240682)
					(mid 122.660345 -55.281215)
					(end 122.68327 -55.315612)
				)
				(arc
					(start 122.68327 -55.315612)
					(mid 122.719061 -55.339464)
					(end 122.761248 -55.34787)
				)
				(arc
					(start 122.911108 -55.34787)
					(mid 122.933559 -55.338571)
					(end 122.942858 -55.31612)
				)
				(arc
					(start 122.942858 -55.234586)
					(mid 123.000008 -54.758837)
					(end 123.057158 -55.234586)
				)
				(xy 123.057158 -55.339742)
				(arc
					(start 123.054872 -55.342028)
					(mid 123.014402 -55.419414)
					(end 122.937016 -55.459884)
				)
				(xy 122.93473 -55.46217) (xy 122.737626 -55.46217)
				(arc
					(start 122.736102 -55.460646)
					(mid 122.68715 -55.449546)
					(end 122.641868 -55.42788)
				)
				(arc
					(start 122.641868 -55.513732)
					(mid 122.70005 -55.532094)
					(end 122.76074 -55.53837)
				)
				(xy 122.93473 -55.53837)
				(arc
					(start 122.937016 -55.540656)
					(mid 123.014402 -55.581126)
					(end 123.054872 -55.658512)
				)
				(xy 123.057158 -55.660798)
				(arc
					(start 123.057158 -55.7657)
					(mid 123.000008 -56.241449)
					(end 122.942858 -55.7657)
				)
				(arc
					(start 122.942858 -55.68442)
					(mid 122.933559 -55.661969)
					(end 122.911108 -55.65267)
				)
				(xy 122.737626 -55.65267)
				(arc
					(start 122.736864 -55.651908)
					(mid 122.688876 -55.646299)
					(end 122.641868 -55.635144)
				)
				(arc
					(start 122.641868 -55.999888)
					(mid 122.999881 -56.358282)
					(end 123.358148 -56.000142)
				)
			)
		)
	)
	(zone
		(layer "B.Cu")
		(hatch none 0.5)
		(connect_pads
			(clearance 0)
		)
		(min_thickness 0.25)
		(keepout
			(tracks not_allowed)
			(vias allowed)
			(pads allowed)
			(copperpour not_allowed)
			(footprints allowed)
		)
		(placement
			(enabled no)
			(sheetname "")
		)
		(fill
			(thermal_gap 0.5)
			(thermal_bridge_width 0.5)
			(island_removal_mode 0)
		)
		(polygon
			(pts
				(arc
					(start 133.731 -44.3103)
					(mid 133.702602 -44.303596)
					(end 133.6802 -44.2849)
				)
				(arc
					(start 133.6802 -44.5135)
					(mid 133.702602 -44.494804)
					(end 133.731 -44.4881)
				)
				(arc
					(start 133.9342 -44.4881)
					(mid 133.962598 -44.494804)
					(end 133.985 -44.5135)
				)
				(arc
					(start 133.985 -44.2849)
					(mid 133.962598 -44.303596)
					(end 133.9342 -44.3103)
				)
			)
		)
	)
	(zone
		(net "P12V_SYBY_VDD_U6")
		(layer "B.Cu")
		(hatch none 0.5)
		(connect_pads
			(clearance 0.5)
		)
		(min_thickness 0.25)
		(fill yes
			(thermal_gap 0.5)
			(thermal_bridge_width 0.5)
			(island_removal_mode 0)
		)
		(polygon
			(pts
				(xy 161.5694 -91.6432) (xy 161.4297 -91.7829) (xy 161.4297 -93.3323) (xy 161.5694 -93.472) (xy 163.9824 -93.472)
				(xy 164.0586 -93.3958) (xy 164.0586 -91.694) (xy 164.0078 -91.6432)
			)
		)
	)
	(zone
		(layer "B.Cu")
		(hatch none 0.5)
		(connect_pads
			(clearance 0)
		)
		(min_thickness 0.25)
		(keepout
			(tracks not_allowed)
			(vias allowed)
			(pads allowed)
			(copperpour not_allowed)
			(footprints allowed)
		)
		(placement
			(enabled no)
			(sheetname "")
		)
		(fill
			(thermal_gap 0.5)
			(thermal_bridge_width 0.5)
			(island_removal_mode 0)
		)
		(polygon
			(pts
				(arc
					(start 126.000256 -69.641974)
					(mid 125.641862 -69.999987)
					(end 126.000002 -70.358254)
				)
				(arc
					(start 127 -70.358254)
					(mid 127.355781 -70.041151)
					(end 127.081534 -69.651372)
				)
				(arc
					(start 126.750826 -69.651372)
					(mid 126.681139 -69.680237)
					(end 126.652274 -69.749924)
				)
				(arc
					(start 126.652274 -69.900038)
					(mid 126.664847 -69.930391)
					(end 126.6952 -69.942964)
				)
				(arc
					(start 126.765558 -69.942964)
					(mid 127.241307 -70.000114)
					(end 126.765558 -70.057264)
				)
				(xy 126.671578 -70.057264)
				(arc
					(start 126.669292 -70.055232)
					(mid 126.583943 -70.011295)
					(end 126.540006 -69.925946)
				)
				(xy 126.537974 -69.92366) (xy 126.537974 -69.726302)
				(arc
					(start 126.539498 -69.724778)
					(mid 126.549164 -69.681923)
					(end 126.567438 -69.641974)
				)
				(arc
					(start 126.482602 -69.641974)
					(mid 126.467016 -69.69495)
					(end 126.461774 -69.749924)
				)
				(xy 126.461774 -69.923914)
				(arc
					(start 126.459742 -69.9262)
					(mid 126.415882 -70.011372)
					(end 126.33071 -70.055232)
				)
				(xy 126.328424 -70.057264)
				(arc
					(start 126.234444 -70.057264)
					(mid 125.758695 -70.000114)
					(end 126.234444 -69.942964)
				)
				(arc
					(start 126.304802 -69.942964)
					(mid 126.334976 -69.930466)
					(end 126.347474 -69.900292)
				)
				(xy 126.347474 -69.726302)
				(arc
					(start 126.348236 -69.72554)
					(mid 126.353024 -69.68339)
					(end 126.362206 -69.641974)
				)
			)
		)
	)
	(zone
		(layer "B.Cu")
		(hatch none 0.5)
		(connect_pads
			(clearance 0)
		)
		(min_thickness 0.25)
		(keepout
			(tracks allowed)
			(vias allowed)
			(pads allowed)
			(copperpour allowed)
			(footprints allowed)
		)
		(placement
			(enabled no)
			(sheetname "")
		)
		(fill
			(thermal_gap 0.5)
			(thermal_bridge_width 0.5)
			(island_removal_mode 0)
		)
		(polygon
			(pts
				(xy 73.2536 -95.9104) (xy 73.2536 -93.853) (xy 87.5792 -93.853) (xy 87.5792 -95.9104)
			)
		)
	)
	(zone
		(layer "B.Cu")
		(hatch none 0.5)
		(connect_pads
			(clearance 0)
		)
		(min_thickness 0.25)
		(keepout
			(tracks not_allowed)
			(vias allowed)
			(pads allowed)
			(copperpour not_allowed)
			(footprints allowed)
		)
		(placement
			(enabled no)
			(sheetname "")
		)
		(fill
			(thermal_gap 0.5)
			(thermal_bridge_width 0.5)
			(island_removal_mode 0)
		)
		(polygon
			(pts
				(arc
					(start 193.161158 -9.800082)
					(mid 192.599818 -9.238742)
					(end 192.038478 -9.800082)
				)
				(xy 192.038478 -10.26414) (xy 192.089278 -10.259568) (xy 192.09004 -10.258552) (xy 192.112646 -10.258552)
				(xy 192.1256 -10.258552) (xy 192.130172 -10.258552) (xy 192.419224 -10.258552)
				(arc
					(start 192.423796 -10.258552)
					(mid 192.481825 -10.237399)
					(end 192.512696 -10.183876)
				)
				(arc
					(start 192.512696 -10.183876)
					(mid 192.601119 -9.406469)
					(end 192.685416 -10.184384)
				)
				(xy 192.685416 -10.203942)
				(arc
					(start 192.682876 -10.206482)
					(mid 192.608964 -10.35355)
					(end 192.461896 -10.427462)
				)
				(xy 192.459356 -10.430256) (xy 192.431924 -10.430256) (xy 192.423796 -10.430256) (xy 192.419224 -10.430256)
				(xy 192.130172 -10.430256)
				(arc
					(start 192.1256 -10.430256)
					(mid 192.081871 -10.432144)
					(end 192.038478 -10.437876)
				)
				(arc
					(start 192.038478 -10.580624)
					(mid 192.063211 -10.575291)
					(end 192.088262 -10.571734)
				)
				(xy 192.09004 -10.569956) (xy 192.116202 -10.569956) (xy 192.1256 -10.569702) (xy 192.130172 -10.569956)
				(xy 192.41897 -10.569956) (xy 192.423542 -10.569702) (xy 192.43167 -10.569956) (xy 192.459102 -10.569956)
				(arc
					(start 192.461642 -10.572496)
					(mid 192.608887 -10.646485)
					(end 192.682876 -10.79373)
				)
				(xy 192.685416 -10.79627)
				(arc
					(start 192.685416 -10.815828)
					(mid 192.601119 -11.593793)
					(end 192.512696 -10.816336)
				)
				(arc
					(start 192.512696 -10.816336)
					(mid 192.481793 -10.762582)
					(end 192.423542 -10.741406)
				)
				(xy 192.41897 -10.741152) (xy 192.130172 -10.741152)
				(arc
					(start 192.1256 -10.741406)
					(mid 192.080691 -10.74695)
					(end 192.038478 -10.76325)
				)
				(arc
					(start 192.038478 -11.199876)
					(mid 192.599691 -11.76147)
					(end 193.161158 -11.20013)
				)
			)
		)
	)
	(zone
		(net "P1V8_C")
		(layer "B.Cu")
		(hatch none 0.5)
		(connect_pads
			(clearance 0.5)
		)
		(min_thickness 0.25)
		(fill yes
			(thermal_gap 0.5)
			(thermal_bridge_width 0.5)
			(island_removal_mode 0)
		)
		(polygon
			(pts
				(xy 158.216346 -52.222654) (xy 158.115 -52.324) (xy 158.115 -54.214776) (xy 158.29534 -54.395116)
				(xy 164.171884 -54.395116) (xy 165.5826 -52.9844) (xy 167.8686 -52.9844) (xy 168.021 -52.832) (xy 168.021 -52.324)
				(xy 167.919654 -52.222654)
			)
		)
		(polygon
			(pts
				(xy 165.4302 -52.6796) (xy 165.227 -52.6796) (xy 165.227 -52.8828) (xy 165.4302 -52.8828)
			)
		)
		(polygon
			(pts
				(xy 164.973 -52.6796) (xy 164.7698 -52.6796) (xy 164.7698 -52.8828) (xy 164.973 -52.8828)
			)
		)
		(polygon
			(pts
				(xy 164.4142 -52.6796) (xy 164.211 -52.6796) (xy 164.211 -52.8828) (xy 164.4142 -52.8828)
			)
		)
		(polygon
			(pts
				(xy 163.957 -52.6796) (xy 163.7538 -52.6796) (xy 163.7538 -52.8828) (xy 163.957 -52.8828)
			)
		)
		(polygon
			(pts
				(xy 163.3982 -52.6796) (xy 163.195 -52.6796) (xy 163.195 -52.8828) (xy 163.3982 -52.8828)
			)
		)
		(polygon
			(pts
				(xy 162.941 -52.6796) (xy 162.7378 -52.6796) (xy 162.7378 -52.8828) (xy 162.941 -52.8828)
			)
		)
		(polygon
			(pts
				(xy 162.3822 -52.6796) (xy 162.179 -52.6796) (xy 162.179 -52.8828) (xy 162.3822 -52.8828)
			)
		)
		(polygon
			(pts
				(xy 161.925 -52.6796) (xy 161.7218 -52.6796) (xy 161.7218 -52.8828) (xy 161.925 -52.8828)
			)
		)
		(polygon
			(pts
				(xy 161.3662 -52.6796) (xy 161.163 -52.6796) (xy 161.163 -52.8828) (xy 161.3662 -52.8828)
			)
		)
		(polygon
			(pts
				(xy 160.909 -52.6796) (xy 160.7058 -52.6796) (xy 160.7058 -52.8828) (xy 160.909 -52.8828)
			)
		)
		(polygon
			(pts
				(xy 160.3502 -52.6796) (xy 160.147 -52.6796) (xy 160.147 -52.8828) (xy 160.3502 -52.8828)
			)
		)
		(polygon
			(pts
				(xy 159.893 -52.6796) (xy 159.6898 -52.6796) (xy 159.6898 -52.8828) (xy 159.893 -52.8828)
			)
		)
		(polygon
			(pts
				(xy 159.3342 -52.6796) (xy 159.131 -52.6796) (xy 159.131 -52.8828) (xy 159.3342 -52.8828)
			)
		)
		(polygon
			(pts
				(xy 158.877 -52.6796) (xy 158.6738 -52.6796) (xy 158.6738 -52.8828) (xy 158.877 -52.8828)
			)
		)
	)
	(zone
		(layer "B.Cu")
		(hatch none 0.5)
		(connect_pads
			(clearance 0)
		)
		(min_thickness 0.25)
		(keepout
			(tracks not_allowed)
			(vias allowed)
			(pads allowed)
			(copperpour not_allowed)
			(footprints allowed)
		)
		(placement
			(enabled no)
			(sheetname "")
		)
		(fill
			(thermal_gap 0.5)
			(thermal_bridge_width 0.5)
			(island_removal_mode 0)
		)
		(polygon
			(pts
				(arc
					(start 122.56135 -3.800094)
					(mid 122.00001 -3.238754)
					(end 121.43867 -3.800094)
				)
				(arc
					(start 121.43867 -4.228592)
					(mid 121.471622 -4.224901)
					(end 121.50471 -4.22275)
				)
				(xy 121.505472 -4.221988)
				(arc
					(start 121.880884 -4.221988)
					(mid 121.897797 -4.218624)
					(end 121.912126 -4.209034)
				)
				(arc
					(start 121.912126 -4.209034)
					(mid 121.919892 -4.198635)
					(end 121.924318 -4.186428)
				)
				(arc
					(start 121.924318 -4.186428)
					(mid 122.000912 -3.406367)
					(end 122.07494 -4.186682)
				)
				(xy 122.07494 -4.20878)
				(arc
					(start 122.071892 -4.211828)
					(mid 122.052961 -4.267359)
					(end 122.018298 -4.314698)
				)
				(arc
					(start 122.018298 -4.314698)
					(mid 121.970782 -4.349728)
					(end 121.91492 -4.3688)
				)
				(xy 121.911872 -4.371848)
				(arc
					(start 121.53646 -4.371848)
					(mid 121.487376 -4.37403)
					(end 121.43867 -4.380484)
				)
				(arc
					(start 121.43867 -4.64439)
					(mid 121.470795 -4.635509)
					(end 121.503694 -4.630166)
				)
				(xy 121.505472 -4.628388) (xy 121.911872 -4.628388)
				(arc
					(start 121.91492 -4.631436)
					(mid 121.970769 -4.650533)
					(end 122.018298 -4.685538)
				)
				(arc
					(start 122.018298 -4.685538)
					(mid 122.052986 -4.732864)
					(end 122.071892 -4.788408)
				)
				(xy 122.07494 -4.791456)
				(arc
					(start 122.07494 -4.813554)
					(mid 122.000912 -5.593876)
					(end 121.924318 -4.813808)
				)
				(arc
					(start 121.924318 -4.813808)
					(mid 121.91992 -4.801586)
					(end 121.912126 -4.791202)
				)
				(arc
					(start 121.912126 -4.791202)
					(mid 121.897792 -4.781624)
					(end 121.880884 -4.778248)
				)
				(arc
					(start 121.53646 -4.778248)
					(mid 121.484727 -4.786928)
					(end 121.43867 -4.81203)
				)
				(arc
					(start 121.43867 -5.199888)
					(mid 121.999883 -5.761482)
					(end 122.56135 -5.200142)
				)
			)
		)
	)
	(zone
		(net "P1V5_E_OUT")
		(layer "B.Cu")
		(hatch none 0.5)
		(connect_pads
			(clearance 0.5)
		)
		(min_thickness 0.25)
		(fill yes
			(thermal_gap 0.5)
			(thermal_bridge_width 0.5)
			(island_removal_mode 0)
		)
		(polygon
			(pts
				(xy 134.7851 -110.3376) (xy 134.5057 -110.617) (xy 134.5057 -114.5921) (xy 134.7978 -114.8842) (xy 140.5128 -114.8842)
				(xy 140.9954 -114.4016) (xy 140.9954 -110.6424) (xy 140.6906 -110.3376)
			)
		)
	)
	(zone
		(layer "B.Cu")
		(hatch none 0.5)
		(connect_pads
			(clearance 0)
		)
		(min_thickness 0.25)
		(keepout
			(tracks not_allowed)
			(vias allowed)
			(pads allowed)
			(copperpour not_allowed)
			(footprints allowed)
		)
		(placement
			(enabled no)
			(sheetname "")
		)
		(fill
			(thermal_gap 0.5)
			(thermal_bridge_width 0.5)
			(island_removal_mode 0)
		)
		(polygon
			(pts
				(arc
					(start 201.499978 -50.500026)
					(mid 198.499984 -47.500032)
					(end 195.49999 -50.500026)
				)
				(arc
					(start 195.49999 -50.500026)
					(mid 198.499984 -53.50002)
					(end 201.499978 -50.500026)
				)
			)
		)
	)
	(zone
		(net "GND")
		(layer "B.Cu")
		(hatch none 0.5)
		(connect_pads
			(clearance 0.5)
		)
		(min_thickness 0.25)
		(fill yes
			(thermal_gap 0.5)
			(thermal_bridge_width 0.5)
			(island_removal_mode 0)
		)
		(polygon
			(pts
				(xy 203.00442 -45.96384) (xy 202.826874 -46.14164) (xy 202.826874 -46.763178) (xy 202.677776 -46.912276)
				(xy 202.671934 -46.912276) (xy 202.541378 -47.042832) (xy 201.766678 -47.042832) (xy 201.666856 -47.142654)
				(xy 201.666856 -47.676562) (xy 201.760328 -47.770034) (xy 204.500988 -47.770034) (xy 204.820012 -47.45101)
				(xy 204.820012 -46.112684) (xy 204.671168 -45.96384)
			)
		)
		(polygon
			(pts
				(xy 204.1398 -46.46422) (xy 203.9366 -46.46422) (xy 203.9366 -46.66742) (xy 204.1398 -46.66742)
			)
		)
		(polygon
			(pts
				(xy 203.7588 -46.46422) (xy 203.5556 -46.46422) (xy 203.5556 -46.66742) (xy 203.7588 -46.66742)
			)
		)
		(polygon
			(pts
				(xy 203.1492 -46.46422) (xy 202.946 -46.46422) (xy 202.946 -46.66742) (xy 203.1492 -46.66742)
			)
		)
	)
	(zone
		(net "GND")
		(layer "B.Cu")
		(hatch none 0.5)
		(connect_pads
			(clearance 0.5)
		)
		(min_thickness 0.25)
		(fill yes
			(thermal_gap 0.5)
			(thermal_bridge_width 0.5)
			(island_removal_mode 0)
		)
		(polygon
			(pts
				(xy 73.025 -41.275) (xy 72.263 -42.037) (xy 72.263 -46.355) (xy 72.39 -46.482) (xy 76.835 -46.482)
				(xy 76.962 -46.355) (xy 76.962 -41.402) (xy 76.835 -41.275)
			)
		)
		(polygon
			(pts
				(xy 75.9968 -45.3644) (xy 75.7936 -45.3644) (xy 75.7936 -45.5676) (xy 75.9968 -45.5676)
			)
		)
		(polygon
			(pts
				(xy 76.1238 -42.1894) (xy 75.9206 -42.1894) (xy 75.9206 -42.3926) (xy 76.1238 -42.3926)
			)
		)
	)
	(zone
		(net "PCE_VDDH")
		(layer "B.Cu")
		(hatch none 0.5)
		(connect_pads
			(clearance 0.5)
		)
		(min_thickness 0.25)
		(fill yes
			(thermal_gap 0.5)
			(thermal_bridge_width 0.5)
			(island_removal_mode 0)
		)
		(polygon
			(pts
				(xy 194.6402 -26.59507) (xy 194.4116 -26.82367) (xy 194.4116 -29.1084) (xy 194.4878 -29.1846) (xy 195.3006 -29.1846)
				(xy 195.326 -29.1592) (xy 195.326 -28.4226) (xy 195.559934 -28.188666) (xy 199.943466 -28.188666)
				(xy 200.000616 -28.245816) (xy 200.000616 -29.210762) (xy 200.22566 -29.435806) (xy 201.241152 -29.435806)
				(xy 201.401934 -29.275024) (xy 201.401934 -26.677874) (xy 201.31913 -26.59507)
			)
		)
		(polygon
			(pts
				(xy 196.5452 -27.4574) (xy 196.342 -27.4574) (xy 196.342 -27.6606) (xy 196.5452 -27.6606)
			)
		)
		(polygon
			(pts
				(xy 195.834 -27.4574) (xy 195.6308 -27.4574) (xy 195.6308 -27.6606) (xy 195.834 -27.6606)
			)
		)
		(polygon
			(pts
				(xy 200.9394 -27.2288) (xy 200.7362 -27.2288) (xy 200.7362 -27.432) (xy 200.9394 -27.432)
			)
		)
		(polygon
			(pts
				(xy 197.7644 -27.0764) (xy 197.5612 -27.0764) (xy 197.5612 -27.2796) (xy 197.7644 -27.2796)
			)
		)
		(polygon
			(pts
				(xy 196.9008 -27.0764) (xy 196.6976 -27.0764) (xy 196.6976 -27.2796) (xy 196.9008 -27.2796)
			)
		)
	)
	(zone
		(net "GND")
		(layer "B.Cu")
		(hatch none 0.5)
		(connect_pads
			(clearance 0.5)
		)
		(min_thickness 0.25)
		(fill yes
			(thermal_gap 0.5)
			(thermal_bridge_width 0.5)
			(island_removal_mode 0)
		)
		(polygon
			(pts
				(xy 44.1452 -31.5976) (xy 44.0309 -31.7119) (xy 44.0309 -34.582608) (xy 44.610528 -35.162236) (xy 47.12081 -35.162236)
				(xy 47.253906 -35.02914) (xy 47.253906 -34.1376) (xy 47.2186 -34.102294) (xy 47.2186 -31.9151) (xy 46.9011 -31.5976)
			)
		)
	)
	(zone
		(layer "B.Cu")
		(hatch none 0.5)
		(connect_pads
			(clearance 0)
		)
		(min_thickness 0.25)
		(keepout
			(tracks not_allowed)
			(vias allowed)
			(pads allowed)
			(copperpour not_allowed)
			(footprints allowed)
		)
		(placement
			(enabled no)
			(sheetname "")
		)
		(fill
			(thermal_gap 0.5)
			(thermal_bridge_width 0.5)
			(island_removal_mode 0)
		)
		(polygon
			(pts
				(arc
					(start 131.561332 -2.600198)
					(mid 130.999992 -2.038858)
					(end 130.438652 -2.600198)
				)
				(arc
					(start 130.438652 -3.028442)
					(mid 130.471604 -3.024751)
					(end 130.504692 -3.0226)
				)
				(xy 130.505454 -3.021838)
				(arc
					(start 130.880866 -3.021838)
					(mid 130.897779 -3.018474)
					(end 130.912108 -3.008884)
				)
				(arc
					(start 130.912108 -3.008884)
					(mid 130.919705 -2.99858)
					(end 130.924046 -2.986532)
				)
				(arc
					(start 130.924046 -2.986532)
					(mid 131.001018 -2.206422)
					(end 131.074922 -2.986786)
				)
				(xy 131.074922 -3.00863)
				(arc
					(start 131.071874 -3.011678)
					(mid 131.052943 -3.067209)
					(end 131.01828 -3.114548)
				)
				(arc
					(start 131.01828 -3.114548)
					(mid 130.970764 -3.149578)
					(end 130.914902 -3.16865)
				)
				(xy 130.911854 -3.171698)
				(arc
					(start 130.536442 -3.171698)
					(mid 130.487358 -3.17388)
					(end 130.438652 -3.180334)
				)
				(arc
					(start 130.438652 -3.44424)
					(mid 130.470777 -3.435359)
					(end 130.503676 -3.430016)
				)
				(xy 130.505454 -3.428238) (xy 130.911854 -3.428238)
				(arc
					(start 130.914902 -3.431286)
					(mid 130.970751 -3.450383)
					(end 131.01828 -3.485388)
				)
				(arc
					(start 131.01828 -3.485388)
					(mid 131.052968 -3.532714)
					(end 131.071874 -3.588258)
				)
				(xy 131.074922 -3.591306)
				(arc
					(start 131.074922 -3.613404)
					(mid 131.000894 -4.393726)
					(end 130.9243 -3.613658)
				)
				(arc
					(start 130.9243 -3.613658)
					(mid 130.919902 -3.601436)
					(end 130.912108 -3.591052)
				)
				(arc
					(start 130.912108 -3.591052)
					(mid 130.897774 -3.581474)
					(end 130.880866 -3.578098)
				)
				(arc
					(start 130.536442 -3.578098)
					(mid 130.484709 -3.586778)
					(end 130.438652 -3.61188)
				)
				(arc
					(start 130.438652 -3.999738)
					(mid 130.999865 -4.561332)
					(end 131.561332 -3.999992)
				)
			)
		)
	)
	(zone
		(net "GND")
		(layer "B.Cu")
		(hatch none 0.5)
		(connect_pads
			(clearance 0.5)
		)
		(min_thickness 0.25)
		(fill yes
			(thermal_gap 0.5)
			(thermal_bridge_width 0.5)
			(island_removal_mode 0)
		)
		(polygon
			(pts
				(xy 73.279 -51.562) (xy 72.517 -52.324) (xy 72.517 -56.896) (xy 72.771 -57.15) (xy 76.962 -57.15)
				(xy 77.089 -57.023) (xy 77.089 -51.943) (xy 76.708 -51.562)
			)
		)
		(polygon
			(pts
				(xy 76.1238 -56.1594) (xy 75.9206 -56.1594) (xy 75.9206 -56.3626) (xy 76.1238 -56.3626)
			)
		)
		(polygon
			(pts
				(xy 76.8604 -52.3494) (xy 76.6572 -52.3494) (xy 76.6572 -52.5526) (xy 76.8604 -52.5526)
			)
		)
		(polygon
			(pts
				(xy 75.9968 -52.3494) (xy 75.7936 -52.3494) (xy 75.7936 -52.5526) (xy 75.9968 -52.5526)
			)
		)
	)
	(zone
		(layer "B.Cu")
		(hatch none 0.5)
		(connect_pads
			(clearance 0)
		)
		(min_thickness 0.25)
		(keepout
			(tracks not_allowed)
			(vias allowed)
			(pads allowed)
			(copperpour not_allowed)
			(footprints allowed)
		)
		(placement
			(enabled no)
			(sheetname "")
		)
		(fill
			(thermal_gap 0.5)
			(thermal_bridge_width 0.5)
			(island_removal_mode 0)
		)
		(polygon
			(pts
				(arc
					(start 122.35815 -55.000144)
					(mid 122.044686 -54.644801)
					(end 121.653046 -54.911498)
				)
				(arc
					(start 121.653046 -55.24246)
					(mid 121.660915 -55.282021)
					(end 121.683272 -55.315612)
				)
				(arc
					(start 121.683272 -55.315612)
					(mid 121.719063 -55.339464)
					(end 121.76125 -55.34787)
				)
				(arc
					(start 121.91111 -55.34787)
					(mid 121.933561 -55.338571)
					(end 121.94286 -55.31612)
				)
				(arc
					(start 121.94286 -55.234586)
					(mid 122.00001 -54.758837)
					(end 122.05716 -55.234586)
				)
				(xy 122.05716 -55.339742)
				(arc
					(start 122.054874 -55.342028)
					(mid 122.014404 -55.419414)
					(end 121.937018 -55.459884)
				)
				(xy 121.934732 -55.46217) (xy 121.737628 -55.46217)
				(arc
					(start 121.736104 -55.460646)
					(mid 121.687152 -55.449546)
					(end 121.64187 -55.42788)
				)
				(arc
					(start 121.64187 -55.513732)
					(mid 121.700052 -55.532094)
					(end 121.760742 -55.53837)
				)
				(xy 121.934732 -55.53837)
				(arc
					(start 121.937018 -55.540656)
					(mid 122.014404 -55.581126)
					(end 122.054874 -55.658512)
				)
				(xy 122.05716 -55.660798)
				(arc
					(start 122.05716 -55.7657)
					(mid 122.00001 -56.241449)
					(end 121.94286 -55.7657)
				)
				(arc
					(start 121.94286 -55.68442)
					(mid 121.933561 -55.661969)
					(end 121.91111 -55.65267)
				)
				(xy 121.737628 -55.65267)
				(arc
					(start 121.736866 -55.651908)
					(mid 121.688878 -55.646299)
					(end 121.64187 -55.635144)
				)
				(arc
					(start 121.64187 -55.999888)
					(mid 121.999883 -56.358282)
					(end 122.35815 -56.000142)
				)
			)
		)
	)
	(zone
		(layer "B.Cu")
		(hatch none 0.5)
		(connect_pads
			(clearance 0)
		)
		(min_thickness 0.25)
		(keepout
			(tracks not_allowed)
			(vias allowed)
			(pads allowed)
			(copperpour not_allowed)
			(footprints allowed)
		)
		(placement
			(enabled no)
			(sheetname "")
		)
		(fill
			(thermal_gap 0.5)
			(thermal_bridge_width 0.5)
			(island_removal_mode 0)
		)
		(polygon
			(pts
				(arc
					(start 95.561404 -2.600198)
					(mid 95.000064 -2.038858)
					(end 94.438724 -2.600198)
				)
				(arc
					(start 94.438724 -3.028442)
					(mid 94.471676 -3.024751)
					(end 94.504764 -3.0226)
				)
				(xy 94.505526 -3.021838)
				(arc
					(start 94.880938 -3.021838)
					(mid 94.897851 -3.018474)
					(end 94.91218 -3.008884)
				)
				(arc
					(start 94.91218 -3.008884)
					(mid 94.919777 -2.99858)
					(end 94.924118 -2.986532)
				)
				(arc
					(start 94.924118 -2.986532)
					(mid 95.00109 -2.206422)
					(end 95.074994 -2.986786)
				)
				(xy 95.074994 -3.00863)
				(arc
					(start 95.071946 -3.011678)
					(mid 95.053015 -3.067209)
					(end 95.018352 -3.114548)
				)
				(arc
					(start 95.018352 -3.114548)
					(mid 94.970836 -3.149578)
					(end 94.914974 -3.16865)
				)
				(xy 94.911926 -3.171698)
				(arc
					(start 94.536514 -3.171698)
					(mid 94.48743 -3.17388)
					(end 94.438724 -3.180334)
				)
				(arc
					(start 94.438724 -3.44424)
					(mid 94.470849 -3.435359)
					(end 94.503748 -3.430016)
				)
				(xy 94.505526 -3.428238) (xy 94.911926 -3.428238)
				(arc
					(start 94.914974 -3.431286)
					(mid 94.970823 -3.450383)
					(end 95.018352 -3.485388)
				)
				(arc
					(start 95.018352 -3.485388)
					(mid 95.05304 -3.532714)
					(end 95.071946 -3.588258)
				)
				(xy 95.074994 -3.591306)
				(arc
					(start 95.074994 -3.613404)
					(mid 95.000966 -4.393726)
					(end 94.924372 -3.613658)
				)
				(arc
					(start 94.924372 -3.613658)
					(mid 94.919974 -3.601436)
					(end 94.91218 -3.591052)
				)
				(arc
					(start 94.91218 -3.591052)
					(mid 94.897846 -3.581474)
					(end 94.880938 -3.578098)
				)
				(arc
					(start 94.536514 -3.578098)
					(mid 94.484781 -3.586778)
					(end 94.438724 -3.61188)
				)
				(arc
					(start 94.438724 -3.999738)
					(mid 94.999937 -4.561332)
					(end 95.561404 -3.999992)
				)
			)
		)
	)
	(zone
		(layer "B.Cu")
		(hatch none 0.5)
		(connect_pads
			(clearance 0)
		)
		(min_thickness 0.25)
		(keepout
			(tracks not_allowed)
			(vias allowed)
			(pads allowed)
			(copperpour not_allowed)
			(footprints allowed)
		)
		(placement
			(enabled no)
			(sheetname "")
		)
		(fill
			(thermal_gap 0.5)
			(thermal_bridge_width 0.5)
			(island_removal_mode 0)
		)
		(polygon
			(pts
				(arc
					(start 126.161546 -3.800094)
					(mid 125.600206 -3.238754)
					(end 125.038866 -3.800094)
				)
				(arc
					(start 125.038866 -4.228592)
					(mid 125.071818 -4.224901)
					(end 125.104906 -4.22275)
				)
				(xy 125.105668 -4.221988)
				(arc
					(start 125.48108 -4.221988)
					(mid 125.497993 -4.218624)
					(end 125.512322 -4.209034)
				)
				(arc
					(start 125.512322 -4.209034)
					(mid 125.520088 -4.198635)
					(end 125.524514 -4.186428)
				)
				(arc
					(start 125.524514 -4.186428)
					(mid 125.601108 -3.406367)
					(end 125.675136 -4.186682)
				)
				(xy 125.675136 -4.20878)
				(arc
					(start 125.672088 -4.211828)
					(mid 125.653157 -4.267359)
					(end 125.618494 -4.314698)
				)
				(arc
					(start 125.618494 -4.314698)
					(mid 125.570978 -4.349728)
					(end 125.515116 -4.3688)
				)
				(xy 125.512068 -4.371848)
				(arc
					(start 125.136656 -4.371848)
					(mid 125.087572 -4.37403)
					(end 125.038866 -4.380484)
				)
				(arc
					(start 125.038866 -4.64439)
					(mid 125.070991 -4.635509)
					(end 125.10389 -4.630166)
				)
				(xy 125.105668 -4.628388) (xy 125.512068 -4.628388)
				(arc
					(start 125.515116 -4.631436)
					(mid 125.570965 -4.650533)
					(end 125.618494 -4.685538)
				)
				(arc
					(start 125.618494 -4.685538)
					(mid 125.653182 -4.732864)
					(end 125.672088 -4.788408)
				)
				(xy 125.675136 -4.791456)
				(arc
					(start 125.675136 -4.813554)
					(mid 125.601108 -5.593876)
					(end 125.524514 -4.813808)
				)
				(arc
					(start 125.524514 -4.813808)
					(mid 125.520116 -4.801586)
					(end 125.512322 -4.791202)
				)
				(arc
					(start 125.512322 -4.791202)
					(mid 125.497988 -4.781624)
					(end 125.48108 -4.778248)
				)
				(arc
					(start 125.136656 -4.778248)
					(mid 125.084923 -4.786928)
					(end 125.038866 -4.81203)
				)
				(arc
					(start 125.038866 -5.199888)
					(mid 125.600079 -5.761482)
					(end 126.161546 -5.200142)
				)
			)
		)
	)
	(zone
		(layer "B.Cu")
		(hatch none 0.5)
		(connect_pads
			(clearance 0)
		)
		(min_thickness 0.25)
		(keepout
			(tracks not_allowed)
			(vias allowed)
			(pads allowed)
			(copperpour not_allowed)
			(footprints allowed)
		)
		(placement
			(enabled no)
			(sheetname "")
		)
		(fill
			(thermal_gap 0.5)
			(thermal_bridge_width 0.5)
			(island_removal_mode 0)
		)
		(polygon
			(pts
				(arc
					(start 180.561234 -10.999978)
					(mid 179.999894 -10.438638)
					(end 179.438554 -10.999978)
				)
				(xy 179.438554 -11.458448) (xy 179.8193 -11.458448)
				(arc
					(start 179.823872 -11.458448)
					(mid 179.881901 -11.437295)
					(end 179.912772 -11.383772)
				)
				(arc
					(start 179.912772 -11.383772)
					(mid 180.001195 -10.606365)
					(end 180.085492 -11.38428)
				)
				(xy 180.085492 -11.403838)
				(arc
					(start 180.082952 -11.406378)
					(mid 180.00904 -11.553446)
					(end 179.861972 -11.627358)
				)
				(xy 179.859432 -11.630152) (xy 179.832 -11.630152) (xy 179.823872 -11.630152) (xy 179.8193 -11.630152)
				(xy 179.438554 -11.630152) (xy 179.438554 -11.769852) (xy 179.819046 -11.769852) (xy 179.823618 -11.769598)
				(xy 179.831746 -11.769852) (xy 179.859178 -11.769852)
				(arc
					(start 179.861718 -11.772392)
					(mid 180.008963 -11.846381)
					(end 180.082952 -11.993626)
				)
				(xy 180.085492 -11.996166)
				(arc
					(start 180.085492 -12.015724)
					(mid 180.001195 -12.793689)
					(end 179.912772 -12.016232)
				)
				(arc
					(start 179.912772 -12.016232)
					(mid 179.881869 -11.962478)
					(end 179.823618 -11.941302)
				)
				(xy 179.819046 -11.941048) (xy 179.438554 -11.941048)
				(arc
					(start 179.438554 -12.399772)
					(mid 179.999767 -12.961366)
					(end 180.561234 -12.400026)
				)
			)
		)
	)
	(zone
		(layer "B.Cu")
		(hatch none 0.5)
		(connect_pads
			(clearance 0)
		)
		(min_thickness 0.25)
		(keepout
			(tracks not_allowed)
			(vias allowed)
			(pads allowed)
			(copperpour not_allowed)
			(footprints allowed)
		)
		(placement
			(enabled no)
			(sheetname "")
		)
		(fill
			(thermal_gap 0.5)
			(thermal_bridge_width 0.5)
			(island_removal_mode 0)
		)
		(polygon
			(pts
				(arc
					(start 139.750038 -134.999984)
					(mid 134.999984 -130.24993)
					(end 130.24993 -134.999984)
				)
				(arc
					(start 130.24993 -134.999984)
					(mid 134.999984 -139.750038)
					(end 139.750038 -134.999984)
				)
			)
		)
	)
	(zone
		(layer "B.Cu")
		(hatch none 0.5)
		(connect_pads
			(clearance 0)
		)
		(min_thickness 0.25)
		(keepout
			(tracks allowed)
			(vias allowed)
			(pads allowed)
			(copperpour allowed)
			(footprints not_allowed)
		)
		(placement
			(enabled no)
			(sheetname "")
		)
		(fill
			(thermal_gap 0.5)
			(thermal_bridge_width 0.5)
			(island_removal_mode 0)
		)
		(polygon
			(pts
				(arc
					(start 195.49999 -50.500026)
					(mid 198.499984 -53.50002)
					(end 201.499978 -50.500026)
				)
				(arc
					(start 201.499978 -50.500026)
					(mid 198.499984 -47.500032)
					(end 195.49999 -50.500026)
				)
			)
		)
	)
	(zone
		(net "GND")
		(layer "B.Cu")
		(hatch none 0.5)
		(connect_pads
			(clearance 0.5)
		)
		(min_thickness 0.25)
		(fill yes
			(thermal_gap 0.5)
			(thermal_bridge_width 0.5)
			(island_removal_mode 0)
		)
		(polygon
			(pts
				(xy 173.0883 -36.5506) (xy 173.0121 -36.6268) (xy 173.0121 -44.1452) (xy 173.1391 -44.2722) (xy 173.5709 -44.2722)
				(xy 173.7106 -44.1325) (xy 173.7106 -36.6268) (xy 173.6344 -36.5506)
			)
		)
		(polygon
			(pts
				(xy 173.3931 -43.54322) (xy 173.1899 -43.54322) (xy 173.1899 -43.74642) (xy 173.3931 -43.74642)
			)
		)
		(polygon
			(pts
				(xy 173.3931 -42.98442) (xy 173.1899 -42.98442) (xy 173.1899 -43.39082) (xy 173.3931 -43.39082)
			)
		)
		(polygon
			(pts
				(xy 173.3931 -42.62882) (xy 173.1899 -42.62882) (xy 173.1899 -42.83202) (xy 173.3931 -42.83202)
			)
		)
		(polygon
			(pts
				(xy 173.4058 -41.94302) (xy 173.2026 -41.94302) (xy 173.2026 -42.14622) (xy 173.4058 -42.14622)
			)
		)
		(polygon
			(pts
				(xy 173.4058 -41.38422) (xy 173.2026 -41.38422) (xy 173.2026 -41.79062) (xy 173.4058 -41.79062)
			)
		)
		(polygon
			(pts
				(xy 173.4058 -41.02862) (xy 173.2026 -41.02862) (xy 173.2026 -41.23182) (xy 173.4058 -41.23182)
			)
		)
	)
	(zone
		(net "GND")
		(layer "B.Cu")
		(hatch none 0.5)
		(connect_pads
			(clearance 0.5)
		)
		(min_thickness 0.25)
		(fill yes
			(thermal_gap 0.5)
			(thermal_bridge_width 0.5)
			(island_removal_mode 0)
		)
		(polygon
			(pts
				(xy 184.023 -83.058) (xy 183.8198 -83.2612) (xy 183.8198 -90.4748) (xy 184.023 -90.678) (xy 187.3758 -90.678)
				(xy 187.6044 -90.4494) (xy 187.6044 -83.3628) (xy 187.2996 -83.058)
			)
		)
		(polygon
			(pts
				(xy 184.913016 -86.318852) (xy 184.709816 -86.318852) (xy 184.709816 -86.522052) (xy 184.913016 -86.522052)
			)
		)
		(polygon
			(pts
				(xy 184.913016 -85.455252) (xy 184.709816 -85.455252) (xy 184.709816 -85.658452) (xy 184.913016 -85.658452)
			)
		)
		(polygon
			(pts
				(xy 184.481216 -84.896452) (xy 184.278016 -84.896452) (xy 184.278016 -85.099652) (xy 184.481216 -85.099652)
			)
		)
		(polygon
			(pts
				(xy 184.481216 -84.337652) (xy 184.278016 -84.337652) (xy 184.278016 -84.540852) (xy 184.481216 -84.540852)
			)
		)
		(polygon
			(pts
				(xy 184.532016 -83.931252) (xy 184.328816 -83.931252) (xy 184.328816 -84.134452) (xy 184.532016 -84.134452)
			)
		)
		(polygon
			(pts
				(xy 184.532016 -83.321652) (xy 184.328816 -83.321652) (xy 184.328816 -83.524852) (xy 184.532016 -83.524852)
			)
		)
	)
	(zone
		(layer "B.Cu")
		(hatch none 0.5)
		(connect_pads
			(clearance 0)
		)
		(min_thickness 0.25)
		(keepout
			(tracks not_allowed)
			(vias allowed)
			(pads allowed)
			(copperpour not_allowed)
			(footprints allowed)
		)
		(placement
			(enabled no)
			(sheetname "")
		)
		(fill
			(thermal_gap 0.5)
			(thermal_bridge_width 0.5)
			(island_removal_mode 0)
		)
		(polygon
			(pts
				(arc
					(start 126.000256 -65.641982)
					(mid 125.641862 -65.999995)
					(end 126.000002 -66.358262)
				)
				(arc
					(start 127 -66.358262)
					(mid 127.355075 -66.046875)
					(end 127.09271 -65.654174)
				)
				(arc
					(start 126.748032 -65.654174)
					(mid 126.680321 -65.682221)
					(end 126.652274 -65.749932)
				)
				(arc
					(start 126.652274 -65.900046)
					(mid 126.664847 -65.930399)
					(end 126.6952 -65.942972)
				)
				(arc
					(start 126.765558 -65.942972)
					(mid 127.241307 -66.000122)
					(end 126.765558 -66.057272)
				)
				(xy 126.671578 -66.057272)
				(arc
					(start 126.669292 -66.05524)
					(mid 126.583943 -66.011303)
					(end 126.540006 -65.925954)
				)
				(xy 126.537974 -65.923668) (xy 126.537974 -65.72631)
				(arc
					(start 126.539498 -65.724786)
					(mid 126.549369 -65.681889)
					(end 126.567946 -65.641982)
				)
				(arc
					(start 126.482856 -65.641982)
					(mid 126.467058 -65.694933)
					(end 126.461774 -65.749932)
				)
				(xy 126.461774 -65.923922)
				(arc
					(start 126.459742 -65.926208)
					(mid 126.415882 -66.01138)
					(end 126.33071 -66.05524)
				)
				(xy 126.328424 -66.057272)
				(arc
					(start 126.234444 -66.057272)
					(mid 125.758695 -66.000122)
					(end 126.234444 -65.942972)
				)
				(arc
					(start 126.304802 -65.942972)
					(mid 126.334976 -65.930474)
					(end 126.347474 -65.9003)
				)
				(xy 126.347474 -65.72631)
				(arc
					(start 126.348236 -65.725548)
					(mid 126.353004 -65.683394)
					(end 126.362206 -65.641982)
				)
			)
		)
	)
	(zone
		(layer "B.Cu")
		(hatch none 0.5)
		(connect_pads
			(clearance 0)
		)
		(min_thickness 0.25)
		(keepout
			(tracks not_allowed)
			(vias allowed)
			(pads allowed)
			(copperpour not_allowed)
			(footprints allowed)
		)
		(placement
			(enabled no)
			(sheetname "")
		)
		(fill
			(thermal_gap 0.5)
			(thermal_bridge_width 0.5)
			(island_removal_mode 0)
		)
		(polygon
			(pts
				(arc
					(start 126.000256 -74.641964)
					(mid 125.641862 -74.999977)
					(end 126.000002 -75.358244)
				)
				(arc
					(start 126.36881 -75.358244)
					(mid 126.354942 -75.304436)
					(end 126.348236 -75.249278)
				)
				(xy 126.347474 -75.248516)
				(arc
					(start 126.347474 -75.089004)
					(mid 126.338175 -75.066553)
					(end 126.315724 -75.057254)
				)
				(arc
					(start 126.234444 -75.057254)
					(mid 125.758695 -75.000104)
					(end 126.234444 -74.942954)
				)
				(xy 126.339346 -74.942954)
				(arc
					(start 126.341632 -74.94524)
					(mid 126.419018 -74.98571)
					(end 126.459488 -75.063096)
				)
				(xy 126.461774 -75.065382)
				(arc
					(start 126.461774 -75.224894)
					(mid 126.46937 -75.293227)
					(end 126.491746 -75.358244)
				)
				(arc
					(start 126.579376 -75.358244)
					(mid 126.552517 -75.306526)
					(end 126.539244 -75.249786)
				)
				(xy 126.537974 -75.248516) (xy 126.537974 -75.065382)
				(arc
					(start 126.54026 -75.063096)
					(mid 126.58073 -74.98571)
					(end 126.658116 -74.94524)
				)
				(xy 126.660402 -74.942954)
				(arc
					(start 126.765558 -74.942954)
					(mid 127.241307 -75.000104)
					(end 126.765558 -75.057254)
				)
				(arc
					(start 126.684024 -75.057254)
					(mid 126.661573 -75.066553)
					(end 126.652274 -75.089004)
				)
				(arc
					(start 126.652274 -75.224894)
					(mid 126.687612 -75.310206)
					(end 126.772924 -75.345544)
				)
				(arc
					(start 127.094488 -75.345544)
					(mid 127.354943 -74.952436)
					(end 127 -74.641964)
				)
			)
		)
	)
	(zone
		(layer "B.Cu")
		(hatch none 0.5)
		(connect_pads
			(clearance 0)
		)
		(min_thickness 0.25)
		(keepout
			(tracks not_allowed)
			(vias allowed)
			(pads allowed)
			(copperpour not_allowed)
			(footprints allowed)
		)
		(placement
			(enabled no)
			(sheetname "")
		)
		(fill
			(thermal_gap 0.5)
			(thermal_bridge_width 0.5)
			(island_removal_mode 0)
		)
		(polygon
			(pts
				(arc
					(start 142.361412 -2.600198)
					(mid 141.800072 -2.038858)
					(end 141.238732 -2.600198)
				)
				(arc
					(start 141.238732 -3.028442)
					(mid 141.271684 -3.024751)
					(end 141.304772 -3.0226)
				)
				(xy 141.305534 -3.021838)
				(arc
					(start 141.680946 -3.021838)
					(mid 141.697859 -3.018474)
					(end 141.712188 -3.008884)
				)
				(arc
					(start 141.712188 -3.008884)
					(mid 141.719785 -2.99858)
					(end 141.724126 -2.986532)
				)
				(arc
					(start 141.724126 -2.986532)
					(mid 141.801098 -2.206422)
					(end 141.875002 -2.986786)
				)
				(xy 141.875002 -3.00863)
				(arc
					(start 141.871954 -3.011678)
					(mid 141.853023 -3.067209)
					(end 141.81836 -3.114548)
				)
				(arc
					(start 141.81836 -3.114548)
					(mid 141.770844 -3.149578)
					(end 141.714982 -3.16865)
				)
				(xy 141.711934 -3.171698)
				(arc
					(start 141.336522 -3.171698)
					(mid 141.287438 -3.17388)
					(end 141.238732 -3.180334)
				)
				(arc
					(start 141.238732 -3.44424)
					(mid 141.270857 -3.435359)
					(end 141.303756 -3.430016)
				)
				(xy 141.305534 -3.428238) (xy 141.711934 -3.428238)
				(arc
					(start 141.714982 -3.431286)
					(mid 141.770831 -3.450383)
					(end 141.81836 -3.485388)
				)
				(arc
					(start 141.81836 -3.485388)
					(mid 141.853048 -3.532714)
					(end 141.871954 -3.588258)
				)
				(xy 141.875002 -3.591306)
				(arc
					(start 141.875002 -3.613404)
					(mid 141.800974 -4.393726)
					(end 141.72438 -3.613658)
				)
				(arc
					(start 141.72438 -3.613658)
					(mid 141.719982 -3.601436)
					(end 141.712188 -3.591052)
				)
				(arc
					(start 141.712188 -3.591052)
					(mid 141.697854 -3.581474)
					(end 141.680946 -3.578098)
				)
				(arc
					(start 141.336522 -3.578098)
					(mid 141.284789 -3.586778)
					(end 141.238732 -3.61188)
				)
				(arc
					(start 141.238732 -3.999738)
					(mid 141.799945 -4.561332)
					(end 142.361412 -3.999992)
				)
			)
		)
	)
	(zone
		(layer "B.Cu")
		(hatch none 0.5)
		(connect_pads
			(clearance 0)
		)
		(min_thickness 0.25)
		(keepout
			(tracks not_allowed)
			(vias allowed)
			(pads allowed)
			(copperpour not_allowed)
			(footprints allowed)
		)
		(placement
			(enabled no)
			(sheetname "")
		)
		(fill
			(thermal_gap 0.5)
			(thermal_bridge_width 0.5)
			(island_removal_mode 0)
		)
		(polygon
			(pts
				(arc
					(start 126.000256 -64.641984)
					(mid 125.641862 -64.999997)
					(end 126.000002 -65.358264)
				)
				(arc
					(start 127 -65.358264)
					(mid 127.355598 -65.042721)
					(end 127.084582 -64.652144)
				)
				(arc
					(start 126.750064 -64.652144)
					(mid 126.680916 -64.680786)
					(end 126.652274 -64.749934)
				)
				(arc
					(start 126.652274 -64.900048)
					(mid 126.664847 -64.930401)
					(end 126.6952 -64.942974)
				)
				(arc
					(start 126.765558 -64.942974)
					(mid 127.241307 -65.000124)
					(end 126.765558 -65.057274)
				)
				(xy 126.671578 -65.057274)
				(arc
					(start 126.669292 -65.055242)
					(mid 126.583943 -65.011305)
					(end 126.540006 -64.925956)
				)
				(xy 126.537974 -64.92367) (xy 126.537974 -64.726312)
				(arc
					(start 126.539498 -64.724788)
					(mid 126.549148 -64.681927)
					(end 126.567438 -64.641984)
				)
				(arc
					(start 126.482856 -64.641984)
					(mid 126.467122 -64.694945)
					(end 126.461774 -64.749934)
				)
				(xy 126.461774 -64.923924)
				(arc
					(start 126.459742 -64.92621)
					(mid 126.415882 -65.011382)
					(end 126.33071 -65.055242)
				)
				(xy 126.328424 -65.057274)
				(arc
					(start 126.234444 -65.057274)
					(mid 125.758695 -65.000124)
					(end 126.234444 -64.942974)
				)
				(arc
					(start 126.304802 -64.942974)
					(mid 126.334976 -64.930476)
					(end 126.347474 -64.900302)
				)
				(xy 126.347474 -64.726312)
				(arc
					(start 126.348236 -64.72555)
					(mid 126.353007 -64.683396)
					(end 126.362206 -64.641984)
				)
			)
		)
	)
	(zone
		(net "GND")
		(layer "B.Cu")
		(hatch none 0.5)
		(connect_pads
			(clearance 0.5)
		)
		(min_thickness 0.25)
		(fill yes
			(thermal_gap 0.5)
			(thermal_bridge_width 0.5)
			(island_removal_mode 0)
		)
		(polygon
			(pts
				(xy 151.957278 -58.480198) (xy 151.8158 -58.621676) (xy 151.8158 -64.4144) (xy 152.0444 -64.643)
				(xy 153.797 -64.643) (xy 153.994358 -64.445642) (xy 153.994358 -58.795158) (xy 153.679398 -58.480198)
			)
		)
		(polygon
			(pts
				(xy 153.143204 -63.589408) (xy 152.940004 -63.589408) (xy 152.940004 -63.792608) (xy 153.143204 -63.792608)
			)
		)
		(polygon
			(pts
				(xy 153.473404 -60.871608) (xy 153.270204 -60.871608) (xy 153.270204 -61.074808) (xy 153.473404 -61.074808)
			)
		)
		(polygon
			(pts
				(xy 153.448004 -59.881008) (xy 153.244804 -59.881008) (xy 153.244804 -60.084208) (xy 153.270204 -60.160408)
				(xy 153.270204 -60.363608) (xy 153.473404 -60.363608) (xy 153.473404 -60.160408) (xy 153.448004 -60.084208)
			)
		)
		(polygon
			(pts
				(xy 153.448004 -59.271408) (xy 153.244804 -59.271408) (xy 153.244804 -59.474608) (xy 153.448004 -59.474608)
			)
		)
	)
	(zone
		(layer "B.Cu")
		(hatch none 0.5)
		(connect_pads
			(clearance 0)
		)
		(min_thickness 0.25)
		(keepout
			(tracks not_allowed)
			(vias allowed)
			(pads allowed)
			(copperpour not_allowed)
			(footprints allowed)
		)
		(placement
			(enabled no)
			(sheetname "")
		)
		(fill
			(thermal_gap 0.5)
			(thermal_bridge_width 0.5)
			(island_removal_mode 0)
		)
		(polygon
			(pts
				(arc
					(start 126.000256 -61.64199)
					(mid 125.641862 -62.000003)
					(end 126.000002 -62.35827)
				)
				(arc
					(start 127 -62.35827)
					(mid 127.355841 -62.040646)
					(end 127.080518 -61.651134)
				)
				(arc
					(start 126.75108 -61.651134)
					(mid 126.681214 -61.680074)
					(end 126.652274 -61.74994)
				)
				(arc
					(start 126.652274 -61.900054)
					(mid 126.664847 -61.930407)
					(end 126.6952 -61.94298)
				)
				(arc
					(start 126.765558 -61.94298)
					(mid 127.241307 -62.00013)
					(end 126.765558 -62.05728)
				)
				(xy 126.671578 -62.05728)
				(arc
					(start 126.669292 -62.055248)
					(mid 126.583943 -62.011311)
					(end 126.540006 -61.925962)
				)
				(xy 126.537974 -61.923676) (xy 126.537974 -61.726318)
				(arc
					(start 126.539498 -61.724794)
					(mid 126.549153 -61.681933)
					(end 126.567438 -61.64199)
				)
				(arc
					(start 126.482602 -61.64199)
					(mid 126.467029 -61.694968)
					(end 126.461774 -61.74994)
				)
				(xy 126.461774 -61.92393)
				(arc
					(start 126.459742 -61.926216)
					(mid 126.415882 -62.011388)
					(end 126.33071 -62.055248)
				)
				(xy 126.328424 -62.05728)
				(arc
					(start 126.234444 -62.05728)
					(mid 125.758695 -62.00013)
					(end 126.234444 -61.94298)
				)
				(arc
					(start 126.304802 -61.94298)
					(mid 126.334976 -61.930482)
					(end 126.347474 -61.900308)
				)
				(xy 126.347474 -61.726318)
				(arc
					(start 126.348236 -61.725556)
					(mid 126.353021 -61.683405)
					(end 126.362206 -61.64199)
				)
			)
		)
	)
	(zone
		(layer "B.Cu")
		(hatch none 0.5)
		(connect_pads
			(clearance 0)
		)
		(min_thickness 0.25)
		(keepout
			(tracks not_allowed)
			(vias allowed)
			(pads allowed)
			(copperpour not_allowed)
			(footprints allowed)
		)
		(placement
			(enabled no)
			(sheetname "")
		)
		(fill
			(thermal_gap 0.5)
			(thermal_bridge_width 0.5)
			(island_removal_mode 0)
		)
		(polygon
			(pts
				(arc
					(start 175.114204 -30.060646)
					(mid 174.790886 -30.109249)
					(end 174.641764 -30.400244)
				)
				(arc
					(start 174.642018 -31.199836)
					(mid 175.000158 -31.55823)
					(end 175.358298 -31.199836)
				)
				(xy 175.358298 -31.029402) (xy 175.358044 -30.711648)
				(arc
					(start 175.170846 -31.029402)
					(mid 174.877517 -31.408004)
					(end 175.06696 -30.968188)
				)
				(xy 175.339756 -30.5054)
				(arc
					(start 175.339756 -30.286706)
					(mid 175.330061 -30.260897)
					(end 175.31842 -30.235906)
				)
				(xy 175.298608 -30.216094)
				(arc
					(start 175.298608 -30.202124)
					(mid 175.269309 -30.163778)
					(end 175.235108 -30.129734)
				)
				(xy 175.235108 -30.25013) (xy 175.234854 -30.25013)
				(arc
					(start 175.207676 -30.277562)
					(mid 174.832708 -30.573781)
					(end 175.114204 -30.187646)
				)
			)
		)
	)
	(zone
		(layer "B.Cu")
		(hatch none 0.5)
		(connect_pads
			(clearance 0)
		)
		(min_thickness 0.25)
		(keepout
			(tracks not_allowed)
			(vias allowed)
			(pads allowed)
			(copperpour not_allowed)
			(footprints allowed)
		)
		(placement
			(enabled no)
			(sheetname "")
		)
		(fill
			(thermal_gap 0.5)
			(thermal_bridge_width 0.5)
			(island_removal_mode 0)
		)
		(polygon
			(pts
				(arc
					(start 108.161328 -3.800094)
					(mid 107.599988 -3.238754)
					(end 107.038648 -3.800094)
				)
				(arc
					(start 107.038648 -4.228592)
					(mid 107.0716 -4.224901)
					(end 107.104688 -4.22275)
				)
				(xy 107.10545 -4.221988)
				(arc
					(start 107.480862 -4.221988)
					(mid 107.497775 -4.218624)
					(end 107.512104 -4.209034)
				)
				(arc
					(start 107.512104 -4.209034)
					(mid 107.51987 -4.198635)
					(end 107.524296 -4.186428)
				)
				(arc
					(start 107.524296 -4.186428)
					(mid 107.60089 -3.406367)
					(end 107.674918 -4.186682)
				)
				(xy 107.674918 -4.20878)
				(arc
					(start 107.67187 -4.211828)
					(mid 107.652939 -4.267359)
					(end 107.618276 -4.314698)
				)
				(arc
					(start 107.618276 -4.314698)
					(mid 107.57076 -4.349728)
					(end 107.514898 -4.3688)
				)
				(xy 107.51185 -4.371848)
				(arc
					(start 107.136438 -4.371848)
					(mid 107.087354 -4.37403)
					(end 107.038648 -4.380484)
				)
				(arc
					(start 107.038648 -4.64439)
					(mid 107.070773 -4.635509)
					(end 107.103672 -4.630166)
				)
				(xy 107.10545 -4.628388) (xy 107.51185 -4.628388)
				(arc
					(start 107.514898 -4.631436)
					(mid 107.570747 -4.650533)
					(end 107.618276 -4.685538)
				)
				(arc
					(start 107.618276 -4.685538)
					(mid 107.652964 -4.732864)
					(end 107.67187 -4.788408)
				)
				(xy 107.674918 -4.791456)
				(arc
					(start 107.674918 -4.813554)
					(mid 107.60089 -5.593876)
					(end 107.524296 -4.813808)
				)
				(arc
					(start 107.524296 -4.813808)
					(mid 107.519898 -4.801586)
					(end 107.512104 -4.791202)
				)
				(arc
					(start 107.512104 -4.791202)
					(mid 107.49777 -4.781624)
					(end 107.480862 -4.778248)
				)
				(arc
					(start 107.136438 -4.778248)
					(mid 107.084705 -4.786928)
					(end 107.038648 -4.81203)
				)
				(arc
					(start 107.038648 -5.199888)
					(mid 107.599861 -5.761482)
					(end 108.161328 -5.200142)
				)
			)
		)
	)
	(zone
		(layer "B.Cu")
		(hatch none 0.5)
		(connect_pads
			(clearance 0)
		)
		(min_thickness 0.25)
		(keepout
			(tracks not_allowed)
			(vias allowed)
			(pads allowed)
			(copperpour not_allowed)
			(footprints allowed)
		)
		(placement
			(enabled no)
			(sheetname "")
		)
		(fill
			(thermal_gap 0.5)
			(thermal_bridge_width 0.5)
			(island_removal_mode 0)
		)
		(polygon
			(pts
				(arc
					(start 126.000256 -76.64196)
					(mid 125.641862 -76.999973)
					(end 126.000002 -77.35824)
				)
				(arc
					(start 126.354586 -77.35824)
					(mid 126.350628 -77.334468)
					(end 126.348236 -77.310488)
				)
				(xy 126.347474 -77.309726)
				(arc
					(start 126.347474 -77.089)
					(mid 126.338175 -77.066549)
					(end 126.315724 -77.05725)
				)
				(arc
					(start 126.234444 -77.05725)
					(mid 125.758695 -77.0001)
					(end 126.234444 -76.94295)
				)
				(xy 126.339346 -76.94295)
				(arc
					(start 126.341632 -76.945236)
					(mid 126.419018 -76.985706)
					(end 126.459488 -77.063092)
				)
				(xy 126.461774 -77.065378)
				(arc
					(start 126.461774 -77.286104)
					(mid 126.464378 -77.322547)
					(end 126.472188 -77.35824)
				)
				(arc
					(start 126.553468 -77.35824)
					(mid 126.545015 -77.33547)
					(end 126.539752 -77.311758)
				)
				(xy 126.537974 -77.309726) (xy 126.537974 -77.065378)
				(arc
					(start 126.54026 -77.063092)
					(mid 126.58073 -76.985706)
					(end 126.658116 -76.945236)
				)
				(xy 126.660402 -76.94295)
				(arc
					(start 126.765558 -76.94295)
					(mid 127.241307 -77.0001)
					(end 126.765558 -77.05725)
				)
				(arc
					(start 126.684024 -77.05725)
					(mid 126.661573 -77.066549)
					(end 126.652274 -77.089)
				)
				(arc
					(start 126.652274 -77.286104)
					(mid 126.670501 -77.330107)
					(end 126.714504 -77.348334)
				)
				(arc
					(start 127.083566 -77.348334)
					(mid 127.35564 -76.958026)
					(end 127 -76.64196)
				)
			)
		)
	)
	(zone
		(net "P1V8_C")
		(layer "B.Cu")
		(hatch none 0.5)
		(connect_pads
			(clearance 0.5)
		)
		(min_thickness 0.25)
		(fill yes
			(thermal_gap 0.5)
			(thermal_bridge_width 0.5)
			(island_removal_mode 0)
		)
		(polygon
			(pts
				(xy 190.860172 -20.48002) (xy 190.685928 -20.654518) (xy 190.685928 -22.159722) (xy 190.878206 -22.352)
				(xy 193.2178 -22.352) (xy 193.2178 -20.62353) (xy 193.07429 -20.48002)
			)
		)
		(polygon
			(pts
				(xy 192.65138 -21.4884) (xy 192.44818 -21.4884) (xy 192.44818 -21.6916) (xy 192.65138 -21.6916)
			)
		)
		(polygon
			(pts
				(xy 192.65138 -20.9804) (xy 192.44818 -20.9804) (xy 192.44818 -21.1836) (xy 192.65138 -21.1836)
			)
		)
	)
	(zone
		(layer "B.Cu")
		(hatch none 0.5)
		(connect_pads
			(clearance 0)
		)
		(min_thickness 0.25)
		(keepout
			(tracks not_allowed)
			(vias allowed)
			(pads allowed)
			(copperpour not_allowed)
			(footprints allowed)
		)
		(placement
			(enabled no)
			(sheetname "")
		)
		(fill
			(thermal_gap 0.5)
			(thermal_bridge_width 0.5)
			(island_removal_mode 0)
		)
		(polygon
			(pts
				(arc
					(start 120.761506 -2.600198)
					(mid 120.200166 -2.038858)
					(end 119.638826 -2.600198)
				)
				(arc
					(start 119.638826 -3.028442)
					(mid 119.671778 -3.024751)
					(end 119.704866 -3.0226)
				)
				(xy 119.705628 -3.021838)
				(arc
					(start 120.08104 -3.021838)
					(mid 120.097953 -3.018474)
					(end 120.112282 -3.008884)
				)
				(arc
					(start 120.112282 -3.008884)
					(mid 120.119879 -2.99858)
					(end 120.12422 -2.986532)
				)
				(arc
					(start 120.12422 -2.986532)
					(mid 120.201192 -2.206422)
					(end 120.275096 -2.986786)
				)
				(xy 120.275096 -3.00863)
				(arc
					(start 120.272048 -3.011678)
					(mid 120.253117 -3.067209)
					(end 120.218454 -3.114548)
				)
				(arc
					(start 120.218454 -3.114548)
					(mid 120.170938 -3.149578)
					(end 120.115076 -3.16865)
				)
				(xy 120.112028 -3.171698)
				(arc
					(start 119.736616 -3.171698)
					(mid 119.687532 -3.17388)
					(end 119.638826 -3.180334)
				)
				(arc
					(start 119.638826 -3.44424)
					(mid 119.670951 -3.435359)
					(end 119.70385 -3.430016)
				)
				(xy 119.705628 -3.428238) (xy 120.112028 -3.428238)
				(arc
					(start 120.115076 -3.431286)
					(mid 120.170925 -3.450383)
					(end 120.218454 -3.485388)
				)
				(arc
					(start 120.218454 -3.485388)
					(mid 120.253142 -3.532714)
					(end 120.272048 -3.588258)
				)
				(xy 120.275096 -3.591306)
				(arc
					(start 120.275096 -3.613404)
					(mid 120.201068 -4.393726)
					(end 120.124474 -3.613658)
				)
				(arc
					(start 120.124474 -3.613658)
					(mid 120.120076 -3.601436)
					(end 120.112282 -3.591052)
				)
				(arc
					(start 120.112282 -3.591052)
					(mid 120.097948 -3.581474)
					(end 120.08104 -3.578098)
				)
				(arc
					(start 119.736616 -3.578098)
					(mid 119.684883 -3.586778)
					(end 119.638826 -3.61188)
				)
				(arc
					(start 119.638826 -3.999738)
					(mid 120.200039 -4.561332)
					(end 120.761506 -3.999992)
				)
			)
		)
	)
	(zone
		(layer "B.Cu")
		(hatch none 0.5)
		(connect_pads
			(clearance 0)
		)
		(min_thickness 0.25)
		(keepout
			(tracks not_allowed)
			(vias allowed)
			(pads allowed)
			(copperpour not_allowed)
			(footprints allowed)
		)
		(placement
			(enabled no)
			(sheetname "")
		)
		(fill
			(thermal_gap 0.5)
			(thermal_bridge_width 0.5)
			(island_removal_mode 0)
		)
		(polygon
			(pts
				(arc
					(start 112.35817 -55.000144)
					(mid 112.047181 -54.645121)
					(end 111.654336 -54.906672)
				)
				(arc
					(start 111.654336 -55.245508)
					(mid 111.661876 -55.283417)
					(end 111.683292 -55.315612)
				)
				(arc
					(start 111.683292 -55.315612)
					(mid 111.719083 -55.339464)
					(end 111.76127 -55.34787)
				)
				(arc
					(start 111.91113 -55.34787)
					(mid 111.933581 -55.338571)
					(end 111.94288 -55.31612)
				)
				(arc
					(start 111.94288 -55.234586)
					(mid 112.00003 -54.758837)
					(end 112.05718 -55.234586)
				)
				(xy 112.05718 -55.339742)
				(arc
					(start 112.054894 -55.342028)
					(mid 112.014424 -55.419414)
					(end 111.937038 -55.459884)
				)
				(xy 111.934752 -55.46217) (xy 111.737648 -55.46217)
				(arc
					(start 111.736124 -55.460646)
					(mid 111.687172 -55.449546)
					(end 111.64189 -55.42788)
				)
				(arc
					(start 111.64189 -55.513732)
					(mid 111.700072 -55.532094)
					(end 111.760762 -55.53837)
				)
				(xy 111.934752 -55.53837)
				(arc
					(start 111.937038 -55.540656)
					(mid 112.014424 -55.581126)
					(end 112.054894 -55.658512)
				)
				(xy 112.05718 -55.660798)
				(arc
					(start 112.05718 -55.7657)
					(mid 112.00003 -56.241449)
					(end 111.94288 -55.7657)
				)
				(arc
					(start 111.94288 -55.68442)
					(mid 111.933581 -55.661969)
					(end 111.91113 -55.65267)
				)
				(xy 111.737648 -55.65267)
				(arc
					(start 111.736886 -55.651908)
					(mid 111.688898 -55.646299)
					(end 111.64189 -55.635144)
				)
				(arc
					(start 111.64189 -55.999888)
					(mid 111.999903 -56.358282)
					(end 112.35817 -56.000142)
				)
			)
		)
	)
	(zone
		(net "GND")
		(layer "B.Cu")
		(hatch none 0.5)
		(connect_pads
			(clearance 0.5)
		)
		(min_thickness 0.25)
		(fill yes
			(thermal_gap 0.5)
			(thermal_bridge_width 0.5)
			(island_removal_mode 0)
		)
		(polygon
			(pts
				(xy 57.1246 -32.5628) (xy 56.134 -33.5534) (xy 56.134 -40.6146) (xy 56.3372 -40.8178) (xy 61.214 -40.8178)
				(xy 61.699648 -40.332152) (xy 61.699648 -33.68675) (xy 60.575698 -32.5628)
			)
		)
	)
	(zone
		(layer "B.Cu")
		(hatch none 0.5)
		(connect_pads
			(clearance 0)
		)
		(min_thickness 0.25)
		(keepout
			(tracks allowed)
			(vias allowed)
			(pads allowed)
			(copperpour allowed)
			(footprints not_allowed)
		)
		(placement
			(enabled no)
			(sheetname "")
		)
		(fill
			(thermal_gap 0.5)
			(thermal_bridge_width 0.5)
			(island_removal_mode 0)
		)
		(polygon
			(pts
				(arc
					(start 32.980884 -9.92505)
					(mid 29.481018 -6.425184)
					(end 25.980898 -9.92505)
				)
				(arc
					(start 25.980898 -9.92505)
					(mid 29.481018 -13.42517)
					(end 32.980884 -9.92505)
				)
			)
		)
	)
	(zone
		(layer "B.Cu")
		(hatch none 0.5)
		(connect_pads
			(clearance 0)
		)
		(min_thickness 0.25)
		(keepout
			(tracks allowed)
			(vias allowed)
			(pads allowed)
			(copperpour allowed)
			(footprints allowed)
		)
		(placement
			(enabled no)
			(sheetname "")
		)
		(fill
			(thermal_gap 0.5)
			(thermal_bridge_width 0.5)
			(island_removal_mode 0)
		)
		(polygon
			(pts
				(xy 96.528636 -47.461678) (xy 123.954794 -47.461678) (xy 124.289058 -47.795942) (xy 124.289058 -49.406556)
				(xy 123.3297 -50.365914) (xy 98.05797 -50.365914) (xy 96.430084 -48.738028) (xy 96.430084 -47.56023)
			)
		)
	)
	(zone
		(layer "B.Cu")
		(hatch none 0.5)
		(connect_pads
			(clearance 0)
		)
		(min_thickness 0.25)
		(keepout
			(tracks not_allowed)
			(vias allowed)
			(pads allowed)
			(copperpour not_allowed)
			(footprints allowed)
		)
		(placement
			(enabled no)
			(sheetname "")
		)
		(fill
			(thermal_gap 0.5)
			(thermal_bridge_width 0.5)
			(island_removal_mode 0)
		)
		(polygon
			(pts
				(xy 104.893872 -115.286536) (xy 104.98963 -115.434872)
				(arc
					(start 105.057702 -115.503198)
					(mid 105.101413 -115.541567)
					(end 105.14965 -115.574064)
				)
				(xy 105.158032 -115.578636) (xy 105.170224 -115.584986) (xy 105.170732 -115.584732) (xy 105.174288 -115.586764)
				(xy 105.175304 -115.58651) (xy 105.189528 -115.595146) (xy 105.200704 -115.595146) (xy 105.213658 -115.6081)
				(xy 105.221786 -115.612164) (xy 105.22458 -115.613688) (xy 105.224834 -115.613942) (xy 105.230676 -115.61699)
				(arc
					(start 105.2322 -115.621562)
					(mid 105.301479 -115.721339)
					(end 105.300018 -115.842796)
				)
				(xy 105.301288 -115.84686) (xy 105.286556 -115.874038)
				(arc
					(start 105.242614 -115.95608)
					(mid 104.820006 -116.585801)
					(end 105.110534 -115.885214)
				)
				(arc
					(start 105.154476 -115.803172)
					(mid 105.159824 -115.772719)
					(end 105.146094 -115.745006)
				)
				(xy 105.138474 -115.745006) (xy 105.125012 -115.731544) (xy 105.1052 -115.721638) (xy 105.104946 -115.721384)
				(xy 105.101136 -115.719352) (xy 105.098342 -115.717828) (xy 105.097834 -115.716558) (xy 105.087928 -115.711224)
				(xy 105.0544 -115.693698)
				(arc
					(start 105.053638 -115.691158)
					(mid 105.012903 -115.662683)
					(end 104.974644 -115.63096)
				)
				(xy 104.973374 -115.63096) (xy 104.893618 -115.550696) (xy 104.884982 -115.548918) (xy 104.872282 -115.52936)
				(xy 104.856026 -115.513104) (xy 104.856026 -115.504214) (xy 104.812846 -115.437412)
				(arc
					(start 104.516428 -115.990624)
					(mid 104.740809 -116.733627)
					(end 105.48366 -116.509038)
				)
				(arc
					(start 106.233722 -115.10899)
					(mid 106.242004 -114.606921)
					(end 105.838244 -114.308382)
				)
				(xy 105.7021 -114.308382)
				(arc
					(start 105.541064 -114.342672)
					(mid 105.382226 -114.442904)
					(end 105.26649 -114.59083)
				)
				(xy 105.13822 -114.830352) (xy 105.16489 -114.956844) (xy 105.306622 -115.176046) (xy 105.34523 -115.215924)
				(xy 105.353104 -115.22202) (xy 105.367582 -115.22964) (xy 105.371646 -115.228878) (xy 105.37571 -115.231418)
				(xy 105.376218 -115.231418) (xy 105.396538 -115.24488)
				(arc
					(start 105.40365 -115.248436)
					(mid 105.438085 -115.247912)
					(end 105.463848 -115.225068)
				)
				(arc
					(start 105.507536 -115.143788)
					(mid 105.930144 -114.514067)
					(end 105.639616 -115.214654)
				)
				(xy 105.581196 -115.323366)
				(arc
					(start 105.577386 -115.324636)
					(mid 105.477789 -115.392782)
					(end 105.357168 -115.39093)
				)
				(xy 105.354628 -115.391946) (xy 105.350818 -115.389914) (xy 105.345484 -115.39093) (xy 105.342182 -115.388898)
				(xy 105.341674 -115.388898) (xy 105.31983 -115.37442) (xy 105.296208 -115.362482) (xy 105.295954 -115.362228)
				(xy 105.291636 -115.359942) (xy 105.291128 -115.358672) (xy 105.28046 -115.353084) (xy 105.262934 -115.343432)
				(xy 105.260394 -115.343432) (xy 105.2576 -115.340638) (xy 105.253282 -115.338352) (xy 105.252266 -115.335304)
				(xy 105.209848 -115.291616) (xy 105.201466 -115.289838) (xy 105.188766 -115.270026) (xy 105.172256 -115.253008)
				(xy 105.17251 -115.244626) (xy 105.040176 -115.039902) (xy 105.029508 -115.033044)
			)
		)
	)
	(zone
		(net "GND")
		(layer "B.Cu")
		(hatch none 0.5)
		(connect_pads
			(clearance 0.5)
		)
		(min_thickness 0.25)
		(fill yes
			(thermal_gap 0.5)
			(thermal_bridge_width 0.5)
			(island_removal_mode 0)
		)
		(polygon
			(pts
				(xy 195.770246 -28.46324) (xy 195.674742 -28.558744) (xy 195.674742 -31.731458) (xy 195.715382 -31.772098)
				(xy 200.39203 -31.772098) (xy 200.734422 -31.429706) (xy 200.734422 -30.513274) (xy 199.629014 -29.407866)
				(xy 199.629014 -28.664916) (xy 199.427338 -28.46324)
			)
		)
		(polygon
			(pts
				(xy 197.410578 -31.062422) (xy 197.207378 -31.062422) (xy 197.207378 -31.265622) (xy 197.410578 -31.265622)
			)
		)
		(polygon
			(pts
				(xy 196.699378 -31.062422) (xy 196.191378 -31.062422) (xy 196.191378 -31.265622) (xy 196.699378 -31.265622)
			)
		)
		(polygon
			(pts
				(xy 199.848978 -30.605222) (xy 199.645778 -30.605222) (xy 199.645778 -30.808422) (xy 199.848978 -30.808422)
			)
		)
		(polygon
			(pts
				(xy 197.7644 -29.3624) (xy 197.5612 -29.3624) (xy 197.5612 -29.5656) (xy 197.7644 -29.5656)
			)
		)
		(polygon
			(pts
				(xy 196.9008 -29.3624) (xy 196.6976 -29.3624) (xy 196.6976 -29.5656) (xy 196.9008 -29.5656)
			)
		)
		(polygon
			(pts
				(xy 196.5452 -28.9814) (xy 196.342 -28.9814) (xy 196.342 -29.1846) (xy 196.5452 -29.1846)
			)
		)
	)
	(zone
		(net "P1V8_C")
		(layer "B.Cu")
		(hatch none 0.5)
		(connect_pads
			(clearance 0.5)
		)
		(min_thickness 0.25)
		(fill yes
			(thermal_gap 0.5)
			(thermal_bridge_width 0.5)
			(island_removal_mode 0)
		)
		(polygon
			(pts
				(xy 157.5816 -25.4508) (xy 157.4038 -25.6286) (xy 157.4038 -26.8478) (xy 157.607 -27.051) (xy 161.163 -27.051)
				(xy 161.4424 -26.7716) (xy 161.4424 -25.5524) (xy 161.3408 -25.4508)
			)
		)
		(polygon
			(pts
				(xy 160.782 -26.3652) (xy 160.5788 -26.3652) (xy 160.5788 -26.5684) (xy 160.782 -26.5684)
			)
		)
		(polygon
			(pts
				(xy 160.2232 -26.3652) (xy 160.02 -26.3652) (xy 160.02 -26.5684) (xy 160.2232 -26.5684)
			)
		)
	)
	(zone
		(layer "B.Cu")
		(hatch none 0.5)
		(connect_pads
			(clearance 0)
		)
		(min_thickness 0.25)
		(keepout
			(tracks not_allowed)
			(vias allowed)
			(pads allowed)
			(copperpour not_allowed)
			(footprints allowed)
		)
		(placement
			(enabled no)
			(sheetname "")
		)
		(fill
			(thermal_gap 0.5)
			(thermal_bridge_width 0.5)
			(island_removal_mode 0)
		)
		(polygon
			(pts
				(arc
					(start 91.961462 -2.600198)
					(mid 91.400122 -2.038858)
					(end 90.838782 -2.600198)
				)
				(arc
					(start 90.838782 -3.028442)
					(mid 90.871734 -3.024751)
					(end 90.904822 -3.0226)
				)
				(xy 90.905584 -3.021838)
				(arc
					(start 91.280996 -3.021838)
					(mid 91.297909 -3.018474)
					(end 91.312238 -3.008884)
				)
				(arc
					(start 91.312238 -3.008884)
					(mid 91.319835 -2.99858)
					(end 91.324176 -2.986532)
				)
				(arc
					(start 91.324176 -2.986532)
					(mid 91.401148 -2.206422)
					(end 91.475052 -2.986786)
				)
				(xy 91.475052 -3.00863)
				(arc
					(start 91.472004 -3.011678)
					(mid 91.453073 -3.067209)
					(end 91.41841 -3.114548)
				)
				(arc
					(start 91.41841 -3.114548)
					(mid 91.370894 -3.149578)
					(end 91.315032 -3.16865)
				)
				(xy 91.311984 -3.171698)
				(arc
					(start 90.936572 -3.171698)
					(mid 90.887488 -3.17388)
					(end 90.838782 -3.180334)
				)
				(arc
					(start 90.838782 -3.44424)
					(mid 90.870907 -3.435359)
					(end 90.903806 -3.430016)
				)
				(xy 90.905584 -3.428238) (xy 91.311984 -3.428238)
				(arc
					(start 91.315032 -3.431286)
					(mid 91.370881 -3.450383)
					(end 91.41841 -3.485388)
				)
				(arc
					(start 91.41841 -3.485388)
					(mid 91.453098 -3.532714)
					(end 91.472004 -3.588258)
				)
				(xy 91.475052 -3.591306)
				(arc
					(start 91.475052 -3.613404)
					(mid 91.401024 -4.393726)
					(end 91.32443 -3.613658)
				)
				(arc
					(start 91.32443 -3.613658)
					(mid 91.320032 -3.601436)
					(end 91.312238 -3.591052)
				)
				(arc
					(start 91.312238 -3.591052)
					(mid 91.297904 -3.581474)
					(end 91.280996 -3.578098)
				)
				(arc
					(start 90.936572 -3.578098)
					(mid 90.884839 -3.586778)
					(end 90.838782 -3.61188)
				)
				(arc
					(start 90.838782 -3.999738)
					(mid 91.399995 -4.561332)
					(end 91.961462 -3.999992)
				)
			)
		)
	)
	(zone
		(layer "B.Cu")
		(hatch none 0.5)
		(connect_pads
			(clearance 0)
		)
		(min_thickness 0.25)
		(keepout
			(tracks allowed)
			(vias allowed)
			(pads allowed)
			(copperpour allowed)
			(footprints not_allowed)
		)
		(placement
			(enabled no)
			(sheetname "")
		)
		(fill
			(thermal_gap 0.5)
			(thermal_bridge_width 0.5)
			(island_removal_mode 0)
		)
		(polygon
			(pts
				(xy 4.99999 0)
				(arc
					(start 1.999996 0)
					(mid 0.585785 -0.585785)
					(end 0 -1.999996)
				)
				(arc
					(start 0 -142.999968)
					(mid 0.585785 -144.414179)
					(end 1.999996 -144.999964)
				)
				(xy 4.99999 -144.999964)
			)
		)
	)
	(zone
		(layer "B.Cu")
		(hatch none 0.5)
		(connect_pads
			(clearance 0)
		)
		(min_thickness 0.25)
		(keepout
			(tracks allowed)
			(vias allowed)
			(pads allowed)
			(copperpour allowed)
			(footprints allowed)
		)
		(placement
			(enabled no)
			(sheetname "")
		)
		(fill
			(thermal_gap 0.5)
			(thermal_bridge_width 0.5)
			(island_removal_mode 0)
		)
		(polygon
			(pts
				(xy 181.296818 -22.068536) (xy 181.296818 -21.177758) (xy 181.702456 -21.177758) (xy 181.702456 -22.068536)
			)
		)
	)
	(zone
		(layer "B.Cu")
		(hatch none 0.5)
		(connect_pads
			(clearance 0)
		)
		(min_thickness 0.25)
		(keepout
			(tracks not_allowed)
			(vias allowed)
			(pads allowed)
			(copperpour not_allowed)
			(footprints allowed)
		)
		(placement
			(enabled no)
			(sheetname "")
		)
		(fill
			(thermal_gap 0.5)
			(thermal_bridge_width 0.5)
			(island_removal_mode 0)
		)
		(polygon
			(pts
				(arc
					(start 99.161346 -2.600198)
					(mid 98.600006 -2.038858)
					(end 98.038666 -2.600198)
				)
				(arc
					(start 98.038666 -3.028442)
					(mid 98.071618 -3.024751)
					(end 98.104706 -3.0226)
				)
				(xy 98.105468 -3.021838)
				(arc
					(start 98.48088 -3.021838)
					(mid 98.497793 -3.018474)
					(end 98.512122 -3.008884)
				)
				(arc
					(start 98.512122 -3.008884)
					(mid 98.519719 -2.99858)
					(end 98.52406 -2.986532)
				)
				(arc
					(start 98.52406 -2.986532)
					(mid 98.601032 -2.206422)
					(end 98.674936 -2.986786)
				)
				(xy 98.674936 -3.00863)
				(arc
					(start 98.671888 -3.011678)
					(mid 98.652957 -3.067209)
					(end 98.618294 -3.114548)
				)
				(arc
					(start 98.618294 -3.114548)
					(mid 98.570778 -3.149578)
					(end 98.514916 -3.16865)
				)
				(xy 98.511868 -3.171698)
				(arc
					(start 98.136456 -3.171698)
					(mid 98.087372 -3.17388)
					(end 98.038666 -3.180334)
				)
				(arc
					(start 98.038666 -3.44424)
					(mid 98.070791 -3.435359)
					(end 98.10369 -3.430016)
				)
				(xy 98.105468 -3.428238) (xy 98.511868 -3.428238)
				(arc
					(start 98.514916 -3.431286)
					(mid 98.570765 -3.450383)
					(end 98.618294 -3.485388)
				)
				(arc
					(start 98.618294 -3.485388)
					(mid 98.652982 -3.532714)
					(end 98.671888 -3.588258)
				)
				(xy 98.674936 -3.591306)
				(arc
					(start 98.674936 -3.613404)
					(mid 98.600908 -4.393726)
					(end 98.524314 -3.613658)
				)
				(arc
					(start 98.524314 -3.613658)
					(mid 98.519916 -3.601436)
					(end 98.512122 -3.591052)
				)
				(arc
					(start 98.512122 -3.591052)
					(mid 98.497788 -3.581474)
					(end 98.48088 -3.578098)
				)
				(arc
					(start 98.136456 -3.578098)
					(mid 98.084723 -3.586778)
					(end 98.038666 -3.61188)
				)
				(arc
					(start 98.038666 -3.999738)
					(mid 98.599879 -4.561332)
					(end 99.161346 -3.999992)
				)
			)
		)
	)
	(zone
		(net "GND")
		(layer "B.Cu")
		(hatch none 0.5)
		(connect_pads
			(clearance 0.5)
		)
		(min_thickness 0.25)
		(fill yes
			(thermal_gap 0.5)
			(thermal_bridge_width 0.5)
			(island_removal_mode 0)
		)
		(polygon
			(pts
				(xy 126.8476 -51.6382) (xy 126.7587 -51.7271) (xy 126.7587 -52.1843) (xy 126.8603 -52.2859) (xy 128.0033 -52.2859)
				(xy 128.3462 -52.6288) (xy 128.3462 -53.4543) (xy 128.3716 -53.4797) (xy 129.184146 -53.4797) (xy 129.534412 -53.829966)
				(xy 129.534412 -59.898788) (xy 129.580132 -59.944508) (xy 130.081274 -59.944508) (xy 130.13182 -59.893962)
				(xy 130.13182 -56.930036) (xy 131.3688 -55.693056) (xy 131.3688 -52.898802) (xy 130.133598 -51.6636)
				(xy 129.413 -51.6636) (xy 129.3876 -51.6382)
			)
		)
		(polygon
			(pts
				(xy 129.981452 -59.448192) (xy 129.778252 -59.448192) (xy 129.778252 -59.651392) (xy 129.981452 -59.651392)
			)
		)
		(polygon
			(pts
				(xy 129.981452 -59.092592) (xy 129.778252 -59.092592) (xy 129.778252 -59.295792) (xy 129.981452 -59.295792)
			)
		)
		(polygon
			(pts
				(xy 129.981452 -58.772806) (xy 129.778252 -58.772806) (xy 129.778252 -58.976006) (xy 129.981452 -58.976006)
			)
		)
		(polygon
			(pts
				(xy 129.981452 -58.417206) (xy 129.778252 -58.417206) (xy 129.778252 -58.620406) (xy 129.981452 -58.620406)
			)
		)
		(polygon
			(pts
				(xy 129.981452 -57.42686) (xy 129.778252 -57.42686) (xy 129.778252 -57.63006) (xy 129.981452 -57.63006)
			)
		)
		(polygon
			(pts
				(xy 129.981452 -56.79186) (xy 129.778252 -56.79186) (xy 129.778252 -57.27446) (xy 129.981452 -57.27446)
			)
		)
		(polygon
			(pts
				(xy 129.981452 -56.43626) (xy 129.778252 -56.43626) (xy 129.778252 -56.63946) (xy 129.981452 -56.63946)
			)
		)
		(polygon
			(pts
				(xy 129.981452 -55.310024) (xy 129.778252 -55.310024) (xy 129.778252 -55.513224) (xy 129.981452 -55.513224)
			)
		)
		(polygon
			(pts
				(xy 129.981452 -54.678834) (xy 129.778252 -54.678834) (xy 129.778252 -55.157624) (xy 129.981452 -55.157624)
			)
		)
		(polygon
			(pts
				(xy 129.981452 -54.323234) (xy 129.778252 -54.323234) (xy 129.778252 -54.526434) (xy 129.981452 -54.526434)
			)
		)
	)
	(zone
		(net "GND")
		(layer "B.Cu")
		(hatch none 0.5)
		(connect_pads
			(clearance 0.5)
		)
		(min_thickness 0.25)
		(fill yes
			(thermal_gap 0.5)
			(thermal_bridge_width 0.5)
			(island_removal_mode 0)
		)
		(polygon
			(pts
				(xy 102.06736 -56.519572) (xy 101.823012 -56.76392) (xy 101.823012 -57.587134) (xy 101.890576 -57.654698)
				(xy 102.565708 -57.654698) (xy 102.765606 -57.4548) (xy 103.776272 -57.4548) (xy 104.072436 -57.750964)
				(xy 104.072436 -58.31459) (xy 104.212644 -58.454798) (xy 105.316274 -58.454798) (xy 106.505248 -59.643772)
				(xy 107.630468 -59.643772) (xy 107.780836 -59.493404) (xy 107.780836 -58.554112) (xy 107.757468 -58.530744)
				(xy 106.95559 -58.530744) (xy 106.472228 -58.047382) (xy 106.472228 -57.634886) (xy 106.728514 -57.3786)
				(xy 124.537216 -57.3786) (xy 124.6124 -57.453784) (xy 124.6124 -60.93587) (xy 124.879608 -61.203078)
				(xy 125.171708 -61.203078) (xy 125.213364 -61.161422) (xy 125.213364 -56.718708) (xy 125.014228 -56.519572)
			)
		)
		(polygon
			(pts
				(xy 125.0823 -60.579) (xy 124.8791 -60.579) (xy 124.8791 -60.7822) (xy 125.0823 -60.7822)
			)
		)
		(polygon
			(pts
				(xy 125.0823 -60.2234) (xy 124.8791 -60.2234) (xy 124.8791 -60.4266) (xy 125.0823 -60.4266)
			)
		)
		(polygon
			(pts
				(xy 125.099318 -59.565032) (xy 124.896118 -59.565032) (xy 124.896118 -59.768232) (xy 125.099318 -59.768232)
			)
		)
		(polygon
			(pts
				(xy 125.099318 -59.209432) (xy 124.896118 -59.209432) (xy 124.896118 -59.412632) (xy 125.099318 -59.412632)
			)
		)
		(polygon
			(pts
				(xy 107.50423 -58.7629) (xy 107.30103 -58.7629) (xy 107.30103 -59.2455) (xy 107.50423 -59.2455)
			)
		)
		(polygon
			(pts
				(xy 125.095 -58.4708) (xy 124.8918 -58.4708) (xy 124.8918 -58.674) (xy 125.095 -58.674)
			)
		)
		(polygon
			(pts
				(xy 104.774492 -57.9628) (xy 104.571292 -57.9628) (xy 104.571292 -58.166) (xy 104.774492 -58.166)
			)
		)
		(polygon
			(pts
				(xy 104.418892 -57.9628) (xy 104.215692 -57.9628) (xy 104.215692 -58.166) (xy 104.418892 -58.166)
			)
		)
		(polygon
			(pts
				(xy 125.095 -57.8358) (xy 124.8918 -57.8358) (xy 124.8918 -58.3184) (xy 125.095 -58.3184)
			)
		)
		(polygon
			(pts
				(xy 125.095 -57.4802) (xy 124.8918 -57.4802) (xy 124.8918 -57.6834) (xy 125.095 -57.6834)
			)
		)
		(polygon
			(pts
				(xy 102.3112 -57.2262) (xy 102.108 -57.2262) (xy 102.108 -57.4294) (xy 102.3112 -57.4294)
			)
		)
		(polygon
			(pts
				(xy 123.5329 -56.896) (xy 123.3297 -56.896) (xy 123.3297 -57.0992) (xy 123.5329 -57.0992)
			)
		)
		(polygon
			(pts
				(xy 123.1773 -56.896) (xy 122.6947 -56.896) (xy 122.6947 -57.0992) (xy 123.1773 -57.0992)
			)
		)
		(polygon
			(pts
				(xy 122.5423 -56.896) (xy 122.3391 -56.896) (xy 122.3391 -57.0992) (xy 122.5423 -57.0992)
			)
		)
		(polygon
			(pts
				(xy 121.539 -56.896) (xy 121.3358 -56.896) (xy 121.3358 -57.0992) (xy 121.539 -57.0992)
			)
		)
		(polygon
			(pts
				(xy 121.1834 -56.896) (xy 120.7008 -56.896) (xy 120.7008 -57.0992) (xy 121.1834 -57.0992)
			)
		)
		(polygon
			(pts
				(xy 120.5484 -56.896) (xy 120.3452 -56.896) (xy 120.3452 -57.0992) (xy 120.5484 -57.0992)
			)
		)
		(polygon
			(pts
				(xy 119.5451 -56.896) (xy 119.3419 -56.896) (xy 119.3419 -57.0992) (xy 119.5451 -57.0992)
			)
		)
		(polygon
			(pts
				(xy 119.1895 -56.896) (xy 118.7069 -56.896) (xy 118.7069 -57.0992) (xy 119.1895 -57.0992)
			)
		)
		(polygon
			(pts
				(xy 118.5545 -56.896) (xy 118.3513 -56.896) (xy 118.3513 -57.0992) (xy 118.5545 -57.0992)
			)
		)
		(polygon
			(pts
				(xy 117.5385 -56.896) (xy 117.3353 -56.896) (xy 117.3353 -57.0992) (xy 117.5385 -57.0992)
			)
		)
		(polygon
			(pts
				(xy 117.1829 -56.896) (xy 116.7003 -56.896) (xy 116.7003 -57.0992) (xy 117.1829 -57.0992)
			)
		)
		(polygon
			(pts
				(xy 116.5479 -56.896) (xy 116.3447 -56.896) (xy 116.3447 -57.0992) (xy 116.5479 -57.0992)
			)
		)
		(polygon
			(pts
				(xy 115.6335 -56.896) (xy 115.4303 -56.896) (xy 115.4303 -57.0992) (xy 115.6335 -57.0992)
			)
		)
		(polygon
			(pts
				(xy 115.2779 -56.896) (xy 114.7953 -56.896) (xy 114.7953 -57.0992) (xy 115.2779 -57.0992)
			)
		)
		(polygon
			(pts
				(xy 114.6429 -56.896) (xy 114.4397 -56.896) (xy 114.4397 -57.0992) (xy 114.6429 -57.0992)
			)
		)
		(polygon
			(pts
				(xy 113.538 -56.896) (xy 113.3348 -56.896) (xy 113.3348 -57.0992) (xy 113.538 -57.0992)
			)
		)
		(polygon
			(pts
				(xy 113.1824 -56.896) (xy 112.6998 -56.896) (xy 112.6998 -57.0992) (xy 113.1824 -57.0992)
			)
		)
		(polygon
			(pts
				(xy 112.5474 -56.896) (xy 112.3442 -56.896) (xy 112.3442 -57.0992) (xy 112.5474 -57.0992)
			)
		)
		(polygon
			(pts
				(xy 111.5568 -56.896) (xy 111.3536 -56.896) (xy 111.3536 -57.0992) (xy 111.5568 -57.0992)
			)
		)
		(polygon
			(pts
				(xy 111.2012 -56.896) (xy 110.7186 -56.896) (xy 110.7186 -57.0992) (xy 111.2012 -57.0992)
			)
		)
		(polygon
			(pts
				(xy 110.5662 -56.896) (xy 110.363 -56.896) (xy 110.363 -57.0992) (xy 110.5662 -57.0992)
			)
		)
		(polygon
			(pts
				(xy 109.5502 -56.896) (xy 109.347 -56.896) (xy 109.347 -57.0992) (xy 109.5502 -57.0992)
			)
		)
		(polygon
			(pts
				(xy 109.1946 -56.896) (xy 108.712 -56.896) (xy 108.712 -57.0992) (xy 109.1946 -57.0992)
			)
		)
		(polygon
			(pts
				(xy 108.5596 -56.896) (xy 108.3564 -56.896) (xy 108.3564 -57.0992) (xy 108.5596 -57.0992)
			)
		)
		(polygon
			(pts
				(xy 107.7722 -56.896) (xy 107.569 -56.896) (xy 107.569 -57.0992) (xy 107.7722 -57.0992)
			)
		)
		(polygon
			(pts
				(xy 107.4166 -56.896) (xy 106.934 -56.896) (xy 106.934 -57.0992) (xy 107.4166 -57.0992)
			)
		)
		(polygon
			(pts
				(xy 106.7816 -56.896) (xy 106.5784 -56.896) (xy 106.5784 -57.0992) (xy 106.7816 -57.0992)
			)
		)
	)
	(zone
		(layer "B.Cu")
		(hatch none 0.5)
		(connect_pads
			(clearance 0)
		)
		(min_thickness 0.25)
		(keepout
			(tracks allowed)
			(vias allowed)
			(pads allowed)
			(copperpour allowed)
			(footprints not_allowed)
		)
		(placement
			(enabled no)
			(sheetname "")
		)
		(fill
			(thermal_gap 0.5)
			(thermal_bridge_width 0.5)
			(island_removal_mode 0)
		)
		(polygon
			(pts
				(arc
					(start 92.00007 -39.67988)
					(mid 95.000064 -42.679874)
					(end 98.000058 -39.67988)
				)
				(arc
					(start 98.000058 -39.67988)
					(mid 95.000064 -36.679886)
					(end 92.00007 -39.67988)
				)
			)
		)
	)
	(zone
		(net "AGND_CURRENT_MON")
		(layer "B.Cu")
		(hatch none 0.5)
		(connect_pads
			(clearance 0.5)
		)
		(min_thickness 0.25)
		(fill yes
			(thermal_gap 0.5)
			(thermal_bridge_width 0.5)
			(island_removal_mode 0)
		)
		(polygon
			(pts
				(xy 12.35202 -51.714654) (xy 12.20851 -51.858164) (xy 12.20851 -52.18049) (xy 11.938 -52.451) (xy 11.0744 -52.451)
				(xy 10.922 -52.6034) (xy 10.922 -53.63718) (xy 12.348718 -55.063898) (xy 15.383256 -55.063898) (xy 15.640812 -54.806342)
				(xy 15.640812 -51.931062) (xy 15.424404 -51.714654)
			)
		)
	)
	(zone
		(net "GND")
		(layer "B.Cu")
		(hatch none 0.5)
		(connect_pads
			(clearance 0.5)
		)
		(min_thickness 0.25)
		(fill yes
			(thermal_gap 0.5)
			(thermal_bridge_width 0.5)
			(island_removal_mode 0)
		)
		(polygon
			(pts
				(xy 48.632872 -40.481758) (xy 48.3362 -40.77843) (xy 48.3362 -53.6448) (xy 48.5013 -53.8099) (xy 51.4223 -53.8099)
				(xy 51.816 -53.4162) (xy 51.816 -40.73525) (xy 51.562508 -40.481758)
			)
		)
	)
	(zone
		(layer "B.Cu")
		(hatch none 0.5)
		(connect_pads
			(clearance 0)
		)
		(min_thickness 0.25)
		(keepout
			(tracks not_allowed)
			(vias allowed)
			(pads allowed)
			(copperpour not_allowed)
			(footprints allowed)
		)
		(placement
			(enabled no)
			(sheetname "")
		)
		(fill
			(thermal_gap 0.5)
			(thermal_bridge_width 0.5)
			(island_removal_mode 0)
		)
		(polygon
			(pts
				(arc
					(start 101.358192 -55.000144)
					(mid 101.000052 -54.642004)
					(end 100.641912 -55.000144)
				)
				(xy 100.641912 -55.34787)
				(arc
					(start 100.911152 -55.34787)
					(mid 100.933603 -55.338571)
					(end 100.942902 -55.31612)
				)
				(arc
					(start 100.942902 -55.234586)
					(mid 101.000052 -54.758837)
					(end 101.057202 -55.234586)
				)
				(xy 101.057202 -55.339742)
				(arc
					(start 101.054916 -55.342028)
					(mid 101.014446 -55.419414)
					(end 100.93706 -55.459884)
				)
				(xy 100.934774 -55.46217) (xy 100.641912 -55.46217) (xy 100.641912 -55.53837) (xy 100.934774 -55.53837)
				(arc
					(start 100.93706 -55.540656)
					(mid 101.014446 -55.581126)
					(end 101.054916 -55.658512)
				)
				(xy 101.057202 -55.660798)
				(arc
					(start 101.057202 -55.7657)
					(mid 101.000052 -56.241449)
					(end 100.942902 -55.7657)
				)
				(arc
					(start 100.942902 -55.68442)
					(mid 100.933603 -55.661969)
					(end 100.911152 -55.65267)
				)
				(xy 100.641912 -55.65267)
				(arc
					(start 100.641912 -55.999888)
					(mid 100.999925 -56.358282)
					(end 101.358192 -56.000142)
				)
			)
		)
	)
	(zone
		(layer "B.Cu")
		(hatch none 0.5)
		(connect_pads
			(clearance 0)
		)
		(min_thickness 0.25)
		(keepout
			(tracks not_allowed)
			(vias allowed)
			(pads allowed)
			(copperpour not_allowed)
			(footprints allowed)
		)
		(placement
			(enabled no)
			(sheetname "")
		)
		(fill
			(thermal_gap 0.5)
			(thermal_bridge_width 0.5)
			(island_removal_mode 0)
		)
		(polygon
			(pts
				(arc
					(start 126.000256 -73.641966)
					(mid 125.641862 -73.999979)
					(end 126.000002 -74.358246)
				)
				(arc
					(start 126.383034 -74.358246)
					(mid 126.358901 -74.281752)
					(end 126.347982 -74.20229)
				)
				(xy 126.347474 -74.201528)
				(arc
					(start 126.347474 -74.089006)
					(mid 126.338175 -74.066555)
					(end 126.315724 -74.057256)
				)
				(arc
					(start 126.234444 -74.057256)
					(mid 125.758695 -74.000106)
					(end 126.234444 -73.942956)
				)
				(xy 126.339346 -73.942956)
				(arc
					(start 126.341632 -73.945242)
					(mid 126.419018 -73.985712)
					(end 126.459488 -74.063098)
				)
				(xy 126.461774 -74.065384)
				(arc
					(start 126.461774 -74.177906)
					(mid 126.474044 -74.271251)
					(end 126.510034 -74.358246)
				)
				(arc
					(start 126.602236 -74.358246)
					(mid 126.558881 -74.285161)
					(end 126.53899 -74.202544)
				)
				(xy 126.537974 -74.201528) (xy 126.537974 -74.065384)
				(arc
					(start 126.54026 -74.063098)
					(mid 126.58073 -73.985712)
					(end 126.658116 -73.945242)
				)
				(xy 126.660402 -73.942956)
				(arc
					(start 126.765558 -73.942956)
					(mid 127.241307 -74.000106)
					(end 126.765558 -74.057256)
				)
				(arc
					(start 126.684024 -74.057256)
					(mid 126.661573 -74.066555)
					(end 126.652274 -74.089006)
				)
				(arc
					(start 126.652274 -74.177906)
					(mid 126.702267 -74.298601)
					(end 126.822962 -74.348594)
				)
				(arc
					(start 127.08255 -74.348594)
					(mid 127.355713 -73.95855)
					(end 127 -73.641966)
				)
			)
		)
	)
	(zone
		(net "GND")
		(layer "B.Cu")
		(hatch none 0.5)
		(connect_pads
			(clearance 0.5)
		)
		(min_thickness 0.25)
		(fill yes
			(thermal_gap 0.5)
			(thermal_bridge_width 0.5)
			(island_removal_mode 0)
		)
		(polygon
			(pts
				(xy 166.8526 -32.3342) (xy 166.7002 -32.4866) (xy 166.7002 -33.0454) (xy 166.8526 -33.1978) (xy 167.1574 -33.1978)
				(xy 167.386 -33.4264) (xy 167.386 -33.8328) (xy 167.4876 -33.9344) (xy 168.0464 -33.9344) (xy 168.148 -33.8328)
				(xy 168.148 -32.4358) (xy 168.0464 -32.3342)
			)
		)
		(polygon
			(pts
				(xy 167.5892 -32.8803) (xy 167.386 -32.8803) (xy 167.386 -33.0835) (xy 167.5892 -33.0835)
			)
		)
	)
	(zone
		(layer "B.Cu")
		(hatch none 0.5)
		(connect_pads
			(clearance 0)
		)
		(min_thickness 0.25)
		(keepout
			(tracks not_allowed)
			(vias allowed)
			(pads allowed)
			(copperpour not_allowed)
			(footprints allowed)
		)
		(placement
			(enabled no)
			(sheetname "")
		)
		(fill
			(thermal_gap 0.5)
			(thermal_bridge_width 0.5)
			(island_removal_mode 0)
		)
		(polygon
			(pts
				(arc
					(start 79.749904 -134.999984)
					(mid 75.000104 -130.250184)
					(end 70.25005 -134.999984)
				)
				(arc
					(start 70.25005 -134.999984)
					(mid 75.000104 -139.750038)
					(end 79.749904 -134.999984)
				)
			)
		)
	)
	(zone
		(net "GND")
		(layer "B.Cu")
		(hatch none 0.5)
		(connect_pads
			(clearance 0.5)
		)
		(min_thickness 0.25)
		(fill yes
			(thermal_gap 0.5)
			(thermal_bridge_width 0.5)
			(island_removal_mode 0)
		)
		(polygon
			(pts
				(xy 60.1091 -98.8568) (xy 60.0075 -98.9584) (xy 60.0075 -101.9683) (xy 60.1472 -102.108) (xy 66.8655 -102.108)
				(xy 67.0052 -101.9683) (xy 67.0052 -99.0854) (xy 66.7766 -98.8568)
			)
		)
	)
	(zone
		(layer "B.Cu")
		(hatch none 0.5)
		(connect_pads
			(clearance 0)
		)
		(min_thickness 0.25)
		(keepout
			(tracks allowed)
			(vias allowed)
			(pads allowed)
			(copperpour allowed)
			(footprints not_allowed)
		)
		(placement
			(enabled no)
			(sheetname "")
		)
		(fill
			(thermal_gap 0.5)
			(thermal_bridge_width 0.5)
			(island_removal_mode 0)
		)
		(polygon
			(pts
				(arc
					(start 201.499978 -50.500026)
					(mid 198.499984 -47.500032)
					(end 195.49999 -50.500026)
				)
				(arc
					(start 195.49999 -50.500026)
					(mid 198.499984 -53.50002)
					(end 201.499978 -50.500026)
				)
			)
		)
	)
	(zone
		(layer "B.Cu")
		(hatch none 0.5)
		(connect_pads
			(clearance 0)
		)
		(min_thickness 0.25)
		(keepout
			(tracks not_allowed)
			(vias allowed)
			(pads allowed)
			(copperpour not_allowed)
			(footprints allowed)
		)
		(placement
			(enabled no)
			(sheetname "")
		)
		(fill
			(thermal_gap 0.5)
			(thermal_bridge_width 0.5)
			(island_removal_mode 0)
		)
		(polygon
			(pts
				(arc
					(start 97.361502 -3.800094)
					(mid 96.800162 -3.238754)
					(end 96.238822 -3.800094)
				)
				(arc
					(start 96.238822 -4.228592)
					(mid 96.271775 -4.224914)
					(end 96.304862 -4.22275)
				)
				(xy 96.305624 -4.221988)
				(arc
					(start 96.681036 -4.221988)
					(mid 96.697949 -4.218624)
					(end 96.712278 -4.209034)
				)
				(arc
					(start 96.712278 -4.209034)
					(mid 96.720044 -4.198635)
					(end 96.72447 -4.186428)
				)
				(arc
					(start 96.72447 -4.186428)
					(mid 96.801064 -3.406367)
					(end 96.875092 -4.186682)
				)
				(xy 96.875092 -4.20878)
				(arc
					(start 96.872044 -4.211828)
					(mid 96.853113 -4.267359)
					(end 96.81845 -4.314698)
				)
				(arc
					(start 96.81845 -4.314698)
					(mid 96.770934 -4.349728)
					(end 96.715072 -4.3688)
				)
				(xy 96.712024 -4.371848)
				(arc
					(start 96.336612 -4.371848)
					(mid 96.287535 -4.373923)
					(end 96.238822 -4.38023)
				)
				(arc
					(start 96.238822 -4.644136)
					(mid 96.270963 -4.635425)
					(end 96.303846 -4.630166)
				)
				(xy 96.305624 -4.628388) (xy 96.712024 -4.628388)
				(arc
					(start 96.715072 -4.631436)
					(mid 96.770921 -4.650533)
					(end 96.81845 -4.685538)
				)
				(arc
					(start 96.81845 -4.685538)
					(mid 96.853138 -4.732864)
					(end 96.872044 -4.788408)
				)
				(xy 96.875092 -4.791456)
				(arc
					(start 96.875092 -4.813554)
					(mid 96.801064 -5.593876)
					(end 96.72447 -4.813808)
				)
				(arc
					(start 96.72447 -4.813808)
					(mid 96.720072 -4.801586)
					(end 96.712278 -4.791202)
				)
				(arc
					(start 96.712278 -4.791202)
					(mid 96.697944 -4.781624)
					(end 96.681036 -4.778248)
				)
				(arc
					(start 96.336612 -4.778248)
					(mid 96.285086 -4.786589)
					(end 96.238822 -4.81076)
				)
				(arc
					(start 96.238822 -5.199888)
					(mid 96.800035 -5.761482)
					(end 97.361502 -5.200142)
				)
			)
		)
	)
	(zone
		(layer "B.Cu")
		(hatch none 0.5)
		(connect_pads
			(clearance 0)
		)
		(min_thickness 0.25)
		(keepout
			(tracks not_allowed)
			(vias allowed)
			(pads allowed)
			(copperpour not_allowed)
			(footprints allowed)
		)
		(placement
			(enabled no)
			(sheetname "")
		)
		(fill
			(thermal_gap 0.5)
			(thermal_bridge_width 0.5)
			(island_removal_mode 0)
		)
		(polygon
			(pts
				(arc
					(start 144.16151 -3.800094)
					(mid 143.60017 -3.238754)
					(end 143.03883 -3.800094)
				)
				(arc
					(start 143.03883 -4.228592)
					(mid 143.071782 -4.224901)
					(end 143.10487 -4.22275)
				)
				(xy 143.105632 -4.221988)
				(arc
					(start 143.481044 -4.221988)
					(mid 143.497957 -4.218624)
					(end 143.512286 -4.209034)
				)
				(arc
					(start 143.512286 -4.209034)
					(mid 143.520052 -4.198635)
					(end 143.524478 -4.186428)
				)
				(arc
					(start 143.524478 -4.186428)
					(mid 143.601072 -3.406367)
					(end 143.6751 -4.186682)
				)
				(xy 143.6751 -4.20878)
				(arc
					(start 143.672052 -4.211828)
					(mid 143.653121 -4.267359)
					(end 143.618458 -4.314698)
				)
				(arc
					(start 143.618458 -4.314698)
					(mid 143.570942 -4.349728)
					(end 143.51508 -4.3688)
				)
				(xy 143.512032 -4.371848)
				(arc
					(start 143.13662 -4.371848)
					(mid 143.087536 -4.37403)
					(end 143.03883 -4.380484)
				)
				(arc
					(start 143.03883 -4.64439)
					(mid 143.070955 -4.635509)
					(end 143.103854 -4.630166)
				)
				(xy 143.105632 -4.628388) (xy 143.512032 -4.628388)
				(arc
					(start 143.51508 -4.631436)
					(mid 143.570929 -4.650533)
					(end 143.618458 -4.685538)
				)
				(arc
					(start 143.618458 -4.685538)
					(mid 143.653146 -4.732864)
					(end 143.672052 -4.788408)
				)
				(xy 143.6751 -4.791456)
				(arc
					(start 143.6751 -4.813554)
					(mid 143.601072 -5.593876)
					(end 143.524478 -4.813808)
				)
				(arc
					(start 143.524478 -4.813808)
					(mid 143.52008 -4.801586)
					(end 143.512286 -4.791202)
				)
				(arc
					(start 143.512286 -4.791202)
					(mid 143.497952 -4.781624)
					(end 143.481044 -4.778248)
				)
				(arc
					(start 143.13662 -4.778248)
					(mid 143.084887 -4.786928)
					(end 143.03883 -4.81203)
				)
				(arc
					(start 143.03883 -5.199888)
					(mid 143.600043 -5.761482)
					(end 144.16151 -5.200142)
				)
			)
		)
	)
	(zone
		(layer "B.Cu")
		(hatch none 0.5)
		(connect_pads
			(clearance 0)
		)
		(min_thickness 0.25)
		(keepout
			(tracks allowed)
			(vias allowed)
			(pads allowed)
			(copperpour allowed)
			(footprints not_allowed)
		)
		(placement
			(enabled no)
			(sheetname "")
		)
		(fill
			(thermal_gap 0.5)
			(thermal_bridge_width 0.5)
			(island_removal_mode 0)
		)
		(polygon
			(pts
				(arc
					(start 4.99999 -139.224258)
					(mid 18.50018 -131.430014)
					(end 4.99999 -123.63577)
				)
				(xy 4.99999 -105.000044) (xy 19.99996 -105.000044) (xy 19.99996 -125.000004) (xy 85.002624 -125.000004)
				(xy 85.002624 -119.000016) (xy 125.002544 -119.000016) (xy 125.002544 -125.000004) (xy 189.999874 -125.000004)
				(xy 189.999874 -105.000044) (xy 205.000098 -105.000044)
				(arc
					(start 205.000098 -123.63577)
					(mid 191.499908 -131.430014)
					(end 205.000098 -139.224258)
				)
				(xy 205.000098 -144.999964)
				(arc
					(start 127.00254 -144.999964)
					(mid 125.588329 -144.414179)
					(end 125.002544 -142.999968)
				)
				(arc
					(start 125.002544 -132.263642)
					(mid 123.807045 -129.019301)
					(end 120.79224 -127.32639)
				)
				(xy 112.499902 -126.000002) (xy 97.499932 -126.000002)
				(arc
					(start 89.212674 -127.325628)
					(mid 86.197998 -129.018598)
					(end 85.002624 -132.26288)
				)
				(arc
					(start 85.002624 -142.999968)
					(mid 84.416749 -144.414269)
					(end 83.002374 -144.999964)
				)
				(xy 4.99999 -144.999964)
			)
		)
	)
	(zone
		(layer "B.Cu")
		(hatch none 0.5)
		(connect_pads
			(clearance 0)
		)
		(min_thickness 0.25)
		(keepout
			(tracks not_allowed)
			(vias allowed)
			(pads allowed)
			(copperpour not_allowed)
			(footprints allowed)
		)
		(placement
			(enabled no)
			(sheetname "")
		)
		(fill
			(thermal_gap 0.5)
			(thermal_bridge_width 0.5)
			(island_removal_mode 0)
		)
		(polygon
			(pts
				(arc
					(start 147.761452 -3.800094)
					(mid 147.200112 -3.238754)
					(end 146.638772 -3.800094)
				)
				(arc
					(start 146.638772 -4.228592)
					(mid 146.671724 -4.224901)
					(end 146.704812 -4.22275)
				)
				(xy 146.705574 -4.221988)
				(arc
					(start 147.080986 -4.221988)
					(mid 147.097899 -4.218624)
					(end 147.112228 -4.209034)
				)
				(arc
					(start 147.112228 -4.209034)
					(mid 147.119994 -4.198635)
					(end 147.12442 -4.186428)
				)
				(arc
					(start 147.12442 -4.186428)
					(mid 147.201014 -3.406367)
					(end 147.275042 -4.186682)
				)
				(xy 147.275042 -4.20878)
				(arc
					(start 147.271994 -4.211828)
					(mid 147.253063 -4.267359)
					(end 147.2184 -4.314698)
				)
				(arc
					(start 147.2184 -4.314698)
					(mid 147.170884 -4.349728)
					(end 147.115022 -4.3688)
				)
				(xy 147.111974 -4.371848)
				(arc
					(start 146.736562 -4.371848)
					(mid 146.687478 -4.37403)
					(end 146.638772 -4.380484)
				)
				(arc
					(start 146.638772 -4.64439)
					(mid 146.670897 -4.635509)
					(end 146.703796 -4.630166)
				)
				(xy 146.705574 -4.628388) (xy 147.111974 -4.628388)
				(arc
					(start 147.115022 -4.631436)
					(mid 147.170871 -4.650533)
					(end 147.2184 -4.685538)
				)
				(arc
					(start 147.2184 -4.685538)
					(mid 147.253088 -4.732864)
					(end 147.271994 -4.788408)
				)
				(xy 147.275042 -4.791456)
				(arc
					(start 147.275042 -4.813554)
					(mid 147.201014 -5.593876)
					(end 147.12442 -4.813808)
				)
				(arc
					(start 147.12442 -4.813808)
					(mid 147.120022 -4.801586)
					(end 147.112228 -4.791202)
				)
				(arc
					(start 147.112228 -4.791202)
					(mid 147.097894 -4.781624)
					(end 147.080986 -4.778248)
				)
				(arc
					(start 146.736562 -4.778248)
					(mid 146.684829 -4.786928)
					(end 146.638772 -4.81203)
				)
				(arc
					(start 146.638772 -5.199888)
					(mid 147.199985 -5.761482)
					(end 147.761452 -5.200142)
				)
			)
		)
	)
	(zone
		(layer "B.Cu")
		(hatch none 0.5)
		(connect_pads
			(clearance 0)
		)
		(min_thickness 0.25)
		(keepout
			(tracks allowed)
			(vias allowed)
			(pads allowed)
			(copperpour allowed)
			(footprints not_allowed)
		)
		(placement
			(enabled no)
			(sheetname "")
		)
		(fill
			(thermal_gap 0.5)
			(thermal_bridge_width 0.5)
			(island_removal_mode 0)
		)
		(polygon
			(pts
				(arc
					(start 210.000088 -1.999996)
					(mid 209.414303 -0.585785)
					(end 208.000092 0)
				)
				(xy 205.000098 0) (xy 205.000098 -144.999964)
				(arc
					(start 208.000092 -144.999964)
					(mid 209.414303 -144.414179)
					(end 210.000088 -142.999968)
				)
			)
		)
	)
	(zone
		(net "GND")
		(layer "B.Cu")
		(hatch none 0.5)
		(connect_pads
			(clearance 0.5)
		)
		(min_thickness 0.25)
		(fill yes
			(thermal_gap 0.5)
			(thermal_bridge_width 0.5)
			(island_removal_mode 0)
		)
		(polygon
			(pts
				(xy 114.2746 -87.199978) (xy 114.2492 -87.225378) (xy 114.2492 -88.003126) (xy 113.3348 -88.917526)
				(xy 111.713772 -88.917526) (xy 111.542322 -89.088976) (xy 111.542322 -90.587322) (xy 111.7092 -90.7542)
				(xy 114.651536 -90.7542) (xy 114.7826 -90.623136) (xy 114.7826 -87.250778) (xy 114.7318 -87.199978)
			)
		)
		(polygon
			(pts
				(xy 114.335814 -89.49436) (xy 114.132614 -89.49436) (xy 114.132614 -89.69756) (xy 114.335814 -89.69756)
			)
		)
		(polygon
			(pts
				(xy 112.188244 -89.418414) (xy 111.985044 -89.418414) (xy 111.985044 -89.621614) (xy 112.188244 -89.621614)
			)
		)
		(polygon
			(pts
				(xy 114.335814 -88.93556) (xy 114.132614 -88.93556) (xy 114.132614 -89.13876) (xy 114.335814 -89.13876)
			)
		)
	)
	(zone
		(layer "B.Cu")
		(hatch none 0.5)
		(connect_pads
			(clearance 0)
		)
		(min_thickness 0.25)
		(keepout
			(tracks not_allowed)
			(vias allowed)
			(pads allowed)
			(copperpour not_allowed)
			(footprints allowed)
		)
		(placement
			(enabled no)
			(sheetname "")
		)
		(fill
			(thermal_gap 0.5)
			(thermal_bridge_width 0.5)
			(island_removal_mode 0)
		)
		(polygon
			(pts
				(arc
					(start 126.000256 -60.641992)
					(mid 125.641862 -61.000005)
					(end 126.000002 -61.358272)
				)
				(arc
					(start 127 -61.358272)
					(mid 127.355913 -61.040005)
					(end 127.079248 -60.650882)
				)
				(arc
					(start 126.751334 -60.650882)
					(mid 126.681288 -60.679896)
					(end 126.652274 -60.749942)
				)
				(arc
					(start 126.652274 -60.900056)
					(mid 126.664847 -60.930409)
					(end 126.6952 -60.942982)
				)
				(arc
					(start 126.765558 -60.942982)
					(mid 127.241307 -61.000132)
					(end 126.765558 -61.057282)
				)
				(xy 126.671578 -61.057282)
				(arc
					(start 126.669292 -61.05525)
					(mid 126.583943 -61.011313)
					(end 126.540006 -60.925964)
				)
				(xy 126.537974 -60.923678) (xy 126.537974 -60.72632)
				(arc
					(start 126.539498 -60.724796)
					(mid 126.549076 -60.68197)
					(end 126.567184 -60.641992)
				)
				(arc
					(start 126.482602 -60.641992)
					(mid 126.466996 -60.694967)
					(end 126.461774 -60.749942)
				)
				(xy 126.461774 -60.923932)
				(arc
					(start 126.459742 -60.926218)
					(mid 126.415882 -61.01139)
					(end 126.33071 -61.05525)
				)
				(xy 126.328424 -61.057282)
				(arc
					(start 126.234444 -61.057282)
					(mid 125.758695 -61.000132)
					(end 126.234444 -60.942982)
				)
				(arc
					(start 126.304802 -60.942982)
					(mid 126.334976 -60.930484)
					(end 126.347474 -60.90031)
				)
				(xy 126.347474 -60.72632)
				(arc
					(start 126.348236 -60.725558)
					(mid 126.353018 -60.683406)
					(end 126.362206 -60.641992)
				)
			)
		)
	)
	(zone
		(layer "B.Cu")
		(hatch none 0.5)
		(connect_pads
			(clearance 0)
		)
		(min_thickness 0.25)
		(keepout
			(tracks not_allowed)
			(vias allowed)
			(pads allowed)
			(copperpour not_allowed)
			(footprints allowed)
		)
		(placement
			(enabled no)
			(sheetname "")
		)
		(fill
			(thermal_gap 0.5)
			(thermal_bridge_width 0.5)
			(island_removal_mode 0)
		)
		(polygon
			(pts
				(arc
					(start 86.561422 -3.800094)
					(mid 86.000082 -3.238754)
					(end 85.438742 -3.800094)
				)
				(arc
					(start 85.438742 -4.22783)
					(mid 85.471708 -4.224494)
					(end 85.504782 -4.222496)
				)
				(xy 85.505544 -4.221988)
				(arc
					(start 85.880956 -4.221988)
					(mid 85.897869 -4.218624)
					(end 85.912198 -4.209034)
				)
				(arc
					(start 85.912198 -4.209034)
					(mid 85.919964 -4.198635)
					(end 85.92439 -4.186428)
				)
				(arc
					(start 85.92439 -4.186428)
					(mid 86.000984 -3.406367)
					(end 86.075012 -4.186682)
				)
				(xy 86.075012 -4.20878)
				(arc
					(start 86.071964 -4.211828)
					(mid 86.053033 -4.267359)
					(end 86.01837 -4.314698)
				)
				(arc
					(start 86.01837 -4.314698)
					(mid 85.970854 -4.349728)
					(end 85.914992 -4.3688)
				)
				(xy 85.911944 -4.371848)
				(arc
					(start 85.536532 -4.371848)
					(mid 85.487506 -4.373601)
					(end 85.438742 -4.37896)
				)
				(arc
					(start 85.438742 -4.640326)
					(mid 85.47129 -4.633653)
					(end 85.504274 -4.629658)
				)
				(xy 85.505544 -4.628388) (xy 85.911944 -4.628388)
				(arc
					(start 85.914992 -4.631436)
					(mid 85.970841 -4.650533)
					(end 86.01837 -4.685538)
				)
				(arc
					(start 86.01837 -4.685538)
					(mid 86.053058 -4.732864)
					(end 86.071964 -4.788408)
				)
				(xy 86.075012 -4.791456)
				(arc
					(start 86.075012 -4.813554)
					(mid 86.000984 -5.593876)
					(end 85.92439 -4.813808)
				)
				(arc
					(start 85.92439 -4.813808)
					(mid 85.919992 -4.801586)
					(end 85.912198 -4.791202)
				)
				(arc
					(start 85.912198 -4.791202)
					(mid 85.897864 -4.781624)
					(end 85.880956 -4.778248)
				)
				(arc
					(start 85.536532 -4.778248)
					(mid 85.486697 -4.783141)
					(end 85.438742 -4.797552)
				)
				(arc
					(start 85.438742 -5.199888)
					(mid 85.999955 -5.761482)
					(end 86.561422 -5.200142)
				)
			)
		)
	)
	(zone
		(layer "B.Cu")
		(hatch none 0.5)
		(connect_pads
			(clearance 0)
		)
		(min_thickness 0.25)
		(keepout
			(tracks not_allowed)
			(vias allowed)
			(pads allowed)
			(copperpour not_allowed)
			(footprints allowed)
		)
		(placement
			(enabled no)
			(sheetname "")
		)
		(fill
			(thermal_gap 0.5)
			(thermal_bridge_width 0.5)
			(island_removal_mode 0)
		)
		(polygon
			(pts
				(arc
					(start 104.561386 -3.800094)
					(mid 104.000046 -3.238754)
					(end 103.438706 -3.800094)
				)
				(arc
					(start 103.438706 -4.228592)
					(mid 103.471658 -4.224901)
					(end 103.504746 -4.22275)
				)
				(xy 103.505508 -4.221988)
				(arc
					(start 103.88092 -4.221988)
					(mid 103.897833 -4.218624)
					(end 103.912162 -4.209034)
				)
				(arc
					(start 103.912162 -4.209034)
					(mid 103.919928 -4.198635)
					(end 103.924354 -4.186428)
				)
				(arc
					(start 103.924354 -4.186428)
					(mid 104.000948 -3.406367)
					(end 104.074976 -4.186682)
				)
				(xy 104.074976 -4.20878)
				(arc
					(start 104.071928 -4.211828)
					(mid 104.052997 -4.267359)
					(end 104.018334 -4.314698)
				)
				(arc
					(start 104.018334 -4.314698)
					(mid 103.970818 -4.349728)
					(end 103.914956 -4.3688)
				)
				(xy 103.911908 -4.371848)
				(arc
					(start 103.536496 -4.371848)
					(mid 103.487412 -4.37403)
					(end 103.438706 -4.380484)
				)
				(arc
					(start 103.438706 -4.64439)
					(mid 103.470831 -4.635509)
					(end 103.50373 -4.630166)
				)
				(xy 103.505508 -4.628388) (xy 103.911908 -4.628388)
				(arc
					(start 103.914956 -4.631436)
					(mid 103.970805 -4.650533)
					(end 104.018334 -4.685538)
				)
				(arc
					(start 104.018334 -4.685538)
					(mid 104.053022 -4.732864)
					(end 104.071928 -4.788408)
				)
				(xy 104.074976 -4.791456)
				(arc
					(start 104.074976 -4.813554)
					(mid 104.000948 -5.593876)
					(end 103.924354 -4.813808)
				)
				(arc
					(start 103.924354 -4.813808)
					(mid 103.919956 -4.801586)
					(end 103.912162 -4.791202)
				)
				(arc
					(start 103.912162 -4.791202)
					(mid 103.897828 -4.781624)
					(end 103.88092 -4.778248)
				)
				(arc
					(start 103.536496 -4.778248)
					(mid 103.484763 -4.786928)
					(end 103.438706 -4.81203)
				)
				(arc
					(start 103.438706 -5.199888)
					(mid 103.999919 -5.761482)
					(end 104.561386 -5.200142)
				)
			)
		)
	)
	(zone
		(layer "B.Cu")
		(hatch none 0.5)
		(connect_pads
			(clearance 0)
		)
		(min_thickness 0.25)
		(keepout
			(tracks not_allowed)
			(vias allowed)
			(pads allowed)
			(copperpour not_allowed)
			(footprints allowed)
		)
		(placement
			(enabled no)
			(sheetname "")
		)
		(fill
			(thermal_gap 0.5)
			(thermal_bridge_width 0.5)
			(island_removal_mode 0)
		)
		(polygon
			(pts
				(arc
					(start 117.16131 -2.600198)
					(mid 116.59997 -2.038858)
					(end 116.03863 -2.600198)
				)
				(arc
					(start 116.03863 -3.028442)
					(mid 116.071582 -3.024751)
					(end 116.10467 -3.0226)
				)
				(xy 116.105432 -3.021838)
				(arc
					(start 116.480844 -3.021838)
					(mid 116.497757 -3.018474)
					(end 116.512086 -3.008884)
				)
				(arc
					(start 116.512086 -3.008884)
					(mid 116.519683 -2.99858)
					(end 116.524024 -2.986532)
				)
				(arc
					(start 116.524024 -2.986532)
					(mid 116.600996 -2.206422)
					(end 116.6749 -2.986786)
				)
				(xy 116.6749 -3.00863)
				(arc
					(start 116.671852 -3.011678)
					(mid 116.652921 -3.067209)
					(end 116.618258 -3.114548)
				)
				(arc
					(start 116.618258 -3.114548)
					(mid 116.570742 -3.149578)
					(end 116.51488 -3.16865)
				)
				(xy 116.511832 -3.171698)
				(arc
					(start 116.13642 -3.171698)
					(mid 116.087336 -3.17388)
					(end 116.03863 -3.180334)
				)
				(arc
					(start 116.03863 -3.44424)
					(mid 116.070755 -3.435359)
					(end 116.103654 -3.430016)
				)
				(xy 116.105432 -3.428238) (xy 116.511832 -3.428238)
				(arc
					(start 116.51488 -3.431286)
					(mid 116.570729 -3.450383)
					(end 116.618258 -3.485388)
				)
				(arc
					(start 116.618258 -3.485388)
					(mid 116.652946 -3.532714)
					(end 116.671852 -3.588258)
				)
				(xy 116.6749 -3.591306)
				(arc
					(start 116.6749 -3.613404)
					(mid 116.600872 -4.393726)
					(end 116.524278 -3.613658)
				)
				(arc
					(start 116.524278 -3.613658)
					(mid 116.51988 -3.601436)
					(end 116.512086 -3.591052)
				)
				(arc
					(start 116.512086 -3.591052)
					(mid 116.497752 -3.581474)
					(end 116.480844 -3.578098)
				)
				(arc
					(start 116.13642 -3.578098)
					(mid 116.084687 -3.586778)
					(end 116.03863 -3.61188)
				)
				(arc
					(start 116.03863 -3.999738)
					(mid 116.599843 -4.561332)
					(end 117.16131 -3.999992)
				)
			)
		)
	)
	(zone
		(layer "B.Cu")
		(hatch none 0.5)
		(connect_pads
			(clearance 0)
		)
		(min_thickness 0.25)
		(keepout
			(tracks allowed)
			(vias allowed)
			(pads allowed)
			(copperpour allowed)
			(footprints not_allowed)
		)
		(placement
			(enabled no)
			(sheetname "")
		)
		(fill
			(thermal_gap 0.5)
			(thermal_bridge_width 0.5)
			(island_removal_mode 0)
		)
		(polygon
			(pts
				(arc
					(start 205.000098 -123.63577)
					(mid 191.499908 -131.430014)
					(end 205.000098 -139.224258)
				)
			)
		)
	)
	(zone
		(net "GND")
		(layer "B.Cu")
		(hatch none 0.5)
		(connect_pads
			(clearance 0.5)
		)
		(min_thickness 0.25)
		(fill yes
			(thermal_gap 0.5)
			(thermal_bridge_width 0.5)
			(island_removal_mode 0)
		)
		(polygon
			(pts
				(xy 166.6113 -6.8326) (xy 166.4716 -6.9723) (xy 166.4716 -8.1534) (xy 166.5478 -8.2296) (xy 167.8432 -8.2296)
				(xy 167.9321 -8.1407) (xy 167.9321 -7.493) (xy 167.2717 -6.8326)
			)
		)
	)
	(zone
		(layer "B.Cu")
		(hatch none 0.5)
		(connect_pads
			(clearance 0)
		)
		(min_thickness 0.25)
		(keepout
			(tracks not_allowed)
			(vias allowed)
			(pads allowed)
			(copperpour not_allowed)
			(footprints allowed)
		)
		(placement
			(enabled no)
			(sheetname "")
		)
		(fill
			(thermal_gap 0.5)
			(thermal_bridge_width 0.5)
			(island_removal_mode 0)
		)
		(polygon
			(pts
				(arc
					(start 109.358176 -55.000144)
					(mid 109.040552 -54.644303)
					(end 108.65104 -54.919626)
				)
				(arc
					(start 108.65104 -55.237634)
					(mid 108.659416 -55.279834)
					(end 108.683298 -55.315612)
				)
				(arc
					(start 108.683298 -55.315612)
					(mid 108.719089 -55.339464)
					(end 108.761276 -55.34787)
				)
				(arc
					(start 108.911136 -55.34787)
					(mid 108.933587 -55.338571)
					(end 108.942886 -55.31612)
				)
				(arc
					(start 108.942886 -55.234586)
					(mid 109.000036 -54.758837)
					(end 109.057186 -55.234586)
				)
				(xy 109.057186 -55.339742)
				(arc
					(start 109.0549 -55.342028)
					(mid 109.01443 -55.419414)
					(end 108.937044 -55.459884)
				)
				(xy 108.934758 -55.46217) (xy 108.737654 -55.46217)
				(arc
					(start 108.73613 -55.460646)
					(mid 108.687178 -55.449546)
					(end 108.641896 -55.42788)
				)
				(arc
					(start 108.641896 -55.513732)
					(mid 108.700078 -55.532094)
					(end 108.760768 -55.53837)
				)
				(xy 108.934758 -55.53837)
				(arc
					(start 108.937044 -55.540656)
					(mid 109.01443 -55.581126)
					(end 109.0549 -55.658512)
				)
				(xy 109.057186 -55.660798)
				(arc
					(start 109.057186 -55.7657)
					(mid 109.000036 -56.241449)
					(end 108.942886 -55.7657)
				)
				(arc
					(start 108.942886 -55.68442)
					(mid 108.933587 -55.661969)
					(end 108.911136 -55.65267)
				)
				(xy 108.737654 -55.65267)
				(arc
					(start 108.736892 -55.651908)
					(mid 108.688904 -55.646299)
					(end 108.641896 -55.635144)
				)
				(arc
					(start 108.641896 -55.999888)
					(mid 108.999909 -56.358282)
					(end 109.358176 -56.000142)
				)
			)
		)
	)
	(zone
		(layer "B.Cu")
		(hatch none 0.5)
		(connect_pads
			(clearance 0)
		)
		(min_thickness 0.25)
		(keepout
			(tracks not_allowed)
			(vias allowed)
			(pads allowed)
			(copperpour not_allowed)
			(footprints allowed)
		)
		(placement
			(enabled no)
			(sheetname "")
		)
		(fill
			(thermal_gap 0.5)
			(thermal_bridge_width 0.5)
			(island_removal_mode 0)
		)
		(polygon
			(pts
				(arc
					(start 185.961274 -9.800082)
					(mid 185.399934 -9.238742)
					(end 184.838594 -9.800082)
				)
				(xy 184.838594 -10.26414) (xy 184.889394 -10.259568) (xy 184.890156 -10.258552) (xy 184.912762 -10.258552)
				(xy 184.925716 -10.258552) (xy 184.930288 -10.258552) (xy 185.21934 -10.258552)
				(arc
					(start 185.223912 -10.258552)
					(mid 185.281941 -10.237399)
					(end 185.312812 -10.183876)
				)
				(arc
					(start 185.312812 -10.183876)
					(mid 185.401235 -9.406469)
					(end 185.485532 -10.184384)
				)
				(xy 185.485532 -10.203942)
				(arc
					(start 185.482992 -10.206482)
					(mid 185.40908 -10.35355)
					(end 185.262012 -10.427462)
				)
				(xy 185.259472 -10.430256) (xy 185.23204 -10.430256) (xy 185.223912 -10.430256) (xy 185.21934 -10.430256)
				(xy 184.930288 -10.430256)
				(arc
					(start 184.925716 -10.430256)
					(mid 184.881987 -10.432144)
					(end 184.838594 -10.437876)
				)
				(arc
					(start 184.838594 -10.580624)
					(mid 184.863327 -10.575291)
					(end 184.888378 -10.571734)
				)
				(xy 184.890156 -10.569956) (xy 184.916318 -10.569956) (xy 184.925716 -10.569702) (xy 184.930288 -10.569956)
				(xy 185.219086 -10.569956) (xy 185.223658 -10.569702) (xy 185.231786 -10.569956) (xy 185.259218 -10.569956)
				(arc
					(start 185.261758 -10.572496)
					(mid 185.409003 -10.646485)
					(end 185.482992 -10.79373)
				)
				(xy 185.485532 -10.79627)
				(arc
					(start 185.485532 -10.815828)
					(mid 185.401235 -11.593793)
					(end 185.312812 -10.816336)
				)
				(arc
					(start 185.312812 -10.816336)
					(mid 185.281909 -10.762582)
					(end 185.223658 -10.741406)
				)
				(xy 185.219086 -10.741152) (xy 184.930288 -10.741152)
				(arc
					(start 184.925716 -10.741406)
					(mid 184.880807 -10.74695)
					(end 184.838594 -10.76325)
				)
				(arc
					(start 184.838594 -11.199876)
					(mid 185.399807 -11.76147)
					(end 185.961274 -11.20013)
				)
			)
		)
	)
	(zone
		(layer "B.Cu")
		(hatch none 0.5)
		(connect_pads
			(clearance 0)
		)
		(min_thickness 0.25)
		(keepout
			(tracks allowed)
			(vias allowed)
			(pads allowed)
			(copperpour allowed)
			(footprints allowed)
		)
		(placement
			(enabled no)
			(sheetname "")
		)
		(fill
			(thermal_gap 0.5)
			(thermal_bridge_width 0.5)
			(island_removal_mode 0)
		)
		(polygon
			(pts
				(xy 74.676 -77.1144) (xy 74.676 -74.676) (xy 87.376 -74.676) (xy 87.376 -77.1144)
			)
		)
	)
	(zone
		(layer "B.Cu")
		(hatch none 0.5)
		(connect_pads
			(clearance 0)
		)
		(min_thickness 0.25)
		(keepout
			(tracks not_allowed)
			(vias allowed)
			(pads allowed)
			(copperpour not_allowed)
			(footprints allowed)
		)
		(placement
			(enabled no)
			(sheetname "")
		)
		(fill
			(thermal_gap 0.5)
			(thermal_bridge_width 0.5)
			(island_removal_mode 0)
		)
		(polygon
			(pts
				(arc
					(start 133.36143 -3.800094)
					(mid 132.80009 -3.238754)
					(end 132.23875 -3.800094)
				)
				(arc
					(start 132.23875 -4.228592)
					(mid 132.271702 -4.224901)
					(end 132.30479 -4.22275)
				)
				(xy 132.305552 -4.221988)
				(arc
					(start 132.680964 -4.221988)
					(mid 132.697877 -4.218624)
					(end 132.712206 -4.209034)
				)
				(arc
					(start 132.712206 -4.209034)
					(mid 132.719972 -4.198635)
					(end 132.724398 -4.186428)
				)
				(arc
					(start 132.724398 -4.186428)
					(mid 132.800992 -3.406367)
					(end 132.87502 -4.186682)
				)
				(xy 132.87502 -4.20878)
				(arc
					(start 132.871972 -4.211828)
					(mid 132.853041 -4.267359)
					(end 132.818378 -4.314698)
				)
				(arc
					(start 132.818378 -4.314698)
					(mid 132.770862 -4.349728)
					(end 132.715 -4.3688)
				)
				(xy 132.711952 -4.371848)
				(arc
					(start 132.33654 -4.371848)
					(mid 132.287456 -4.37403)
					(end 132.23875 -4.380484)
				)
				(arc
					(start 132.23875 -4.64439)
					(mid 132.270875 -4.635509)
					(end 132.303774 -4.630166)
				)
				(xy 132.305552 -4.628388) (xy 132.711952 -4.628388)
				(arc
					(start 132.715 -4.631436)
					(mid 132.770849 -4.650533)
					(end 132.818378 -4.685538)
				)
				(arc
					(start 132.818378 -4.685538)
					(mid 132.853066 -4.732864)
					(end 132.871972 -4.788408)
				)
				(xy 132.87502 -4.791456)
				(arc
					(start 132.87502 -4.813554)
					(mid 132.800992 -5.593876)
					(end 132.724398 -4.813808)
				)
				(arc
					(start 132.724398 -4.813808)
					(mid 132.72 -4.801586)
					(end 132.712206 -4.791202)
				)
				(arc
					(start 132.712206 -4.791202)
					(mid 132.697872 -4.781624)
					(end 132.680964 -4.778248)
				)
				(arc
					(start 132.33654 -4.778248)
					(mid 132.284807 -4.786928)
					(end 132.23875 -4.81203)
				)
				(arc
					(start 132.23875 -5.199888)
					(mid 132.799963 -5.761482)
					(end 133.36143 -5.200142)
				)
			)
		)
	)
	(zone
		(layer "B.Cu")
		(hatch none 0.5)
		(connect_pads
			(clearance 0)
		)
		(min_thickness 0.25)
		(keepout
			(tracks not_allowed)
			(vias allowed)
			(pads allowed)
			(copperpour not_allowed)
			(footprints allowed)
		)
		(placement
			(enabled no)
			(sheetname "")
		)
		(fill
			(thermal_gap 0.5)
			(thermal_bridge_width 0.5)
			(island_removal_mode 0)
		)
		(polygon
			(pts
				(arc
					(start 100.961444 -3.800094)
					(mid 100.400104 -3.238754)
					(end 99.838764 -3.800094)
				)
				(arc
					(start 99.838764 -4.228592)
					(mid 99.871716 -4.224901)
					(end 99.904804 -4.22275)
				)
				(xy 99.905566 -4.221988)
				(arc
					(start 100.280978 -4.221988)
					(mid 100.297891 -4.218624)
					(end 100.31222 -4.209034)
				)
				(arc
					(start 100.31222 -4.209034)
					(mid 100.319986 -4.198635)
					(end 100.324412 -4.186428)
				)
				(arc
					(start 100.324412 -4.186428)
					(mid 100.401006 -3.406367)
					(end 100.475034 -4.186682)
				)
				(xy 100.475034 -4.20878)
				(arc
					(start 100.471986 -4.211828)
					(mid 100.453055 -4.267359)
					(end 100.418392 -4.314698)
				)
				(arc
					(start 100.418392 -4.314698)
					(mid 100.370876 -4.349728)
					(end 100.315014 -4.3688)
				)
				(xy 100.311966 -4.371848)
				(arc
					(start 99.936554 -4.371848)
					(mid 99.88747 -4.37403)
					(end 99.838764 -4.380484)
				)
				(arc
					(start 99.838764 -4.64439)
					(mid 99.870889 -4.635509)
					(end 99.903788 -4.630166)
				)
				(xy 99.905566 -4.628388) (xy 100.311966 -4.628388)
				(arc
					(start 100.315014 -4.631436)
					(mid 100.370863 -4.650533)
					(end 100.418392 -4.685538)
				)
				(arc
					(start 100.418392 -4.685538)
					(mid 100.45308 -4.732864)
					(end 100.471986 -4.788408)
				)
				(xy 100.475034 -4.791456)
				(arc
					(start 100.475034 -4.813554)
					(mid 100.401006 -5.593876)
					(end 100.324412 -4.813808)
				)
				(arc
					(start 100.324412 -4.813808)
					(mid 100.320014 -4.801586)
					(end 100.31222 -4.791202)
				)
				(arc
					(start 100.31222 -4.791202)
					(mid 100.297886 -4.781624)
					(end 100.280978 -4.778248)
				)
				(arc
					(start 99.936554 -4.778248)
					(mid 99.884821 -4.786928)
					(end 99.838764 -4.81203)
				)
				(arc
					(start 99.838764 -5.199888)
					(mid 100.399977 -5.761482)
					(end 100.961444 -5.200142)
				)
			)
		)
	)
	(zone
		(layer "B.Cu")
		(hatch none 0.5)
		(connect_pads
			(clearance 0)
		)
		(min_thickness 0.25)
		(keepout
			(tracks not_allowed)
			(vias allowed)
			(pads allowed)
			(copperpour not_allowed)
			(footprints allowed)
		)
		(placement
			(enabled no)
			(sheetname "")
		)
		(fill
			(thermal_gap 0.5)
			(thermal_bridge_width 0.5)
			(island_removal_mode 0)
		)
		(polygon
			(pts
				(arc
					(start 108.358178 -55.000144)
					(mid 108.040554 -54.644303)
					(end 107.651042 -54.919626)
				)
				(arc
					(start 107.651042 -55.237634)
					(mid 107.659418 -55.279834)
					(end 107.6833 -55.315612)
				)
				(arc
					(start 107.6833 -55.315612)
					(mid 107.719091 -55.339464)
					(end 107.761278 -55.34787)
				)
				(arc
					(start 107.911138 -55.34787)
					(mid 107.933589 -55.338571)
					(end 107.942888 -55.31612)
				)
				(arc
					(start 107.942888 -55.234586)
					(mid 108.000038 -54.758837)
					(end 108.057188 -55.234586)
				)
				(xy 108.057188 -55.339742)
				(arc
					(start 108.054902 -55.342028)
					(mid 108.014432 -55.419414)
					(end 107.937046 -55.459884)
				)
				(xy 107.93476 -55.46217) (xy 107.737656 -55.46217)
				(arc
					(start 107.736132 -55.460646)
					(mid 107.68718 -55.449546)
					(end 107.641898 -55.42788)
				)
				(arc
					(start 107.641898 -55.513732)
					(mid 107.70008 -55.532094)
					(end 107.76077 -55.53837)
				)
				(xy 107.93476 -55.53837)
				(arc
					(start 107.937046 -55.540656)
					(mid 108.014432 -55.581126)
					(end 108.054902 -55.658512)
				)
				(xy 108.057188 -55.660798)
				(arc
					(start 108.057188 -55.7657)
					(mid 108.000038 -56.241449)
					(end 107.942888 -55.7657)
				)
				(arc
					(start 107.942888 -55.68442)
					(mid 107.933589 -55.661969)
					(end 107.911138 -55.65267)
				)
				(xy 107.737656 -55.65267)
				(arc
					(start 107.736894 -55.651908)
					(mid 107.688906 -55.646299)
					(end 107.641898 -55.635144)
				)
				(arc
					(start 107.641898 -55.999888)
					(mid 107.999911 -56.358282)
					(end 108.358178 -56.000142)
				)
			)
		)
	)
	(zone
		(net "GND")
		(layer "B.Cu")
		(hatch none 0.5)
		(connect_pads
			(clearance 0.5)
		)
		(min_thickness 0.25)
		(fill yes
			(thermal_gap 0.5)
			(thermal_bridge_width 0.5)
			(island_removal_mode 0)
		)
		(polygon
			(pts
				(xy 176.3014 -36.8427) (xy 176.2633 -36.8808) (xy 176.2633 -44.02582) (xy 176.494186 -44.256706)
				(xy 176.701704 -44.256706) (xy 176.856898 -44.101512) (xy 176.856898 -36.902898) (xy 176.7967 -36.8427)
			)
		)
		(polygon
			(pts
				(xy 176.7459 -43.5483) (xy 176.5427 -43.5483) (xy 176.5427 -43.7515) (xy 176.7459 -43.7515)
			)
		)
		(polygon
			(pts
				(xy 176.7459 -42.9895) (xy 176.5427 -42.9895) (xy 176.5427 -43.3959) (xy 176.7459 -43.3959)
			)
		)
		(polygon
			(pts
				(xy 176.7459 -42.6339) (xy 176.5427 -42.6339) (xy 176.5427 -42.8371) (xy 176.7459 -42.8371)
			)
		)
	)
	(zone
		(net "SAS0_AVDD")
		(layer "B.Cu")
		(hatch none 0.5)
		(connect_pads
			(clearance 0.5)
		)
		(min_thickness 0.25)
		(fill yes
			(thermal_gap 0.5)
			(thermal_bridge_width 0.5)
			(island_removal_mode 0)
		)
		(polygon
			(pts
				(xy 164.8968 -29.1084) (xy 164.7952 -29.21) (xy 164.7952 -30.7848) (xy 165.1 -31.0896) (xy 165.1 -33.8836)
				(xy 165.1762 -33.9598) (xy 165.6588 -33.9598) (xy 165.8112 -33.8074) (xy 165.8112 -29.1846) (xy 165.735 -29.1084)
			)
		)
		(polygon
			(pts
				(xy 165.586918 -30.585156) (xy 165.383718 -30.585156) (xy 165.383718 -30.788356) (xy 165.586918 -30.788356)
			)
		)
		(polygon
			(pts
				(xy 165.586918 -29.696156) (xy 165.383718 -29.696156) (xy 165.383718 -30.178756) (xy 165.586918 -30.178756)
			)
		)
	)
	(zone
		(layer "B.Cu")
		(hatch none 0.5)
		(connect_pads
			(clearance 0)
		)
		(min_thickness 0.25)
		(keepout
			(tracks allowed)
			(vias allowed)
			(pads allowed)
			(copperpour allowed)
			(footprints allowed)
		)
		(placement
			(enabled no)
			(sheetname "")
		)
		(fill
			(thermal_gap 0.5)
			(thermal_bridge_width 0.5)
			(island_removal_mode 0)
		)
		(polygon
			(pts
				(xy 84.2772 -6.4008) (xy 84.2772 -0.635) (xy 149.987 -0.635) (xy 149.987 -6.4008)
			)
		)
	)
	(zone
		(net "P3V3")
		(layer "B.Cu")
		(hatch none 0.5)
		(connect_pads
			(clearance 0.5)
		)
		(min_thickness 0.25)
		(fill yes
			(thermal_gap 0.5)
			(thermal_bridge_width 0.5)
			(island_removal_mode 0)
		)
		(polygon
			(pts
				(xy 169.1894 -60.1726) (xy 169.099992 -60.262008) (xy 169.099992 -62.725808) (xy 169.214038 -62.8396)
				(xy 170.278044 -62.8396) (xy 170.287442 -62.830202) (xy 171.708318 -62.830202) (xy 171.79798 -62.74054)
				(xy 171.79798 -60.36818) (xy 171.6024 -60.1726)
			)
		)
		(polygon
			(pts
				(xy 170.3324 -62.1284) (xy 170.1292 -62.1284) (xy 170.1292 -62.3316) (xy 170.3324 -62.3316)
			)
		)
		(polygon
			(pts
				(xy 169.7228 -62.1284) (xy 169.5196 -62.1284) (xy 169.5196 -62.3316) (xy 169.7228 -62.3316)
			)
		)
	)
	(zone
		(layer "B.Cu")
		(hatch none 0.5)
		(connect_pads
			(clearance 0)
		)
		(min_thickness 0.25)
		(keepout
			(tracks allowed)
			(vias allowed)
			(pads allowed)
			(copperpour allowed)
			(footprints allowed)
		)
		(placement
			(enabled no)
			(sheetname "")
		)
		(fill
			(thermal_gap 0.5)
			(thermal_bridge_width 0.5)
			(island_removal_mode 0)
		)
		(polygon
			(pts
				(xy 179.307744 -13.196062) (xy 179.307744 -9.245092) (xy 193.400172 -9.245092) (xy 193.400172 -13.196062)
			)
		)
	)
	(zone
		(layer "B.Cu")
		(hatch none 0.5)
		(connect_pads
			(clearance 0)
		)
		(min_thickness 0.25)
		(keepout
			(tracks not_allowed)
			(vias allowed)
			(pads allowed)
			(copperpour not_allowed)
			(footprints allowed)
		)
		(placement
			(enabled no)
			(sheetname "")
		)
		(fill
			(thermal_gap 0.5)
			(thermal_bridge_width 0.5)
			(island_removal_mode 0)
		)
		(polygon
			(pts
				(arc
					(start 129.761488 -3.800094)
					(mid 129.200148 -3.238754)
					(end 128.638808 -3.800094)
				)
				(arc
					(start 128.638808 -4.228592)
					(mid 128.67176 -4.224901)
					(end 128.704848 -4.22275)
				)
				(xy 128.70561 -4.221988)
				(arc
					(start 129.081022 -4.221988)
					(mid 129.097935 -4.218624)
					(end 129.112264 -4.209034)
				)
				(arc
					(start 129.112264 -4.209034)
					(mid 129.12003 -4.198635)
					(end 129.124456 -4.186428)
				)
				(arc
					(start 129.124456 -4.186428)
					(mid 129.20105 -3.406367)
					(end 129.275078 -4.186682)
				)
				(xy 129.275078 -4.20878)
				(arc
					(start 129.27203 -4.211828)
					(mid 129.253099 -4.267359)
					(end 129.218436 -4.314698)
				)
				(arc
					(start 129.218436 -4.314698)
					(mid 129.17092 -4.349728)
					(end 129.115058 -4.3688)
				)
				(xy 129.11201 -4.371848)
				(arc
					(start 128.736598 -4.371848)
					(mid 128.687514 -4.37403)
					(end 128.638808 -4.380484)
				)
				(arc
					(start 128.638808 -4.64439)
					(mid 128.670933 -4.635509)
					(end 128.703832 -4.630166)
				)
				(xy 128.70561 -4.628388) (xy 129.11201 -4.628388)
				(arc
					(start 129.115058 -4.631436)
					(mid 129.170907 -4.650533)
					(end 129.218436 -4.685538)
				)
				(arc
					(start 129.218436 -4.685538)
					(mid 129.253124 -4.732864)
					(end 129.27203 -4.788408)
				)
				(xy 129.275078 -4.791456)
				(arc
					(start 129.275078 -4.813554)
					(mid 129.20105 -5.593876)
					(end 129.124456 -4.813808)
				)
				(arc
					(start 129.124456 -4.813808)
					(mid 129.120058 -4.801586)
					(end 129.112264 -4.791202)
				)
				(arc
					(start 129.112264 -4.791202)
					(mid 129.09793 -4.781624)
					(end 129.081022 -4.778248)
				)
				(arc
					(start 128.736598 -4.778248)
					(mid 128.684865 -4.786928)
					(end 128.638808 -4.81203)
				)
				(arc
					(start 128.638808 -5.199888)
					(mid 129.200021 -5.761482)
					(end 129.761488 -5.200142)
				)
			)
		)
	)
	(zone
		(layer "B.Cu")
		(hatch none 0.5)
		(connect_pads
			(clearance 0)
		)
		(min_thickness 0.25)
		(keepout
			(tracks allowed)
			(vias allowed)
			(pads allowed)
			(copperpour allowed)
			(footprints not_allowed)
		)
		(placement
			(enabled no)
			(sheetname "")
		)
		(fill
			(thermal_gap 0.5)
			(thermal_bridge_width 0.5)
			(island_removal_mode 0)
		)
		(polygon
			(pts
				(arc
					(start 148.500084 -29.500068)
					(mid 151.500078 -32.500062)
					(end 154.500072 -29.500068)
				)
				(arc
					(start 154.500072 -29.500068)
					(mid 151.500078 -26.500074)
					(end 148.500084 -29.500068)
				)
			)
		)
	)
	(zone
		(layer "B.Cu")
		(hatch none 0.5)
		(connect_pads
			(clearance 0)
		)
		(min_thickness 0.25)
		(keepout
			(tracks allowed)
			(vias allowed)
			(pads allowed)
			(copperpour allowed)
			(footprints not_allowed)
		)
		(placement
			(enabled no)
			(sheetname "")
		)
		(fill
			(thermal_gap 0.5)
			(thermal_bridge_width 0.5)
			(island_removal_mode 0)
		)
		(polygon
			(pts
				(arc
					(start 154.500072 -29.500068)
					(mid 151.500078 -26.500074)
					(end 148.500084 -29.500068)
				)
				(arc
					(start 148.500084 -29.500068)
					(mid 151.500078 -32.500062)
					(end 154.500072 -29.500068)
				)
			)
		)
	)
	(zone
		(net "P1V8_C")
		(layer "B.Cu")
		(hatch none 0.5)
		(connect_pads
			(clearance 0.5)
		)
		(min_thickness 0.25)
		(fill yes
			(thermal_gap 0.5)
			(thermal_bridge_width 0.5)
			(island_removal_mode 0)
		)
		(polygon
			(pts
				(xy 202.958446 -42.827956) (xy 202.806046 -42.980356) (xy 202.806046 -45.578522) (xy 202.884786 -45.657262)
				(xy 204.707744 -45.657262) (xy 204.845666 -45.51934) (xy 204.845666 -43.12412) (xy 204.549502 -42.827956)
			)
		)
		(polygon
			(pts
				(xy 204.1398 -44.94022) (xy 203.9366 -44.94022) (xy 203.9366 -45.14342) (xy 204.1398 -45.14342)
			)
		)
		(polygon
			(pts
				(xy 203.7588 -44.94022) (xy 203.5556 -44.94022) (xy 203.5556 -45.14342) (xy 203.7588 -45.14342)
			)
		)
		(polygon
			(pts
				(xy 203.1492 -44.94022) (xy 202.946 -44.94022) (xy 202.946 -45.14342) (xy 203.1492 -45.14342)
			)
		)
	)
	(zone
		(layer "B.Cu")
		(hatch none 0.5)
		(connect_pads
			(clearance 0)
		)
		(min_thickness 0.25)
		(keepout
			(tracks not_allowed)
			(vias allowed)
			(pads allowed)
			(copperpour not_allowed)
			(footprints allowed)
		)
		(placement
			(enabled no)
			(sheetname "")
		)
		(fill
			(thermal_gap 0.5)
			(thermal_bridge_width 0.5)
			(island_removal_mode 0)
		)
		(polygon
			(pts
				(arc
					(start 120.358154 -55.000144)
					(mid 120.039887 -54.644231)
					(end 119.650764 -54.920896)
				)
				(arc
					(start 119.650764 -55.237126)
					(mid 119.659213 -55.279603)
					(end 119.683276 -55.315612)
				)
				(arc
					(start 119.683276 -55.315612)
					(mid 119.719067 -55.339464)
					(end 119.761254 -55.34787)
				)
				(arc
					(start 119.911114 -55.34787)
					(mid 119.933565 -55.338571)
					(end 119.942864 -55.31612)
				)
				(arc
					(start 119.942864 -55.234586)
					(mid 120.000014 -54.758837)
					(end 120.057164 -55.234586)
				)
				(xy 120.057164 -55.339742)
				(arc
					(start 120.054878 -55.342028)
					(mid 120.014408 -55.419414)
					(end 119.937022 -55.459884)
				)
				(xy 119.934736 -55.46217) (xy 119.737632 -55.46217)
				(arc
					(start 119.736108 -55.460646)
					(mid 119.687156 -55.449546)
					(end 119.641874 -55.42788)
				)
				(arc
					(start 119.641874 -55.513732)
					(mid 119.700056 -55.532094)
					(end 119.760746 -55.53837)
				)
				(xy 119.934736 -55.53837)
				(arc
					(start 119.937022 -55.540656)
					(mid 120.014408 -55.581126)
					(end 120.054878 -55.658512)
				)
				(xy 120.057164 -55.660798)
				(arc
					(start 120.057164 -55.7657)
					(mid 120.000014 -56.241449)
					(end 119.942864 -55.7657)
				)
				(arc
					(start 119.942864 -55.68442)
					(mid 119.933565 -55.661969)
					(end 119.911114 -55.65267)
				)
				(xy 119.737632 -55.65267)
				(arc
					(start 119.73687 -55.651908)
					(mid 119.688882 -55.646299)
					(end 119.641874 -55.635144)
				)
				(arc
					(start 119.641874 -55.999888)
					(mid 119.999887 -56.358282)
					(end 120.358154 -56.000142)
				)
			)
		)
	)
	(zone
		(net "PLL_VDD")
		(layer "B.Cu")
		(hatch none 0.5)
		(connect_pads
			(clearance 0.5)
		)
		(min_thickness 0.25)
		(fill yes
			(thermal_gap 0.5)
			(thermal_bridge_width 0.5)
			(island_removal_mode 0)
		)
		(polygon
			(pts
				(xy 201.311256 -30.6324) (xy 201.041254 -30.902402) (xy 201.041254 -31.590996) (xy 200.551542 -32.080708)
				(xy 195.199508 -32.080708) (xy 194.9577 -32.322516) (xy 194.9577 -33.274) (xy 195.3641 -33.6804)
				(xy 195.7832 -33.6804) (xy 195.955666 -33.852866) (xy 198.138034 -33.852866) (xy 198.488808 -33.502092)
				(xy 202.591924 -33.502092) (xy 202.66787 -33.426146) (xy 202.66787 -30.811724) (xy 202.488546 -30.6324)
			)
		)
		(polygon
			(pts
				(xy 200.712578 -32.891222) (xy 200.509378 -32.891222) (xy 200.509378 -33.094422) (xy 200.712578 -33.094422)
			)
		)
		(polygon
			(pts
				(xy 199.848978 -32.891222) (xy 199.645778 -32.891222) (xy 199.645778 -33.094422) (xy 199.848978 -33.094422)
			)
		)
		(polygon
			(pts
				(xy 202.211178 -32.789622) (xy 202.007978 -32.789622) (xy 202.007978 -32.992822) (xy 202.211178 -32.992822)
			)
		)
		(polygon
			(pts
				(xy 197.410578 -32.586422) (xy 197.207378 -32.586422) (xy 197.207378 -32.789622) (xy 197.410578 -32.789622)
			)
		)
		(polygon
			(pts
				(xy 196.699378 -32.586422) (xy 196.191378 -32.586422) (xy 196.191378 -32.789622) (xy 196.699378 -32.789622)
			)
		)
		(polygon
			(pts
				(xy 195.784978 -32.586422) (xy 195.581778 -32.586422) (xy 195.581778 -32.789622) (xy 195.784978 -32.789622)
			)
		)
	)
	(zone
		(net "P1V8_E")
		(layer "B.Cu")
		(hatch none 0.5)
		(connect_pads
			(clearance 0.5)
		)
		(min_thickness 0.25)
		(fill yes
			(thermal_gap 0.5)
			(thermal_bridge_width 0.5)
			(island_removal_mode 0)
		)
		(polygon
			(pts
				(xy 165.287198 -4.7879) (xy 165.147498 -4.9276) (xy 165.147498 -5.9944) (xy 165.223698 -6.0706)
				(xy 166.624 -6.0706) (xy 166.8145 -6.2611) (xy 167.9575 -6.2611) (xy 167.9956 -6.223) (xy 167.9956 -4.953)
				(xy 167.8305 -4.7879)
			)
		)
		(polygon
			(pts
				(xy 167.47363 -5.540756) (xy 167.27043 -5.540756) (xy 167.27043 -5.743956) (xy 167.47363 -5.743956)
			)
		)
	)
	(zone
		(net "SYS_PLL_VDD")
		(layer "B.Cu")
		(hatch none 0.5)
		(connect_pads
			(clearance 0.5)
		)
		(min_thickness 0.25)
		(fill yes
			(thermal_gap 0.5)
			(thermal_bridge_width 0.5)
			(island_removal_mode 0)
		)
		(polygon
			(pts
				(xy 154.432254 -58.528204) (xy 154.27706 -58.683398) (xy 154.27706 -64.67094) (xy 153.924 -65.024)
				(xy 153.162 -65.024) (xy 152.908 -65.278) (xy 152.908 -66.421) (xy 153.2001 -66.7131) (xy 155.7909 -66.7131)
				(xy 155.956 -66.548) (xy 155.956 -58.639964) (xy 155.84424 -58.528204)
			)
		)
		(polygon
			(pts
				(xy 155.708604 -66.053208) (xy 155.505404 -66.053208) (xy 155.505404 -66.256408) (xy 155.708604 -66.256408)
			)
		)
		(polygon
			(pts
				(xy 155.149804 -66.053208) (xy 154.946604 -66.053208) (xy 154.946604 -66.256408) (xy 155.149804 -66.256408)
			)
		)
		(polygon
			(pts
				(xy 155.429204 -64.453008) (xy 155.226004 -64.453008) (xy 155.226004 -64.656208) (xy 155.429204 -64.656208)
			)
		)
		(polygon
			(pts
				(xy 155.429204 -63.589408) (xy 155.226004 -63.589408) (xy 155.226004 -63.792608) (xy 155.429204 -63.792608)
			)
		)
		(polygon
			(pts
				(xy 154.997404 -60.871608) (xy 154.794204 -60.871608) (xy 154.794204 -61.074808) (xy 154.997404 -61.074808)
			)
		)
		(polygon
			(pts
				(xy 154.972004 -59.881008) (xy 154.768804 -59.881008) (xy 154.768804 -60.084208) (xy 154.794204 -60.160408)
				(xy 154.794204 -60.363608) (xy 154.997404 -60.363608) (xy 154.997404 -60.160408) (xy 154.972004 -60.084208)
			)
		)
		(polygon
			(pts
				(xy 154.972004 -59.271408) (xy 154.768804 -59.271408) (xy 154.768804 -59.474608) (xy 154.972004 -59.474608)
			)
		)
	)
	(zone
		(net "P3V3")
		(layer "B.Cu")
		(hatch none 0.5)
		(connect_pads
			(clearance 0.5)
		)
		(min_thickness 0.25)
		(fill yes
			(thermal_gap 0.5)
			(thermal_bridge_width 0.5)
			(island_removal_mode 0)
		)
		(polygon
			(pts
				(xy 161.681922 -8.60933) (xy 160.841436 -9.449816) (xy 160.841436 -11.479022) (xy 163.129214 -13.7668)
				(xy 167.0812 -13.7668) (xy 167.0939 -13.7541) (xy 167.8686 -13.7541) (xy 168.1353 -13.4874) (xy 168.1353 -12.7127)
				(xy 167.894 -12.4714) (xy 167.88892 -12.471654) (xy 167.111426 -12.471654) (xy 167.074596 -12.508484)
				(xy 166.232078 -12.508484) (xy 166.01313 -12.289536) (xy 166.01313 -11.898884) (xy 165.976046 -11.8618)
				(xy 163.144962 -11.8618) (xy 162.037014 -10.753852) (xy 162.037014 -10.162286) (xy 162.56 -9.6393)
				(xy 164.2491 -9.6393) (xy 164.2872 -9.6012) (xy 166.116 -9.6012) (xy 166.1668 -9.5504) (xy 166.1668 -9.0297)
				(xy 166.0652 -8.9281) (xy 164.62375 -8.9281) (xy 164.30498 -8.60933)
			)
		)
		(polygon
			(pts
				(xy 167.9829 -12.9286) (xy 167.7797 -12.9286) (xy 167.7797 -13.1318) (xy 167.9829 -13.1318)
			)
		)
		(polygon
			(pts
				(xy 167.4241 -12.9286) (xy 167.2209 -12.9286) (xy 167.2209 -13.1318) (xy 167.4241 -13.1318)
			)
		)
		(polygon
			(pts
				(xy 165.467792 -12.36853) (xy 164.985192 -12.36853) (xy 164.985192 -12.57173) (xy 165.467792 -12.57173)
			)
		)
		(polygon
			(pts
				(xy 164.578792 -12.36853) (xy 164.096192 -12.36853) (xy 164.096192 -12.57173) (xy 164.578792 -12.57173)
			)
		)
		(polygon
			(pts
				(xy 163.689792 -12.36853) (xy 163.486592 -12.36853) (xy 163.486592 -12.57173) (xy 163.689792 -12.57173)
			)
		)
		(polygon
			(pts
				(xy 164.2237 -8.9154) (xy 164.0205 -8.9154) (xy 164.0205 -9.1186) (xy 164.2237 -9.1186)
			)
		)
		(polygon
			(pts
				(xy 163.6141 -8.9154) (xy 163.4109 -8.9154) (xy 163.4109 -9.1186) (xy 163.6141 -9.1186)
			)
		)
	)
	(zone
		(net "P0V975")
		(layer "B.Cu")
		(hatch none 0.5)
		(connect_pads
			(clearance 0.5)
		)
		(min_thickness 0.25)
		(fill yes
			(thermal_gap 0.5)
			(thermal_bridge_width 0.5)
			(island_removal_mode 0)
		)
		(polygon
			(pts
				(xy 178.7652 -82.9818) (xy 176.403 -85.344) (xy 176.403 -93.0402) (xy 178.3842 -95.0214) (xy 180.1368 -95.0214)
				(xy 182.499 -97.3836) (xy 188.6712 -97.3836) (xy 189.0522 -97.0026) (xy 189.0522 -94.0308) (xy 186.5376 -91.5162)
				(xy 184.3278 -91.5162) (xy 183.515 -90.7034) (xy 183.515 -83.312) (xy 183.1848 -82.9818)
			)
		)
		(polygon
			(pts
				(xy 182.627016 -86.318852) (xy 182.423816 -86.318852) (xy 182.423816 -86.522052) (xy 182.627016 -86.522052)
			)
		)
		(polygon
			(pts
				(xy 182.627016 -85.455252) (xy 182.423816 -85.455252) (xy 182.423816 -85.658452) (xy 182.627016 -85.658452)
			)
		)
		(polygon
			(pts
				(xy 183.058816 -84.896452) (xy 182.855616 -84.896452) (xy 182.855616 -85.099652) (xy 183.058816 -85.099652)
			)
		)
		(polygon
			(pts
				(xy 183.058816 -84.337652) (xy 182.855616 -84.337652) (xy 182.855616 -84.540852) (xy 183.058816 -84.540852)
			)
		)
		(polygon
			(pts
				(xy 183.008016 -83.931252) (xy 182.804816 -83.931252) (xy 182.804816 -84.134452) (xy 183.008016 -84.134452)
			)
		)
		(polygon
			(pts
				(xy 183.008016 -83.321652) (xy 182.804816 -83.321652) (xy 182.804816 -83.524852) (xy 183.008016 -83.524852)
			)
		)
	)
	(zone
		(net "P12V_STBY_VIN_U11")
		(layer "B.Cu")
		(hatch none 0.5)
		(connect_pads
			(clearance 0.5)
		)
		(min_thickness 0.25)
		(fill yes
			(thermal_gap 0.5)
			(thermal_bridge_width 0.5)
			(island_removal_mode 0)
		)
		(polygon
			(pts
				(xy 156.3116 -111.3282) (xy 156.1592 -111.4806) (xy 156.1592 -113.7412) (xy 156.337 -113.919) (xy 160.0708 -113.919)
				(xy 160.4264 -113.5634) (xy 160.4264 -111.4552) (xy 160.2994 -111.3282)
			)
		)
	)
	(zone
		(layer "B.Cu")
		(hatch none 0.5)
		(connect_pads
			(clearance 0)
		)
		(min_thickness 0.25)
		(keepout
			(tracks not_allowed)
			(vias allowed)
			(pads allowed)
			(copperpour not_allowed)
			(footprints allowed)
		)
		(placement
			(enabled no)
			(sheetname "")
		)
		(fill
			(thermal_gap 0.5)
			(thermal_bridge_width 0.5)
			(island_removal_mode 0)
		)
		(polygon
			(pts
				(arc
					(start 103.983536 -115.10899)
					(mid 103.759 -114.366294)
					(end 103.016304 -114.59083)
				)
				(xy 102.880668 -114.844322) (xy 102.897432 -114.924586) (xy 103.070406 -115.190524) (xy 103.095044 -115.21567)
				(xy 103.103172 -115.22202) (xy 103.11765 -115.22964) (xy 103.121714 -115.228878) (xy 103.125778 -115.231418)
				(xy 103.126286 -115.231418) (xy 103.146606 -115.24488)
				(arc
					(start 103.153718 -115.248436)
					(mid 103.188049 -115.247952)
					(end 103.213916 -115.225322)
				)
				(arc
					(start 103.257604 -115.143788)
					(mid 103.680223 -114.514549)
					(end 103.389684 -115.214654)
				)
				(xy 103.331264 -115.323366)
				(arc
					(start 103.327454 -115.324636)
					(mid 103.227857 -115.392782)
					(end 103.107236 -115.39093)
				)
				(xy 103.104696 -115.391946) (xy 103.100886 -115.389914) (xy 103.095552 -115.39093) (xy 103.09225 -115.388898)
				(xy 103.091742 -115.388898) (xy 103.069898 -115.37442) (xy 103.046276 -115.362482) (xy 103.046022 -115.362228)
				(xy 103.041704 -115.359942) (xy 103.041196 -115.358672) (xy 103.030528 -115.353084) (xy 103.012748 -115.343432)
				(xy 103.010462 -115.343432) (xy 103.008176 -115.340892) (xy 103.00335 -115.338352) (xy 103.002334 -115.33505)
				(xy 102.97414 -115.306348) (xy 102.965758 -115.30457) (xy 102.953058 -115.285012) (xy 102.936548 -115.268248)
				(xy 102.936548 -115.259612) (xy 102.783894 -115.024662) (xy 102.645718 -115.28298) (xy 102.753414 -115.448588)
				(arc
					(start 102.80777 -115.503198)
					(mid 102.851481 -115.541567)
					(end 102.899718 -115.574064)
				)
				(xy 102.9081 -115.578636) (xy 102.920292 -115.584986) (xy 102.9208 -115.584732) (xy 102.924356 -115.586764)
				(xy 102.925372 -115.58651) (xy 102.939596 -115.595146) (xy 102.950772 -115.595146) (xy 102.963726 -115.6081)
				(xy 102.971854 -115.612164) (xy 102.974648 -115.613688) (xy 102.974902 -115.613942) (xy 102.980744 -115.61699)
				(arc
					(start 102.982268 -115.621562)
					(mid 103.051547 -115.721339)
					(end 103.050086 -115.842796)
				)
				(xy 103.051356 -115.84686) (xy 103.036624 -115.874038)
				(arc
					(start 102.992682 -115.95608)
					(mid 102.570074 -116.585801)
					(end 102.860602 -115.885214)
				)
				(arc
					(start 102.904544 -115.803172)
					(mid 102.909892 -115.772719)
					(end 102.896162 -115.745006)
				)
				(xy 102.888542 -115.745006) (xy 102.87508 -115.731544) (xy 102.855268 -115.721638) (xy 102.855014 -115.721384)
				(xy 102.851204 -115.719352) (xy 102.84841 -115.717828) (xy 102.847902 -115.716558) (xy 102.837996 -115.711224)
				(xy 102.804468 -115.693698)
				(arc
					(start 102.803706 -115.691158)
					(mid 102.762971 -115.662683)
					(end 102.724712 -115.63096)
				)
				(xy 102.723442 -115.63096) (xy 102.657402 -115.564412) (xy 102.648766 -115.562634) (xy 102.636066 -115.543076)
				(xy 102.61981 -115.52682) (xy 102.61981 -115.51793) (xy 102.564946 -115.433602) (xy 102.266496 -115.990624)
				(arc
					(start 102.266496 -115.990878)
					(mid 102.491032 -116.733574)
					(end 103.233728 -116.509038)
				)
			)
		)
	)
	(zone
		(layer "B.Cu")
		(hatch none 0.5)
		(connect_pads
			(clearance 0)
		)
		(min_thickness 0.25)
		(keepout
			(tracks not_allowed)
			(vias allowed)
			(pads allowed)
			(copperpour not_allowed)
			(footprints allowed)
		)
		(placement
			(enabled no)
			(sheetname "")
		)
		(fill
			(thermal_gap 0.5)
			(thermal_bridge_width 0.5)
			(island_removal_mode 0)
		)
		(polygon
			(pts
				(arc
					(start 113.358168 -55.000144)
					(mid 113.042105 -54.644484)
					(end 112.651794 -54.916578)
				)
				(arc
					(start 112.651794 -55.239412)
					(mid 112.659992 -55.280625)
					(end 112.68329 -55.315612)
				)
				(arc
					(start 112.68329 -55.315612)
					(mid 112.719081 -55.339464)
					(end 112.761268 -55.34787)
				)
				(arc
					(start 112.911128 -55.34787)
					(mid 112.933579 -55.338571)
					(end 112.942878 -55.31612)
				)
				(arc
					(start 112.942878 -55.234586)
					(mid 113.000028 -54.758837)
					(end 113.057178 -55.234586)
				)
				(xy 113.057178 -55.339742)
				(arc
					(start 113.054892 -55.342028)
					(mid 113.014422 -55.419414)
					(end 112.937036 -55.459884)
				)
				(xy 112.93475 -55.46217) (xy 112.737646 -55.46217)
				(arc
					(start 112.736122 -55.460646)
					(mid 112.68717 -55.449546)
					(end 112.641888 -55.42788)
				)
				(arc
					(start 112.641888 -55.513732)
					(mid 112.70007 -55.532094)
					(end 112.76076 -55.53837)
				)
				(xy 112.93475 -55.53837)
				(arc
					(start 112.937036 -55.540656)
					(mid 113.014422 -55.581126)
					(end 113.054892 -55.658512)
				)
				(xy 113.057178 -55.660798)
				(arc
					(start 113.057178 -55.7657)
					(mid 113.000028 -56.241449)
					(end 112.942878 -55.7657)
				)
				(arc
					(start 112.942878 -55.68442)
					(mid 112.933579 -55.661969)
					(end 112.911128 -55.65267)
				)
				(xy 112.737646 -55.65267)
				(arc
					(start 112.736884 -55.651908)
					(mid 112.688896 -55.646299)
					(end 112.641888 -55.635144)
				)
				(arc
					(start 112.641888 -55.999888)
					(mid 112.999901 -56.358282)
					(end 113.358168 -56.000142)
				)
			)
		)
	)
	(zone
		(layer "B.Cu")
		(hatch none 0.5)
		(connect_pads
			(clearance 0)
		)
		(min_thickness 0.25)
		(keepout
			(tracks allowed)
			(vias allowed)
			(pads allowed)
			(copperpour allowed)
			(footprints not_allowed)
		)
		(placement
			(enabled no)
			(sheetname "")
		)
		(fill
			(thermal_gap 0.5)
			(thermal_bridge_width 0.5)
			(island_removal_mode 0)
		)
		(polygon
			(pts
				(arc
					(start 98.000058 -39.67988)
					(mid 95.000064 -36.679886)
					(end 92.00007 -39.67988)
				)
				(arc
					(start 92.00007 -39.67988)
					(mid 95.000064 -42.679874)
					(end 98.000058 -39.67988)
				)
			)
		)
	)
	(zone
		(net "P1V5_C")
		(layer "B.Cu")
		(hatch none 0.5)
		(connect_pads
			(clearance 0.5)
		)
		(min_thickness 0.25)
		(fill yes
			(thermal_gap 0.5)
			(thermal_bridge_width 0.5)
			(island_removal_mode 0)
		)
		(polygon
			(pts
				(xy 201.7649 -26.5811) (xy 201.7014 -26.6446) (xy 201.7014 -29.2354) (xy 201.803 -29.337) (xy 204.7494 -29.337)
				(xy 204.8256 -29.2608) (xy 204.8256 -26.6954) (xy 204.7113 -26.5811)
			)
		)
		(polygon
			(pts
				(xy 202.3618 -27.2288) (xy 202.1586 -27.2288) (xy 202.1586 -27.432) (xy 202.3618 -27.432)
			)
		)
	)
	(zone
		(net "GND")
		(layer "B.Cu")
		(hatch none 0.5)
		(connect_pads
			(clearance 0.5)
		)
		(min_thickness 0.25)
		(fill yes
			(thermal_gap 0.5)
			(thermal_bridge_width 0.5)
			(island_removal_mode 0)
		)
		(polygon
			(pts
				(xy 164.973 -81.6864) (xy 164.561266 -82.098134) (xy 164.561266 -93.466666) (xy 164.6936 -93.599)
				(xy 167.930576 -93.599) (xy 169.815002 -95.483426) (xy 169.815002 -95.67291) (xy 171.12361 -96.981518)
				(xy 172.264832 -96.981518) (xy 172.336968 -96.909382) (xy 172.336968 -95.161608) (xy 170.815254 -93.639894)
				(xy 170.815254 -87.180674) (xy 169.713656 -86.079076) (xy 169.713656 -81.956656) (xy 169.4434 -81.6864)
			)
		)
		(polygon
			(pts
				(xy 171.508674 -95.944182) (xy 171.305474 -95.944182) (xy 171.305474 -96.147382) (xy 171.508674 -96.147382)
			)
		)
	)
	(zone
		(layer "B.Cu")
		(hatch none 0.5)
		(connect_pads
			(clearance 0)
		)
		(min_thickness 0.25)
		(keepout
			(tracks not_allowed)
			(vias allowed)
			(pads allowed)
			(copperpour not_allowed)
			(footprints allowed)
		)
		(placement
			(enabled no)
			(sheetname "")
		)
		(fill
			(thermal_gap 0.5)
			(thermal_bridge_width 0.5)
			(island_removal_mode 0)
		)
		(polygon
			(pts
				(arc
					(start 25.980898 -9.92505)
					(mid 29.481018 -13.42517)
					(end 32.980884 -9.92505)
				)
				(arc
					(start 32.980884 -9.92505)
					(mid 29.481018 -6.425184)
					(end 25.980898 -9.92505)
				)
			)
		)
	)
	(zone
		(net "VDDA_SAS_REF_CLK")
		(layer "B.Cu")
		(hatch none 0.5)
		(connect_pads
			(clearance 0.5)
		)
		(min_thickness 0.25)
		(fill yes
			(thermal_gap 0.5)
			(thermal_bridge_width 0.5)
			(island_removal_mode 0)
		)
		(polygon
			(pts
				(xy 163.449 -59.182) (xy 163.322 -59.309) (xy 163.322 -64.643) (xy 162.941 -65.024) (xy 161.798 -65.024)
				(xy 161.671 -65.151) (xy 161.671 -66.421) (xy 161.8742 -66.6242) (xy 164.4523 -66.6242) (xy 164.719 -66.3575)
				(xy 164.719 -59.309) (xy 164.592 -59.182)
			)
		)
		(polygon
			(pts
				(xy 164.338 -65.9638) (xy 164.1348 -65.9638) (xy 164.1348 -66.167) (xy 164.338 -66.167)
			)
		)
		(polygon
			(pts
				(xy 163.7792 -65.9638) (xy 163.576 -65.9638) (xy 163.576 -66.167) (xy 163.7792 -66.167)
			)
		)
		(polygon
			(pts
				(xy 164.3126 -64.3382) (xy 164.1094 -64.3382) (xy 164.1094 -64.5414) (xy 164.3126 -64.5414)
			)
		)
		(polygon
			(pts
				(xy 164.3126 -63.4746) (xy 164.1094 -63.4746) (xy 164.1094 -63.6778) (xy 164.3126 -63.6778)
			)
		)
		(polygon
			(pts
				(xy 164.0332 -60.7568) (xy 163.83 -60.7568) (xy 163.83 -60.96) (xy 164.0332 -60.96)
			)
		)
		(polygon
			(pts
				(xy 164.0586 -59.8678) (xy 163.8554 -59.8678) (xy 163.8554 -60.071) (xy 163.83 -60.1472) (xy 163.83 -60.3504)
				(xy 164.0332 -60.3504) (xy 164.0332 -60.1472) (xy 164.0586 -60.071)
			)
		)
	)
	(zone
		(layer "B.Cu")
		(hatch none 0.5)
		(connect_pads
			(clearance 0)
		)
		(min_thickness 0.25)
		(keepout
			(tracks not_allowed)
			(vias allowed)
			(pads allowed)
			(copperpour not_allowed)
			(footprints allowed)
		)
		(placement
			(enabled no)
			(sheetname "")
		)
		(fill
			(thermal_gap 0.5)
			(thermal_bridge_width 0.5)
			(island_removal_mode 0)
		)
		(polygon
			(pts
				(arc
					(start 105.507536 -111.343948)
					(mid 105.930144 -110.714227)
					(end 105.639616 -111.414814)
				)
				(xy 105.581196 -111.523526)
				(arc
					(start 105.577386 -111.524796)
					(mid 105.477789 -111.592942)
					(end 105.357168 -111.59109)
				)
				(xy 105.354628 -111.592106) (xy 105.350818 -111.590074) (xy 105.345484 -111.59109) (xy 105.342182 -111.589058)
				(xy 105.341674 -111.589058) (xy 105.31983 -111.57458) (xy 105.296208 -111.562642) (xy 105.295954 -111.562388)
				(xy 105.291636 -111.560102) (xy 105.291128 -111.558832) (xy 105.28046 -111.553244) (xy 105.262934 -111.543592)
				(xy 105.260394 -111.543592) (xy 105.2576 -111.540798) (xy 105.253282 -111.538512) (xy 105.252266 -111.535464)
				(xy 105.21823 -111.500412) (xy 105.210102 -111.498634) (xy 105.197148 -111.478822) (xy 105.180638 -111.461804)
				(xy 105.180892 -111.453422) (xy 105.033572 -111.225584) (xy 104.895142 -111.484156) (xy 104.998266 -111.643668)
				(arc
					(start 105.057702 -111.703358)
					(mid 105.101413 -111.741727)
					(end 105.14965 -111.774224)
				)
				(xy 105.158032 -111.778796) (xy 105.170224 -111.785146) (xy 105.170732 -111.784892) (xy 105.174288 -111.786924)
				(xy 105.175304 -111.78667) (xy 105.189528 -111.795306) (xy 105.200704 -111.795306) (xy 105.213658 -111.80826)
				(xy 105.221786 -111.812324) (xy 105.22458 -111.813848) (xy 105.224834 -111.814102) (xy 105.230676 -111.81715)
				(arc
					(start 105.2322 -111.821722)
					(mid 105.301479 -111.921499)
					(end 105.300018 -112.042956)
				)
				(xy 105.301288 -112.04702) (xy 105.286556 -112.074198)
				(arc
					(start 105.242614 -112.15624)
					(mid 104.820006 -112.785961)
					(end 105.110534 -112.085374)
				)
				(arc
					(start 105.154476 -112.003332)
					(mid 105.159824 -111.972879)
					(end 105.146094 -111.945166)
				)
				(xy 105.138474 -111.945166) (xy 105.125012 -111.931704) (xy 105.1052 -111.921798) (xy 105.104946 -111.921544)
				(xy 105.101136 -111.919512) (xy 105.098342 -111.917988) (xy 105.097834 -111.916718) (xy 105.087928 -111.911384)
				(xy 105.0544 -111.893858)
				(arc
					(start 105.053638 -111.891318)
					(mid 105.012903 -111.862843)
					(end 104.974644 -111.83112)
				)
				(xy 104.973374 -111.83112) (xy 104.902254 -111.759492) (xy 104.893618 -111.757714) (xy 104.880918 -111.738156)
				(xy 104.864662 -111.7219) (xy 104.864662 -111.71301) (xy 104.814116 -111.635032)
				(arc
					(start 104.516428 -112.190784)
					(mid 104.740809 -112.933787)
					(end 105.48366 -112.709198)
				)
				(arc
					(start 106.233722 -111.30915)
					(mid 106.216796 -110.761613)
					(end 105.734612 -110.501684)
				)
				(arc
					(start 105.541064 -110.542832)
					(mid 105.382226 -110.643064)
					(end 105.26649 -110.79099)
				)
				(xy 105.125266 -111.054642) (xy 105.136696 -111.109252) (xy 105.315004 -111.384842) (xy 105.34523 -111.416084)
				(xy 105.353104 -111.42218) (xy 105.367582 -111.4298) (xy 105.371646 -111.429038) (xy 105.37571 -111.431578)
				(xy 105.376218 -111.431578) (xy 105.396538 -111.44504)
				(arc
					(start 105.40365 -111.448596)
					(mid 105.438085 -111.448072)
					(end 105.463848 -111.425228)
				)
			)
		)
	)
	(zone
		(net "GB_VDDA")
		(layer "B.Cu")
		(hatch none 0.5)
		(connect_pads
			(clearance 0.5)
		)
		(min_thickness 0.25)
		(fill yes
			(thermal_gap 0.5)
			(thermal_bridge_width 0.5)
			(island_removal_mode 0)
		)
		(polygon
			(pts
				(xy 70.993 -35.179) (xy 70.739 -35.433) (xy 70.739 -62.865) (xy 70.866 -62.992) (xy 71.628 -62.992)
				(xy 72.771 -61.849) (xy 81.03362 -61.849) (xy 81.89468 -60.98794) (xy 81.89468 -42.19448) (xy 77.089 -37.3888)
				(xy 77.089 -36.322) (xy 76.835 -36.068) (xy 72.517 -36.068) (xy 71.628 -35.179)
			)
		)
		(polygon
			(pts
				(xy 71.7296 -61.9506) (xy 71.5264 -61.9506) (xy 71.5264 -62.1538) (xy 71.7296 -62.1538)
			)
		)
		(polygon
			(pts
				(xy 76.8604 -60.8584) (xy 76.6572 -60.8584) (xy 76.6572 -61.0616) (xy 76.8604 -61.0616)
			)
		)
		(polygon
			(pts
				(xy 75.9968 -60.8584) (xy 75.7936 -60.8584) (xy 75.7936 -61.0616) (xy 75.9968 -61.0616)
			)
		)
		(polygon
			(pts
				(xy 76.9874 -58.4454) (xy 76.7842 -58.4454) (xy 76.7842 -58.6486) (xy 76.9874 -58.6486)
			)
		)
		(polygon
			(pts
				(xy 76.1238 -58.4454) (xy 75.9206 -58.4454) (xy 75.9206 -58.6486) (xy 76.1238 -58.6486)
			)
		)
		(polygon
			(pts
				(xy 76.9874 -57.5818) (xy 76.7842 -57.5818) (xy 76.7842 -57.785) (xy 76.9874 -57.785)
			)
		)
		(polygon
			(pts
				(xy 76.1238 -57.5818) (xy 75.9206 -57.5818) (xy 75.9206 -57.785) (xy 76.1238 -57.785)
			)
		)
		(polygon
			(pts
				(xy 71.8566 -57.3532) (xy 71.6534 -57.3532) (xy 71.6534 -57.5564) (xy 71.8566 -57.5564)
			)
		)
		(polygon
			(pts
				(xy 71.8566 -56.4896) (xy 71.6534 -56.4896) (xy 71.6534 -56.6928) (xy 71.8566 -56.6928)
			)
		)
		(polygon
			(pts
				(xy 76.1238 -56.1594) (xy 75.9206 -56.1594) (xy 75.9206 -56.3626) (xy 76.1238 -56.3626)
			)
		)
		(polygon
			(pts
				(xy 76.8604 -52.3494) (xy 76.6572 -52.3494) (xy 76.6572 -52.5526) (xy 76.8604 -52.5526)
			)
		)
		(polygon
			(pts
				(xy 75.9968 -52.3494) (xy 75.7936 -52.3494) (xy 75.7936 -52.5526) (xy 75.9968 -52.5526)
			)
		)
		(polygon
			(pts
				(xy 71.8566 -52.2732) (xy 71.6534 -52.2732) (xy 71.6534 -52.4764) (xy 71.8566 -52.4764)
			)
		)
		(polygon
			(pts
				(xy 71.8566 -51.4096) (xy 71.6534 -51.4096) (xy 71.6534 -51.6128) (xy 71.8566 -51.6128)
			)
		)
		(polygon
			(pts
				(xy 76.8604 -50.927) (xy 76.6572 -50.927) (xy 76.6572 -51.1302) (xy 76.8604 -51.1302)
			)
		)
		(polygon
			(pts
				(xy 75.9968 -50.927) (xy 75.7936 -50.927) (xy 75.7936 -51.1302) (xy 75.9968 -51.1302)
			)
		)
		(polygon
			(pts
				(xy 76.8604 -50.0634) (xy 76.6572 -50.0634) (xy 76.6572 -50.2666) (xy 76.8604 -50.2666)
			)
		)
		(polygon
			(pts
				(xy 75.9968 -50.0634) (xy 75.7936 -50.0634) (xy 75.7936 -50.2666) (xy 75.9968 -50.2666)
			)
		)
		(polygon
			(pts
				(xy 76.8604 -47.6504) (xy 76.6572 -47.6504) (xy 76.6572 -47.8536) (xy 76.8604 -47.8536)
			)
		)
		(polygon
			(pts
				(xy 75.9968 -47.6504) (xy 75.7936 -47.6504) (xy 75.7936 -47.8536) (xy 75.9968 -47.8536)
			)
		)
		(polygon
			(pts
				(xy 71.7296 -46.8122) (xy 71.5264 -46.8122) (xy 71.5264 -47.0154) (xy 71.7296 -47.0154)
			)
		)
		(polygon
			(pts
				(xy 71.7296 -45.9486) (xy 71.5264 -45.9486) (xy 71.5264 -46.1518) (xy 71.7296 -46.1518)
			)
		)
		(polygon
			(pts
				(xy 75.9968 -45.3644) (xy 75.7936 -45.3644) (xy 75.7936 -45.5676) (xy 75.9968 -45.5676)
			)
		)
		(polygon
			(pts
				(xy 76.1238 -42.1894) (xy 75.9206 -42.1894) (xy 75.9206 -42.3926) (xy 76.1238 -42.3926)
			)
		)
		(polygon
			(pts
				(xy 71.7296 -41.7322) (xy 71.5264 -41.7322) (xy 71.5264 -41.9354) (xy 71.7296 -41.9354)
			)
		)
		(polygon
			(pts
				(xy 71.7296 -40.8686) (xy 71.5264 -40.8686) (xy 71.5264 -41.0718) (xy 71.7296 -41.0718)
			)
		)
		(polygon
			(pts
				(xy 76.9874 -39.9034) (xy 76.7842 -39.9034) (xy 76.7842 -40.1066) (xy 76.9874 -40.1066)
			)
		)
		(polygon
			(pts
				(xy 76.1238 -39.9034) (xy 75.9206 -39.9034) (xy 75.9206 -40.1066) (xy 76.1238 -40.1066)
			)
		)
		(polygon
			(pts
				(xy 76.8604 -36.9824) (xy 76.6572 -36.9824) (xy 76.6572 -37.1856) (xy 76.8604 -37.1856)
			)
		)
		(polygon
			(pts
				(xy 75.9968 -36.9824) (xy 75.7936 -36.9824) (xy 75.7936 -37.1856) (xy 75.9968 -37.1856)
			)
		)
		(polygon
			(pts
				(xy 71.8566 -36.1442) (xy 71.6534 -36.1442) (xy 71.6534 -36.3474) (xy 71.8566 -36.3474)
			)
		)
	)
	(zone
		(layer "B.Cu")
		(hatch none 0.5)
		(connect_pads
			(clearance 0)
		)
		(min_thickness 0.25)
		(keepout
			(tracks not_allowed)
			(vias allowed)
			(pads allowed)
			(copperpour not_allowed)
			(footprints allowed)
		)
		(placement
			(enabled no)
			(sheetname "")
		)
		(fill
			(thermal_gap 0.5)
			(thermal_bridge_width 0.5)
			(island_removal_mode 0)
		)
		(polygon
			(pts
				(arc
					(start 99.358196 -54.000146)
					(mid 99.000056 -53.642006)
					(end 98.641916 -54.000146)
				)
				(xy 98.641916 -54.222142)
				(arc
					(start 98.866452 -54.222142)
					(mid 98.879747 -54.220557)
					(end 98.89236 -54.216046)
				)
				(arc
					(start 98.89236 -54.216046)
					(mid 99.023972 -53.760064)
					(end 99.063048 -54.233064)
				)
				(arc
					(start 99.063048 -54.233064)
					(mid 99.00027 -54.323426)
					(end 98.900234 -54.369208)
				)
				(xy 98.89744 -54.372002) (xy 98.641916 -54.372002) (xy 98.641916 -54.628542) (xy 98.89744 -54.628542)
				(arc
					(start 98.900234 -54.631336)
					(mid 99.000142 -54.677085)
					(end 99.063048 -54.767226)
				)
				(arc
					(start 99.063048 -54.767226)
					(mid 99.023604 -55.24032)
					(end 98.892106 -54.784244)
				)
				(arc
					(start 98.892106 -54.784244)
					(mid 98.879614 -54.779839)
					(end 98.866452 -54.778402)
				)
				(xy 98.641916 -54.778402)
				(arc
					(start 98.641916 -54.99989)
					(mid 98.999929 -55.358284)
					(end 99.358196 -55.000144)
				)
			)
		)
	)
	(zone
		(layer "B.Cu")
		(hatch none 0.5)
		(connect_pads
			(clearance 0)
		)
		(min_thickness 0.25)
		(keepout
			(tracks allowed)
			(vias allowed)
			(pads allowed)
			(copperpour allowed)
			(footprints not_allowed)
		)
		(placement
			(enabled no)
			(sheetname "")
		)
		(fill
			(thermal_gap 0.5)
			(thermal_bridge_width 0.5)
			(island_removal_mode 0)
		)
		(polygon
			(pts
				(arc
					(start 139.750038 -134.999984)
					(mid 134.999984 -130.24993)
					(end 130.24993 -134.999984)
				)
				(arc
					(start 130.24993 -134.999984)
					(mid 134.999984 -139.750038)
					(end 139.750038 -134.999984)
				)
			)
		)
	)
	(zone
		(net "P0V9")
		(layer "B.Cu")
		(hatch none 0.5)
		(connect_pads
			(clearance 0.5)
		)
		(min_thickness 0.25)
		(fill yes
			(thermal_gap 0.5)
			(thermal_bridge_width 0.5)
			(island_removal_mode 0)
		)
		(polygon
			(pts
				(xy 110.701328 -63.903098) (xy 110.557818 -64.046608) (xy 110.557818 -67.205098) (xy 110.235746 -67.52717)
				(xy 109.648498 -67.52717) (xy 109.576108 -67.59956) (xy 109.576108 -68.30441) (xy 110.3884 -69.116702)
				(xy 110.3884 -69.720714) (xy 110.956598 -70.288912) (xy 118.241318 -70.288912) (xy 118.282212 -70.329806)
				(xy 119.253762 -70.329806) (xy 119.306086 -70.277482) (xy 119.306086 -69.026278) (xy 119.048022 -68.768214)
				(xy 117.940074 -68.768214) (xy 117.939566 -68.768722) (xy 112.119918 -68.768722) (xy 111.510318 -68.159376)
				(xy 111.510318 -67.672712) (xy 111.901732 -67.281552) (xy 111.92764 -67.255644) (xy 119.031004 -67.255644)
				(xy 119.138446 -67.148202) (xy 119.138446 -66.6242) (xy 119.011446 -66.4972) (xy 117.790976 -66.4972)
				(xy 117.7544 -66.460624) (xy 111.79683 -66.460624) (xy 111.566198 -66.229992) (xy 111.566198 -65.648078)
				(xy 111.820452 -65.393824) (xy 119.049038 -65.393824) (xy 119.16156 -65.281302) (xy 119.16156 -64.7573)
				(xy 118.989348 -64.585088) (xy 111.89589 -64.585088) (xy 111.2139 -63.903098)
			)
		)
		(polygon
			(pts
				(xy 119.041672 -69.843396) (xy 118.607332 -69.843396) (xy 118.607332 -70.046596) (xy 119.041672 -70.046596)
			)
		)
		(polygon
			(pts
				(xy 118.454932 -69.843396) (xy 118.251732 -69.843396) (xy 118.251732 -70.046596) (xy 118.454932 -70.046596)
			)
		)
		(polygon
			(pts
				(xy 116.7892 -69.7992) (xy 116.586 -69.7992) (xy 116.586 -70.0024) (xy 116.7892 -70.0024)
			)
		)
		(polygon
			(pts
				(xy 116.4336 -69.7992) (xy 116.2304 -69.7992) (xy 116.2304 -70.0024) (xy 116.4336 -70.0024)
			)
		)
		(polygon
			(pts
				(xy 115.7732 -69.7992) (xy 115.57 -69.7992) (xy 115.57 -70.0024) (xy 115.7732 -70.0024)
			)
		)
		(polygon
			(pts
				(xy 115.4176 -69.7992) (xy 115.2144 -69.7992) (xy 115.2144 -70.0024) (xy 115.4176 -70.0024)
			)
		)
		(polygon
			(pts
				(xy 114.5794 -69.7992) (xy 114.3762 -69.7992) (xy 114.3762 -70.0024) (xy 114.5794 -70.0024)
			)
		)
		(polygon
			(pts
				(xy 114.2238 -69.7992) (xy 113.7412 -69.7992) (xy 113.7412 -70.0024) (xy 114.2238 -70.0024)
			)
		)
		(polygon
			(pts
				(xy 113.5888 -69.7992) (xy 113.3856 -69.7992) (xy 113.3856 -70.0024) (xy 113.5888 -70.0024)
			)
		)
		(polygon
			(pts
				(xy 112.6744 -69.7992) (xy 112.4712 -69.7992) (xy 112.4712 -70.0024) (xy 112.6744 -70.0024)
			)
		)
		(polygon
			(pts
				(xy 112.3188 -69.7992) (xy 111.8362 -69.7992) (xy 111.8362 -70.0024) (xy 112.3188 -70.0024)
			)
		)
		(polygon
			(pts
				(xy 111.6838 -69.7992) (xy 111.4806 -69.7992) (xy 111.4806 -70.0024) (xy 111.6838 -70.0024)
			)
		)
		(polygon
			(pts
				(xy 117.767862 -69.79158) (xy 117.564662 -69.79158) (xy 117.564662 -69.99478) (xy 117.767862 -69.99478)
			)
		)
		(polygon
			(pts
				(xy 117.412262 -69.79158) (xy 117.209062 -69.79158) (xy 117.209062 -69.99478) (xy 117.412262 -69.99478)
			)
		)
		(polygon
			(pts
				(xy 110.862618 -69.507862) (xy 110.659418 -69.507862) (xy 110.659418 -69.711062) (xy 110.862618 -69.711062)
			)
		)
		(polygon
			(pts
				(xy 118.500398 -69.290184) (xy 118.297198 -69.290184) (xy 118.297198 -69.493384) (xy 118.500398 -69.493384)
			)
		)
		(polygon
			(pts
				(xy 110.862618 -69.152262) (xy 110.659418 -69.152262) (xy 110.659418 -69.355462) (xy 110.862618 -69.355462)
			)
		)
		(polygon
			(pts
				(xy 117.6274 -69.0372) (xy 117.4242 -69.0372) (xy 117.4242 -69.2404) (xy 117.6274 -69.2404)
			)
		)
		(polygon
			(pts
				(xy 117.2718 -69.0372) (xy 116.7892 -69.0372) (xy 116.7892 -69.2404) (xy 117.2718 -69.2404)
			)
		)
		(polygon
			(pts
				(xy 116.6368 -69.0372) (xy 116.4336 -69.0372) (xy 116.4336 -69.2404) (xy 116.6368 -69.2404)
			)
		)
		(polygon
			(pts
				(xy 115.5954 -69.0372) (xy 115.3922 -69.0372) (xy 115.3922 -69.2404) (xy 115.5954 -69.2404)
			)
		)
		(polygon
			(pts
				(xy 115.2398 -69.0372) (xy 114.7572 -69.0372) (xy 114.7572 -69.2404) (xy 115.2398 -69.2404)
			)
		)
		(polygon
			(pts
				(xy 114.6048 -69.0372) (xy 114.4016 -69.0372) (xy 114.4016 -69.2404) (xy 114.6048 -69.2404)
			)
		)
		(polygon
			(pts
				(xy 113.5634 -69.0372) (xy 113.3602 -69.0372) (xy 113.3602 -69.2404) (xy 113.5634 -69.2404)
			)
		)
		(polygon
			(pts
				(xy 113.2078 -69.0372) (xy 112.7252 -69.0372) (xy 112.7252 -69.2404) (xy 113.2078 -69.2404)
			)
		)
		(polygon
			(pts
				(xy 112.5728 -69.0372) (xy 112.3696 -69.0372) (xy 112.3696 -69.2404) (xy 112.5728 -69.2404)
			)
		)
		(polygon
			(pts
				(xy 110.309406 -68.05676) (xy 110.106206 -68.05676) (xy 110.106206 -68.25996) (xy 110.309406 -68.25996)
			)
		)
		(polygon
			(pts
				(xy 117.6274 -66.7385) (xy 117.4242 -66.7385) (xy 117.4242 -66.9417) (xy 117.6274 -66.9417)
			)
		)
		(polygon
			(pts
				(xy 117.2718 -66.7385) (xy 116.7892 -66.7385) (xy 116.7892 -66.9417) (xy 117.2718 -66.9417)
			)
		)
		(polygon
			(pts
				(xy 116.6368 -66.7385) (xy 116.4336 -66.7385) (xy 116.4336 -66.9417) (xy 116.6368 -66.9417)
			)
		)
		(polygon
			(pts
				(xy 115.7351 -66.7385) (xy 115.5319 -66.7385) (xy 115.5319 -66.9417) (xy 115.7351 -66.9417)
			)
		)
		(polygon
			(pts
				(xy 115.3795 -66.7385) (xy 114.8969 -66.7385) (xy 114.8969 -66.9417) (xy 115.3795 -66.9417)
			)
		)
		(polygon
			(pts
				(xy 114.7445 -66.7385) (xy 114.5413 -66.7385) (xy 114.5413 -66.9417) (xy 114.7445 -66.9417)
			)
		)
		(polygon
			(pts
				(xy 113.538 -66.7385) (xy 113.3348 -66.7385) (xy 113.3348 -66.9417) (xy 113.538 -66.9417)
			)
		)
		(polygon
			(pts
				(xy 113.1824 -66.7385) (xy 112.6998 -66.7385) (xy 112.6998 -66.9417) (xy 113.1824 -66.9417)
			)
		)
		(polygon
			(pts
				(xy 112.5474 -66.7385) (xy 112.3442 -66.7385) (xy 112.3442 -66.9417) (xy 112.5474 -66.9417)
			)
		)
		(polygon
			(pts
				(xy 111.053372 -65.564258) (xy 110.850172 -65.564258) (xy 110.850172 -65.767458) (xy 111.053372 -65.767458)
			)
		)
		(polygon
			(pts
				(xy 111.053372 -65.208658) (xy 110.850172 -65.208658) (xy 110.850172 -65.411858) (xy 111.053372 -65.411858)
			)
		)
		(polygon
			(pts
				(xy 117.6147 -64.8589) (xy 117.4115 -64.8589) (xy 117.4115 -65.0621) (xy 117.6147 -65.0621)
			)
		)
		(polygon
			(pts
				(xy 117.2591 -64.8589) (xy 116.7765 -64.8589) (xy 116.7765 -65.0621) (xy 117.2591 -65.0621)
			)
		)
		(polygon
			(pts
				(xy 116.6241 -64.8589) (xy 116.4209 -64.8589) (xy 116.4209 -65.0621) (xy 116.6241 -65.0621)
			)
		)
		(polygon
			(pts
				(xy 115.5827 -64.8589) (xy 115.3795 -64.8589) (xy 115.3795 -65.0621) (xy 115.5827 -65.0621)
			)
		)
		(polygon
			(pts
				(xy 115.2271 -64.8589) (xy 114.7445 -64.8589) (xy 114.7445 -65.0621) (xy 115.2271 -65.0621)
			)
		)
		(polygon
			(pts
				(xy 114.5921 -64.8589) (xy 114.3889 -64.8589) (xy 114.3889 -65.0621) (xy 114.5921 -65.0621)
			)
		)
		(polygon
			(pts
				(xy 113.5634 -64.8589) (xy 113.3602 -64.8589) (xy 113.3602 -65.0621) (xy 113.5634 -65.0621)
			)
		)
		(polygon
			(pts
				(xy 113.2078 -64.8589) (xy 112.7252 -64.8589) (xy 112.7252 -65.0621) (xy 113.2078 -65.0621)
			)
		)
		(polygon
			(pts
				(xy 112.5728 -64.8589) (xy 112.3696 -64.8589) (xy 112.3696 -65.0621) (xy 112.5728 -65.0621)
			)
		)
		(polygon
			(pts
				(xy 111.358172 -64.541654) (xy 111.154972 -64.541654) (xy 111.154972 -64.744854) (xy 111.358172 -64.744854)
			)
		)
	)
	(zone
		(layer "B.Cu")
		(hatch none 0.5)
		(connect_pads
			(clearance 0)
		)
		(min_thickness 0.25)
		(keepout
			(tracks not_allowed)
			(vias allowed)
			(pads allowed)
			(copperpour not_allowed)
			(footprints allowed)
		)
		(placement
			(enabled no)
			(sheetname "")
		)
		(fill
			(thermal_gap 0.5)
			(thermal_bridge_width 0.5)
			(island_removal_mode 0)
		)
		(polygon
			(pts
				(arc
					(start 102.35819 -55.000144)
					(mid 102.040566 -54.644303)
					(end 101.651054 -54.919626)
				)
				(arc
					(start 101.651054 -55.237634)
					(mid 101.65943 -55.279834)
					(end 101.683312 -55.315612)
				)
				(arc
					(start 101.683312 -55.315612)
					(mid 101.719103 -55.339464)
					(end 101.76129 -55.34787)
				)
				(arc
					(start 101.91115 -55.34787)
					(mid 101.933601 -55.338571)
					(end 101.9429 -55.31612)
				)
				(arc
					(start 101.9429 -55.234586)
					(mid 102.00005 -54.758837)
					(end 102.0572 -55.234586)
				)
				(xy 102.0572 -55.339742)
				(arc
					(start 102.054914 -55.342028)
					(mid 102.014444 -55.419414)
					(end 101.937058 -55.459884)
				)
				(xy 101.934772 -55.46217) (xy 101.737668 -55.46217)
				(arc
					(start 101.736144 -55.460646)
					(mid 101.687192 -55.449546)
					(end 101.64191 -55.42788)
				)
				(arc
					(start 101.64191 -55.513732)
					(mid 101.700092 -55.532094)
					(end 101.760782 -55.53837)
				)
				(xy 101.934772 -55.53837)
				(arc
					(start 101.937058 -55.540656)
					(mid 102.014444 -55.581126)
					(end 102.054914 -55.658512)
				)
				(xy 102.0572 -55.660798)
				(arc
					(start 102.0572 -55.7657)
					(mid 102.00005 -56.241449)
					(end 101.9429 -55.7657)
				)
				(arc
					(start 101.9429 -55.68442)
					(mid 101.933601 -55.661969)
					(end 101.91115 -55.65267)
				)
				(xy 101.737668 -55.65267)
				(arc
					(start 101.736906 -55.651908)
					(mid 101.688918 -55.646299)
					(end 101.64191 -55.635144)
				)
				(arc
					(start 101.64191 -55.999888)
					(mid 101.999923 -56.358282)
					(end 102.35819 -56.000142)
				)
			)
		)
	)
	(zone
		(layer "B.Cu")
		(hatch none 0.5)
		(connect_pads
			(clearance 0)
		)
		(min_thickness 0.25)
		(keepout
			(tracks allowed)
			(vias allowed)
			(pads allowed)
			(copperpour allowed)
			(footprints allowed)
		)
		(placement
			(enabled no)
			(sheetname "")
		)
		(fill
			(thermal_gap 0.5)
			(thermal_bridge_width 0.5)
			(island_removal_mode 0)
		)
		(polygon
			(pts
				(xy 168.842436 -21.47189) (xy 169.685208 -21.47189) (xy 169.794174 -21.362924) (xy 169.794174 -20.48383)
				(xy 169.701464 -20.39112) (xy 168.923208 -20.39112) (xy 168.769792 -20.544536) (xy 168.769792 -21.399246)
			)
		)
	)
	(zone
		(layer "B.Cu")
		(hatch none 0.5)
		(connect_pads
			(clearance 0)
		)
		(min_thickness 0.25)
		(keepout
			(tracks allowed)
			(vias allowed)
			(pads allowed)
			(copperpour allowed)
			(footprints allowed)
		)
		(placement
			(enabled no)
			(sheetname "")
		)
		(fill
			(thermal_gap 0.5)
			(thermal_bridge_width 0.5)
			(island_removal_mode 0)
		)
		(polygon
			(pts
				(xy 183.162956 -74.23277) (xy 183.162956 -67.556888) (xy 182.747158 -67.556888) (xy 182.747158 -66.29527)
				(xy 183.162956 -66.29527) (xy 183.162956 -60.372498) (xy 184.9501 -60.372498) (xy 184.9501 -61.257434)
				(xy 186.01944 -61.257434) (xy 186.01944 -65.962276) (xy 184.9501 -65.962276) (xy 184.9501 -69.326252)
				(xy 186.00166 -69.326252) (xy 186.00166 -73.378314) (xy 184.9501 -73.378314) (xy 184.9501 -74.23277)
			)
		)
	)
	(zone
		(layer "B.Cu")
		(hatch none 0.5)
		(connect_pads
			(clearance 0)
		)
		(min_thickness 0.25)
		(keepout
			(tracks not_allowed)
			(vias allowed)
			(pads allowed)
			(copperpour not_allowed)
			(footprints allowed)
		)
		(placement
			(enabled no)
			(sheetname "")
		)
		(fill
			(thermal_gap 0.5)
			(thermal_bridge_width 0.5)
			(island_removal_mode 0)
		)
		(polygon
			(pts
				(arc
					(start 170.35526 -30.07741)
					(mid 170.009233 -30.096837)
					(end 169.841672 -30.400244)
				)
				(arc
					(start 169.841926 -31.199836)
					(mid 170.200066 -31.55823)
					(end 170.558206 -31.199836)
				)
				(xy 170.558206 -31.031688) (xy 170.558206 -30.897576) (xy 170.557952 -30.726888)
				(arc
					(start 170.372786 -31.031688)
					(mid 170.074924 -31.40632)
					(end 170.269662 -30.969204)
				)
				(xy 170.539664 -30.524958)
				(arc
					(start 170.539664 -30.286706)
					(mid 170.513189 -30.226505)
					(end 170.476164 -30.172152)
				)
				(xy 170.476164 -30.208982) (xy 170.47591 -30.208982)
				(arc
					(start 170.407584 -30.277562)
					(mid 170.029287 -30.570515)
					(end 170.32224 -30.192218)
				)
				(xy 170.35526 -30.159198)
			)
		)
	)
	(zone
		(layer "B.Cu")
		(hatch none 0.5)
		(connect_pads
			(clearance 0)
		)
		(min_thickness 0.25)
		(keepout
			(tracks not_allowed)
			(vias allowed)
			(pads allowed)
			(copperpour not_allowed)
			(footprints allowed)
		)
		(placement
			(enabled no)
			(sheetname "")
		)
		(fill
			(thermal_gap 0.5)
			(thermal_bridge_width 0.5)
			(island_removal_mode 0)
		)
		(polygon
			(pts
				(arc
					(start 189.561216 -9.800082)
					(mid 188.999876 -9.238742)
					(end 188.438536 -9.800082)
				)
				(xy 188.438536 -10.26414) (xy 188.489336 -10.259568) (xy 188.490098 -10.258552) (xy 188.512704 -10.258552)
				(xy 188.525658 -10.258552) (xy 188.53023 -10.258552) (xy 188.819282 -10.258552)
				(arc
					(start 188.823854 -10.258552)
					(mid 188.881883 -10.237399)
					(end 188.912754 -10.183876)
				)
				(arc
					(start 188.912754 -10.183876)
					(mid 189.001555 -9.406413)
					(end 189.085728 -10.184384)
				)
				(xy 189.085728 -10.203942)
				(arc
					(start 189.082934 -10.206482)
					(mid 189.009022 -10.35355)
					(end 188.861954 -10.427462)
				)
				(xy 188.859414 -10.430256) (xy 188.831982 -10.430256) (xy 188.823854 -10.430256) (xy 188.819282 -10.430256)
				(xy 188.53023 -10.430256)
				(arc
					(start 188.525658 -10.430256)
					(mid 188.481929 -10.432144)
					(end 188.438536 -10.437876)
				)
				(arc
					(start 188.438536 -10.580624)
					(mid 188.463269 -10.575291)
					(end 188.48832 -10.571734)
				)
				(xy 188.490098 -10.569956) (xy 188.51626 -10.569956) (xy 188.525658 -10.569702) (xy 188.53023 -10.569956)
				(xy 188.819028 -10.569956) (xy 188.8236 -10.569702) (xy 188.831728 -10.569956) (xy 188.85916 -10.569956)
				(arc
					(start 188.8617 -10.572496)
					(mid 189.008945 -10.646485)
					(end 189.082934 -10.79373)
				)
				(xy 189.085728 -10.79627)
				(arc
					(start 189.085728 -10.815828)
					(mid 189.001555 -11.593793)
					(end 188.912754 -10.816336)
				)
				(arc
					(start 188.912754 -10.816336)
					(mid 188.881851 -10.762582)
					(end 188.8236 -10.741406)
				)
				(xy 188.819028 -10.741152) (xy 188.53023 -10.741152)
				(arc
					(start 188.525658 -10.741406)
					(mid 188.480749 -10.74695)
					(end 188.438536 -10.76325)
				)
				(arc
					(start 188.438536 -11.199876)
					(mid 188.999749 -11.76147)
					(end 189.561216 -11.20013)
				)
			)
		)
	)
	(zone
		(net "P0V9")
		(layer "B.Cu")
		(hatch none 0.5)
		(connect_pads
			(clearance 0.5)
		)
		(min_thickness 0.25)
		(fill yes
			(thermal_gap 0.5)
			(thermal_bridge_width 0.5)
			(island_removal_mode 0)
		)
		(polygon
			(pts
				(xy 64.048386 -32.887666) (xy 62.281054 -34.654998) (xy 62.281054 -63.32982) (xy 63.029846 -64.078612)
				(xy 69.96303 -64.078612) (xy 70.358 -63.683642) (xy 70.358 -33.539684) (xy 69.705982 -32.887666)
			)
		)
		(polygon
			(pts
				(xy 69.4436 -62.8142) (xy 69.2404 -62.8142) (xy 69.2404 -63.0174) (xy 69.4436 -63.0174)
			)
		)
		(polygon
			(pts
				(xy 69.4436 -61.9506) (xy 69.2404 -61.9506) (xy 69.2404 -62.1538) (xy 69.4436 -62.1538)
			)
		)
		(polygon
			(pts
				(xy 69.5706 -57.3532) (xy 69.3674 -57.3532) (xy 69.3674 -57.5564) (xy 69.5706 -57.5564)
			)
		)
		(polygon
			(pts
				(xy 69.5706 -56.4896) (xy 69.3674 -56.4896) (xy 69.3674 -56.6928) (xy 69.5706 -56.6928)
			)
		)
		(polygon
			(pts
				(xy 69.5706 -52.2732) (xy 69.3674 -52.2732) (xy 69.3674 -52.4764) (xy 69.5706 -52.4764)
			)
		)
		(polygon
			(pts
				(xy 69.5706 -51.4096) (xy 69.3674 -51.4096) (xy 69.3674 -51.6128) (xy 69.5706 -51.6128)
			)
		)
		(polygon
			(pts
				(xy 69.4436 -46.8122) (xy 69.2404 -46.8122) (xy 69.2404 -47.0154) (xy 69.4436 -47.0154)
			)
		)
		(polygon
			(pts
				(xy 69.4436 -45.9486) (xy 69.2404 -45.9486) (xy 69.2404 -46.1518) (xy 69.4436 -46.1518)
			)
		)
		(polygon
			(pts
				(xy 69.4436 -41.7322) (xy 69.2404 -41.7322) (xy 69.2404 -41.9354) (xy 69.4436 -41.9354)
			)
		)
		(polygon
			(pts
				(xy 69.4436 -40.8686) (xy 69.2404 -40.8686) (xy 69.2404 -41.0718) (xy 69.4436 -41.0718)
			)
		)
		(polygon
			(pts
				(xy 69.5706 -36.1442) (xy 69.3674 -36.1442) (xy 69.3674 -36.3474) (xy 69.5706 -36.3474)
			)
		)
		(polygon
			(pts
				(xy 69.5706 -35.2806) (xy 69.3674 -35.2806) (xy 69.3674 -35.4838) (xy 69.5706 -35.4838)
			)
		)
	)
	(zone
		(layer "B.Cu")
		(hatch none 0.5)
		(connect_pads
			(clearance 0)
		)
		(min_thickness 0.25)
		(keepout
			(tracks not_allowed)
			(vias allowed)
			(pads allowed)
			(copperpour not_allowed)
			(footprints allowed)
		)
		(placement
			(enabled no)
			(sheetname "")
		)
		(fill
			(thermal_gap 0.5)
			(thermal_bridge_width 0.5)
			(island_removal_mode 0)
		)
		(polygon
			(pts
				(arc
					(start 118.961408 -3.800094)
					(mid 118.400068 -3.238754)
					(end 117.838728 -3.800094)
				)
				(arc
					(start 117.838728 -4.228592)
					(mid 117.87168 -4.224901)
					(end 117.904768 -4.22275)
				)
				(xy 117.90553 -4.221988)
				(arc
					(start 118.280942 -4.221988)
					(mid 118.297855 -4.218624)
					(end 118.312184 -4.209034)
				)
				(arc
					(start 118.312184 -4.209034)
					(mid 118.31995 -4.198635)
					(end 118.324376 -4.186428)
				)
				(arc
					(start 118.324376 -4.186428)
					(mid 118.40097 -3.406367)
					(end 118.474998 -4.186682)
				)
				(xy 118.474998 -4.20878)
				(arc
					(start 118.47195 -4.211828)
					(mid 118.453019 -4.267359)
					(end 118.418356 -4.314698)
				)
				(arc
					(start 118.418356 -4.314698)
					(mid 118.37084 -4.349728)
					(end 118.314978 -4.3688)
				)
				(xy 118.31193 -4.371848)
				(arc
					(start 117.936518 -4.371848)
					(mid 117.887434 -4.37403)
					(end 117.838728 -4.380484)
				)
				(arc
					(start 117.838728 -4.64439)
					(mid 117.870853 -4.635509)
					(end 117.903752 -4.630166)
				)
				(xy 117.90553 -4.628388) (xy 118.31193 -4.628388)
				(arc
					(start 118.314978 -4.631436)
					(mid 118.370827 -4.650533)
					(end 118.418356 -4.685538)
				)
				(arc
					(start 118.418356 -4.685538)
					(mid 118.453044 -4.732864)
					(end 118.47195 -4.788408)
				)
				(xy 118.474998 -4.791456)
				(arc
					(start 118.474998 -4.813554)
					(mid 118.40097 -5.593876)
					(end 118.324376 -4.813808)
				)
				(arc
					(start 118.324376 -4.813808)
					(mid 118.319978 -4.801586)
					(end 118.312184 -4.791202)
				)
				(arc
					(start 118.312184 -4.791202)
					(mid 118.29785 -4.781624)
					(end 118.280942 -4.778248)
				)
				(arc
					(start 117.936518 -4.778248)
					(mid 117.884785 -4.786928)
					(end 117.838728 -4.81203)
				)
				(arc
					(start 117.838728 -5.199888)
					(mid 118.399941 -5.761482)
					(end 118.961408 -5.200142)
				)
			)
		)
	)
	(zone
		(net "P3V3")
		(layer "B.Cu")
		(hatch none 0.5)
		(connect_pads
			(clearance 0.5)
		)
		(min_thickness 0.25)
		(fill yes
			(thermal_gap 0.5)
			(thermal_bridge_width 0.5)
			(island_removal_mode 0)
		)
		(polygon
			(pts
				(xy 78.613 -70.5358) (xy 76.7334 -72.4154) (xy 76.7334 -73.690226) (xy 76.90612 -73.862946) (xy 78.176882 -73.862946)
				(xy 78.964028 -73.0758) (xy 79.7814 -73.0758) (xy 79.9846 -73.279) (xy 79.9846 -73.8632) (xy 80.1116 -73.9902)
				(xy 82.4484 -73.9902) (xy 82.8929 -73.5457) (xy 82.8929 -70.5739) (xy 82.8548 -70.5358)
			)
		)
		(polygon
			(pts
				(xy 80.6958 -73.279) (xy 80.4926 -73.279) (xy 80.4926 -73.4822) (xy 80.6958 -73.4822)
			)
		)
		(polygon
			(pts
				(xy 82.419698 -71.06158) (xy 81.937098 -71.06158) (xy 81.937098 -71.26478) (xy 82.419698 -71.26478)
			)
		)
		(polygon
			(pts
				(xy 81.530698 -71.06158) (xy 81.327498 -71.06158) (xy 81.327498 -71.26478) (xy 81.530698 -71.26478)
			)
		)
	)
	(zone
		(net "P1V8_E")
		(layer "B.Cu")
		(hatch none 0.5)
		(connect_pads
			(clearance 0.5)
		)
		(min_thickness 0.25)
		(fill yes
			(thermal_gap 0.5)
			(thermal_bridge_width 0.5)
			(island_removal_mode 0)
		)
		(polygon
			(pts
				(xy 87.691214 -62.062106) (xy 87.426292 -62.327028) (xy 87.426292 -66.878708) (xy 86.5886 -67.7164)
				(xy 86.5886 -73.7616) (xy 86.6648 -73.8378) (xy 87.3252 -73.8378) (xy 87.376 -73.787) (xy 87.376 -72.0852)
				(xy 87.6808 -71.7804) (xy 88.3412 -71.7804) (xy 88.4682 -71.6534) (xy 88.4682 -71.137018) (xy 88.591644 -71.013574)
				(xy 91.311222 -71.013574) (xy 91.376246 -70.94855) (xy 91.376246 -68.026026) (xy 91.31046 -67.96024)
				(xy 88.792558 -67.96024) (xy 88.400128 -67.56781) (xy 88.400128 -63.999872) (xy 88.506554 -63.893446)
				(xy 91.196922 -63.893446) (xy 91.263978 -63.82639) (xy 91.263978 -62.558168) (xy 90.767916 -62.062106)
			)
		)
		(polygon
			(pts
				(xy 87.3252 -70.75678) (xy 87.122 -70.75678) (xy 87.122 -70.95998) (xy 87.3252 -70.95998)
			)
		)
		(polygon
			(pts
				(xy 90.841068 -70.380098) (xy 90.637868 -70.380098) (xy 90.637868 -70.583298) (xy 90.841068 -70.583298)
			)
		)
		(polygon
			(pts
				(xy 87.3252 -70.14718) (xy 87.122 -70.14718) (xy 87.122 -70.35038) (xy 87.3252 -70.35038)
			)
		)
		(polygon
			(pts
				(xy 90.797126 -68.444872) (xy 90.593926 -68.444872) (xy 90.593926 -68.648072) (xy 90.797126 -68.648072)
			)
		)
		(polygon
			(pts
				(xy 90.829892 -63.231776) (xy 90.626692 -63.231776) (xy 90.626692 -63.434976) (xy 90.829892 -63.434976)
			)
		)
	)
	(zone
		(layer "B.Cu")
		(hatch none 0.5)
		(connect_pads
			(clearance 0)
		)
		(min_thickness 0.25)
		(keepout
			(tracks not_allowed)
			(vias allowed)
			(pads allowed)
			(copperpour not_allowed)
			(footprints allowed)
		)
		(placement
			(enabled no)
			(sheetname "")
		)
		(fill
			(thermal_gap 0.5)
			(thermal_bridge_width 0.5)
			(island_removal_mode 0)
		)
		(polygon
			(pts
				(arc
					(start 117.35816 -55.000144)
					(mid 117.042617 -54.644546)
					(end 116.65204 -54.915562)
				)
				(arc
					(start 116.65204 -55.240174)
					(mid 116.660161 -55.280999)
					(end 116.683282 -55.315612)
				)
				(arc
					(start 116.683282 -55.315612)
					(mid 116.719073 -55.339464)
					(end 116.76126 -55.34787)
				)
				(arc
					(start 116.91112 -55.34787)
					(mid 116.933571 -55.338571)
					(end 116.94287 -55.31612)
				)
				(arc
					(start 116.94287 -55.234586)
					(mid 117.00002 -54.758837)
					(end 117.05717 -55.234586)
				)
				(xy 117.05717 -55.339742)
				(arc
					(start 117.054884 -55.342028)
					(mid 117.014414 -55.419414)
					(end 116.937028 -55.459884)
				)
				(xy 116.934742 -55.46217) (xy 116.737638 -55.46217)
				(arc
					(start 116.736114 -55.460646)
					(mid 116.687162 -55.449546)
					(end 116.64188 -55.42788)
				)
				(arc
					(start 116.64188 -55.513732)
					(mid 116.700062 -55.532094)
					(end 116.760752 -55.53837)
				)
				(xy 116.934742 -55.53837)
				(arc
					(start 116.937028 -55.540656)
					(mid 117.014414 -55.581126)
					(end 117.054884 -55.658512)
				)
				(xy 117.05717 -55.660798)
				(arc
					(start 117.05717 -55.7657)
					(mid 117.00002 -56.241449)
					(end 116.94287 -55.7657)
				)
				(arc
					(start 116.94287 -55.68442)
					(mid 116.933571 -55.661969)
					(end 116.91112 -55.65267)
				)
				(xy 116.737638 -55.65267)
				(arc
					(start 116.736876 -55.651908)
					(mid 116.688888 -55.646299)
					(end 116.64188 -55.635144)
				)
				(arc
					(start 116.64188 -55.999888)
					(mid 116.999893 -56.358282)
					(end 117.35816 -56.000142)
				)
			)
		)
	)
	(zone
		(layer "B.Cu")
		(hatch none 0.5)
		(connect_pads
			(clearance 0)
		)
		(min_thickness 0.25)
		(keepout
			(tracks not_allowed)
			(vias allowed)
			(pads allowed)
			(copperpour not_allowed)
			(footprints allowed)
		)
		(placement
			(enabled no)
			(sheetname "")
		)
		(fill
			(thermal_gap 0.5)
			(thermal_bridge_width 0.5)
			(island_removal_mode 0)
		)
		(polygon
			(pts
				(arc
					(start 115.361466 -3.800094)
					(mid 114.800126 -3.238754)
					(end 114.238786 -3.800094)
				)
				(arc
					(start 114.238786 -4.228592)
					(mid 114.271738 -4.224901)
					(end 114.304826 -4.22275)
				)
				(xy 114.305588 -4.221988)
				(arc
					(start 114.681 -4.221988)
					(mid 114.697913 -4.218624)
					(end 114.712242 -4.209034)
				)
				(arc
					(start 114.712242 -4.209034)
					(mid 114.720008 -4.198635)
					(end 114.724434 -4.186428)
				)
				(arc
					(start 114.724434 -4.186428)
					(mid 114.801028 -3.406367)
					(end 114.875056 -4.186682)
				)
				(xy 114.875056 -4.20878)
				(arc
					(start 114.872008 -4.211828)
					(mid 114.853077 -4.267359)
					(end 114.818414 -4.314698)
				)
				(arc
					(start 114.818414 -4.314698)
					(mid 114.770898 -4.349728)
					(end 114.715036 -4.3688)
				)
				(xy 114.711988 -4.371848)
				(arc
					(start 114.336576 -4.371848)
					(mid 114.287492 -4.37403)
					(end 114.238786 -4.380484)
				)
				(arc
					(start 114.238786 -4.64439)
					(mid 114.270911 -4.635509)
					(end 114.30381 -4.630166)
				)
				(xy 114.305588 -4.628388) (xy 114.711988 -4.628388)
				(arc
					(start 114.715036 -4.631436)
					(mid 114.770885 -4.650533)
					(end 114.818414 -4.685538)
				)
				(arc
					(start 114.818414 -4.685538)
					(mid 114.853102 -4.732864)
					(end 114.872008 -4.788408)
				)
				(xy 114.875056 -4.791456)
				(arc
					(start 114.875056 -4.813554)
					(mid 114.801028 -5.593876)
					(end 114.724434 -4.813808)
				)
				(arc
					(start 114.724434 -4.813808)
					(mid 114.720036 -4.801586)
					(end 114.712242 -4.791202)
				)
				(arc
					(start 114.712242 -4.791202)
					(mid 114.697908 -4.781624)
					(end 114.681 -4.778248)
				)
				(arc
					(start 114.336576 -4.778248)
					(mid 114.284843 -4.786928)
					(end 114.238786 -4.81203)
				)
				(arc
					(start 114.238786 -5.199888)
					(mid 114.799999 -5.761482)
					(end 115.361466 -5.200142)
				)
			)
		)
	)
	(zone
		(layer "B.Cu")
		(hatch none 0.5)
		(connect_pads
			(clearance 0)
		)
		(min_thickness 0.25)
		(keepout
			(tracks not_allowed)
			(vias allowed)
			(pads allowed)
			(copperpour not_allowed)
			(footprints allowed)
		)
		(placement
			(enabled no)
			(sheetname "")
		)
		(fill
			(thermal_gap 0.5)
			(thermal_bridge_width 0.5)
			(island_removal_mode 0)
		)
		(polygon
			(pts
				(arc
					(start 126.000256 -70.641972)
					(mid 125.641862 -70.999985)
					(end 126.000002 -71.358252)
				)
				(arc
					(start 127 -71.358252)
					(mid 127.35521 -71.045827)
					(end 127.090678 -70.653656)
				)
				(arc
					(start 126.74854 -70.653656)
					(mid 126.68047 -70.681852)
					(end 126.652274 -70.749922)
				)
				(arc
					(start 126.652274 -70.900036)
					(mid 126.664847 -70.930389)
					(end 126.6952 -70.942962)
				)
				(arc
					(start 126.765558 -70.942962)
					(mid 127.241307 -71.000112)
					(end 126.765558 -71.057262)
				)
				(xy 126.671578 -71.057262)
				(arc
					(start 126.669292 -71.05523)
					(mid 126.583943 -71.011293)
					(end 126.540006 -70.925944)
				)
				(xy 126.537974 -70.923658) (xy 126.537974 -70.7263)
				(arc
					(start 126.539498 -70.724776)
					(mid 126.549232 -70.681886)
					(end 126.567692 -70.641972)
				)
				(arc
					(start 126.482856 -70.641972)
					(mid 126.467099 -70.694928)
					(end 126.461774 -70.749922)
				)
				(xy 126.461774 -70.923912)
				(arc
					(start 126.459742 -70.926198)
					(mid 126.415882 -71.01137)
					(end 126.33071 -71.05523)
				)
				(xy 126.328424 -71.057262)
				(arc
					(start 126.234444 -71.057262)
					(mid 125.758695 -71.000112)
					(end 126.234444 -70.942962)
				)
				(arc
					(start 126.304802 -70.942962)
					(mid 126.334976 -70.930464)
					(end 126.347474 -70.90029)
				)
				(xy 126.347474 -70.7263)
				(arc
					(start 126.348236 -70.725538)
					(mid 126.352998 -70.683383)
					(end 126.362206 -70.641972)
				)
			)
		)
	)
	(zone
		(layer "B.Cu")
		(hatch none 0.5)
		(connect_pads
			(clearance 0)
		)
		(min_thickness 0.25)
		(keepout
			(tracks not_allowed)
			(vias allowed)
			(pads allowed)
			(copperpour not_allowed)
			(footprints allowed)
		)
		(placement
			(enabled no)
			(sheetname "")
		)
		(fill
			(thermal_gap 0.5)
			(thermal_bridge_width 0.5)
			(island_removal_mode 0)
		)
		(polygon
			(pts
				(arc
					(start 126.000256 -72.641968)
					(mid 125.641862 -72.999981)
					(end 126.000002 -73.358248)
				)
				(arc
					(start 127 -73.358248)
					(mid 127.35552 -73.043347)
					(end 127.085852 -72.652382)
				)
				(arc
					(start 126.74981 -72.652382)
					(mid 126.680842 -72.68095)
					(end 126.652274 -72.749918)
				)
				(arc
					(start 126.652274 -72.900032)
					(mid 126.664847 -72.930385)
					(end 126.6952 -72.942958)
				)
				(arc
					(start 126.765558 -72.942958)
					(mid 127.241307 -73.000108)
					(end 126.765558 -73.057258)
				)
				(xy 126.671578 -73.057258)
				(arc
					(start 126.669292 -73.055226)
					(mid 126.583943 -73.011289)
					(end 126.540006 -72.92594)
				)
				(xy 126.537974 -72.923654) (xy 126.537974 -72.726296)
				(arc
					(start 126.539498 -72.724772)
					(mid 126.549158 -72.681917)
					(end 126.567438 -72.641968)
				)
				(arc
					(start 126.482856 -72.641968)
					(mid 126.467108 -72.694927)
					(end 126.461774 -72.749918)
				)
				(xy 126.461774 -72.923908)
				(arc
					(start 126.459742 -72.926194)
					(mid 126.415882 -73.011366)
					(end 126.33071 -73.055226)
				)
				(xy 126.328424 -73.057258)
				(arc
					(start 126.234444 -73.057258)
					(mid 125.758695 -73.000108)
					(end 126.234444 -72.942958)
				)
				(arc
					(start 126.304802 -72.942958)
					(mid 126.334976 -72.93046)
					(end 126.347474 -72.900286)
				)
				(xy 126.347474 -72.726296)
				(arc
					(start 126.348236 -72.725534)
					(mid 126.35301 -72.683381)
					(end 126.362206 -72.641968)
				)
			)
		)
	)
	(zone
		(layer "B.Cu")
		(hatch none 0.5)
		(connect_pads
			(clearance 0)
		)
		(min_thickness 0.25)
		(keepout
			(tracks not_allowed)
			(vias allowed)
			(pads allowed)
			(copperpour not_allowed)
			(footprints allowed)
		)
		(placement
			(enabled no)
			(sheetname "")
		)
		(fill
			(thermal_gap 0.5)
			(thermal_bridge_width 0.5)
			(island_removal_mode 0)
		)
		(polygon
			(pts
				(arc
					(start 126.000256 -75.641962)
					(mid 125.641862 -75.999975)
					(end 126.000002 -76.358242)
				)
				(arc
					(start 126.369064 -76.358242)
					(mid 126.355081 -76.304442)
					(end 126.348236 -76.249276)
				)
				(xy 126.347474 -76.248514)
				(arc
					(start 126.347474 -76.089002)
					(mid 126.338175 -76.066551)
					(end 126.315724 -76.057252)
				)
				(arc
					(start 126.234444 -76.057252)
					(mid 125.758695 -76.000102)
					(end 126.234444 -75.942952)
				)
				(xy 126.339346 -75.942952)
				(arc
					(start 126.341632 -75.945238)
					(mid 126.419018 -75.985708)
					(end 126.459488 -76.063094)
				)
				(xy 126.461774 -76.06538)
				(arc
					(start 126.461774 -76.224892)
					(mid 126.469464 -76.293247)
					(end 126.492 -76.358242)
				)
				(arc
					(start 126.579884 -76.358242)
					(mid 126.552762 -76.306565)
					(end 126.539244 -76.249784)
				)
				(xy 126.537974 -76.248514) (xy 126.537974 -76.06538)
				(arc
					(start 126.54026 -76.063094)
					(mid 126.58073 -75.985708)
					(end 126.658116 -75.945238)
				)
				(xy 126.660402 -75.942952)
				(arc
					(start 126.765558 -75.942952)
					(mid 127.241307 -76.000102)
					(end 126.765558 -76.057252)
				)
				(arc
					(start 126.684024 -76.057252)
					(mid 126.661573 -76.066551)
					(end 126.652274 -76.089002)
				)
				(arc
					(start 126.652274 -76.224892)
					(mid 126.68724 -76.309306)
					(end 126.771654 -76.344272)
				)
				(arc
					(start 127.09906 -76.344272)
					(mid 127.354632 -75.950082)
					(end 127 -75.641962)
				)
			)
		)
	)
	(zone
		(layer "B.Cu")
		(hatch none 0.5)
		(connect_pads
			(clearance 0)
		)
		(min_thickness 0.25)
		(keepout
			(tracks not_allowed)
			(vias allowed)
			(pads allowed)
			(copperpour not_allowed)
			(footprints allowed)
		)
		(placement
			(enabled no)
			(sheetname "")
		)
		(fill
			(thermal_gap 0.5)
			(thermal_bridge_width 0.5)
			(island_removal_mode 0)
		)
		(polygon
			(pts
				(arc
					(start 133.1722 -44.3103)
					(mid 133.143802 -44.303596)
					(end 133.1214 -44.2849)
				)
				(arc
					(start 133.1214 -44.5135)
					(mid 133.143802 -44.494804)
					(end 133.1722 -44.4881)
				)
				(arc
					(start 133.3754 -44.4881)
					(mid 133.403798 -44.494804)
					(end 133.4262 -44.5135)
				)
				(arc
					(start 133.4262 -44.2849)
					(mid 133.403798 -44.303596)
					(end 133.3754 -44.3103)
				)
			)
		)
	)
	(zone
		(net "GND")
		(layer "B.Cu")
		(hatch none 0.5)
		(connect_pads
			(clearance 0.5)
		)
		(min_thickness 0.25)
		(fill yes
			(thermal_gap 0.5)
			(thermal_bridge_width 0.5)
			(island_removal_mode 0)
		)
		(polygon
			(pts
				(xy 56.4769 -50.9016) (xy 55.6641 -51.7144) (xy 55.6641 -62.407038) (xy 56.400446 -63.143384) (xy 61.417454 -63.143384)
				(xy 61.976 -62.584838) (xy 61.976 -51.5112) (xy 61.3664 -50.9016)
			)
		)
	)
	(zone
		(layer "B.Cu")
		(hatch none 0.5)
		(connect_pads
			(clearance 0)
		)
		(min_thickness 0.25)
		(keepout
			(tracks not_allowed)
			(vias allowed)
			(pads allowed)
			(copperpour not_allowed)
			(footprints allowed)
		)
		(placement
			(enabled no)
			(sheetname "")
		)
		(fill
			(thermal_gap 0.5)
			(thermal_bridge_width 0.5)
			(island_removal_mode 0)
		)
		(polygon
			(pts
				(arc
					(start 124.358146 -55.000144)
					(mid 124.039879 -54.644231)
					(end 123.650756 -54.920896)
				)
				(arc
					(start 123.650756 -55.237126)
					(mid 123.659205 -55.279603)
					(end 123.683268 -55.315612)
				)
				(arc
					(start 123.683268 -55.315612)
					(mid 123.719059 -55.339464)
					(end 123.761246 -55.34787)
				)
				(arc
					(start 123.911106 -55.34787)
					(mid 123.933557 -55.338571)
					(end 123.942856 -55.31612)
				)
				(arc
					(start 123.942856 -55.234586)
					(mid 124.000006 -54.758837)
					(end 124.057156 -55.234586)
				)
				(xy 124.057156 -55.339742)
				(arc
					(start 124.05487 -55.342028)
					(mid 124.0144 -55.419414)
					(end 123.937014 -55.459884)
				)
				(xy 123.934728 -55.46217) (xy 123.737624 -55.46217)
				(arc
					(start 123.7361 -55.460646)
					(mid 123.687148 -55.449546)
					(end 123.641866 -55.42788)
				)
				(arc
					(start 123.641866 -55.513732)
					(mid 123.700048 -55.532094)
					(end 123.760738 -55.53837)
				)
				(xy 123.934728 -55.53837)
				(arc
					(start 123.937014 -55.540656)
					(mid 124.0144 -55.581126)
					(end 124.05487 -55.658512)
				)
				(xy 124.057156 -55.660798)
				(arc
					(start 124.057156 -55.7657)
					(mid 124.000006 -56.241449)
					(end 123.942856 -55.7657)
				)
				(arc
					(start 123.942856 -55.68442)
					(mid 123.933557 -55.661969)
					(end 123.911106 -55.65267)
				)
				(xy 123.737624 -55.65267)
				(arc
					(start 123.736862 -55.651908)
					(mid 123.688874 -55.646299)
					(end 123.641866 -55.635144)
				)
				(arc
					(start 123.641866 -55.999888)
					(mid 123.999879 -56.358282)
					(end 124.358146 -56.000142)
				)
			)
		)
	)
	(zone
		(net "P1V5_C")
		(layer "B.Cu")
		(hatch none 0.5)
		(connect_pads
			(clearance 0.5)
		)
		(min_thickness 0.25)
		(fill yes
			(thermal_gap 0.5)
			(thermal_bridge_width 0.5)
			(island_removal_mode 0)
		)
		(polygon
			(pts
				(xy 131.8514 -115.5954) (xy 131.8514 -121.285) (xy 132.0038 -121.4374) (xy 133.35 -121.4374) (xy 133.4262 -121.3612)
				(xy 133.4262 -120.5103) (xy 133.6167 -120.3198) (xy 138.066526 -120.3198) (xy 138.3284 -120.057926)
				(xy 138.3284 -116.0018) (xy 137.922 -115.5954)
			)
		)
		(polygon
			(pts
				(xy 132.9817 -121.0818) (xy 132.7785 -121.0818) (xy 132.7785 -121.285) (xy 132.9817 -121.285)
			)
		)
		(polygon
			(pts
				(xy 132.4991 -121.0818) (xy 132.2959 -121.0818) (xy 132.2959 -121.285) (xy 132.4991 -121.285)
			)
		)
		(polygon
			(pts
				(xy 132.9817 -120.523) (xy 132.7785 -120.523) (xy 132.7785 -120.7262) (xy 132.9817 -120.7262)
			)
		)
		(polygon
			(pts
				(xy 132.4991 -120.523) (xy 132.2959 -120.523) (xy 132.2959 -120.7262) (xy 132.4991 -120.7262)
			)
		)
		(polygon
			(pts
				(xy 137.46353 -119.197882) (xy 137.26033 -119.197882) (xy 137.26033 -119.401082) (xy 137.46353 -119.401082)
			)
		)
		(polygon
			(pts
				(xy 132.5372 -116.2304) (xy 132.334 -116.2304) (xy 132.334 -116.4336) (xy 132.5372 -116.4336)
			)
		)
	)
	(zone
		(layer "B.Cu")
		(hatch none 0.5)
		(connect_pads
			(clearance 0)
		)
		(min_thickness 0.25)
		(keepout
			(tracks allowed)
			(vias allowed)
			(pads allowed)
			(copperpour allowed)
			(footprints not_allowed)
		)
		(placement
			(enabled no)
			(sheetname "")
		)
		(fill
			(thermal_gap 0.5)
			(thermal_bridge_width 0.5)
			(island_removal_mode 0)
		)
		(polygon
			(pts
				(arc
					(start 4.99999 -139.224258)
					(mid 18.50018 -131.430014)
					(end 4.99999 -123.63577)
				)
			)
		)
	)
	(zone
		(layer "B.Cu")
		(hatch none 0.5)
		(connect_pads
			(clearance 0)
		)
		(min_thickness 0.25)
		(keepout
			(tracks not_allowed)
			(vias allowed)
			(pads allowed)
			(copperpour not_allowed)
			(footprints allowed)
		)
		(placement
			(enabled no)
			(sheetname "")
		)
		(fill
			(thermal_gap 0.5)
			(thermal_bridge_width 0.5)
			(island_removal_mode 0)
		)
		(polygon
			(pts
				(arc
					(start 191.361314 -10.999978)
					(mid 190.799974 -10.438638)
					(end 190.238634 -10.999978)
				)
				(xy 190.238634 -11.464036) (xy 190.289434 -11.459464) (xy 190.290196 -11.458448) (xy 190.312802 -11.458448)
				(xy 190.325756 -11.458448) (xy 190.330328 -11.458448) (xy 190.61938 -11.458448)
				(arc
					(start 190.623952 -11.458448)
					(mid 190.681981 -11.437295)
					(end 190.712852 -11.383772)
				)
				(arc
					(start 190.712852 -11.383772)
					(mid 190.801275 -10.606365)
					(end 190.885572 -11.38428)
				)
				(xy 190.885572 -11.403838)
				(arc
					(start 190.883032 -11.406378)
					(mid 190.80912 -11.553446)
					(end 190.662052 -11.627358)
				)
				(xy 190.659512 -11.630152) (xy 190.63208 -11.630152) (xy 190.623952 -11.630152) (xy 190.61938 -11.630152)
				(xy 190.330328 -11.630152)
				(arc
					(start 190.325756 -11.630152)
					(mid 190.282027 -11.63204)
					(end 190.238634 -11.637772)
				)
				(arc
					(start 190.238634 -11.78052)
					(mid 190.263367 -11.775187)
					(end 190.288418 -11.77163)
				)
				(xy 190.290196 -11.769852) (xy 190.316358 -11.769852) (xy 190.325756 -11.769598) (xy 190.330328 -11.769852)
				(xy 190.619126 -11.769852) (xy 190.623698 -11.769598) (xy 190.631826 -11.769852) (xy 190.659258 -11.769852)
				(arc
					(start 190.661798 -11.772392)
					(mid 190.809043 -11.846381)
					(end 190.883032 -11.993626)
				)
				(xy 190.885572 -11.996166)
				(arc
					(start 190.885572 -12.015724)
					(mid 190.801275 -12.793689)
					(end 190.712852 -12.016232)
				)
				(arc
					(start 190.712852 -12.016232)
					(mid 190.681949 -11.962478)
					(end 190.623698 -11.941302)
				)
				(xy 190.619126 -11.941048) (xy 190.330328 -11.941048)
				(arc
					(start 190.325756 -11.941302)
					(mid 190.280847 -11.946846)
					(end 190.238634 -11.963146)
				)
				(arc
					(start 190.238634 -12.399772)
					(mid 190.799847 -12.961366)
					(end 191.361314 -12.400026)
				)
			)
		)
	)
	(zone
		(layer "B.Cu")
		(hatch none 0.5)
		(connect_pads
			(clearance 0)
		)
		(min_thickness 0.25)
		(keepout
			(tracks not_allowed)
			(vias allowed)
			(pads allowed)
			(copperpour not_allowed)
			(footprints allowed)
		)
		(placement
			(enabled no)
			(sheetname "")
		)
		(fill
			(thermal_gap 0.5)
			(thermal_bridge_width 0.5)
			(island_removal_mode 0)
		)
		(polygon
			(pts
				(arc
					(start 98.000058 -39.67988)
					(mid 95.000064 -36.679886)
					(end 92.00007 -39.67988)
				)
				(arc
					(start 92.00007 -39.67988)
					(mid 95.000064 -42.679874)
					(end 98.000058 -39.67988)
				)
			)
		)
	)
	(zone
		(net "P1V8_C")
		(layer "B.Cu")
		(hatch none 0.5)
		(connect_pads
			(clearance 0.5)
		)
		(min_thickness 0.25)
		(fill yes
			(thermal_gap 0.5)
			(thermal_bridge_width 0.5)
			(island_removal_mode 0)
		)
		(polygon
			(pts
				(xy 185.3946 -116.6876) (xy 185.0136 -117.0686) (xy 185.0136 -121.6406) (xy 185.3946 -122.0216)
				(xy 188.4426 -122.0216) (xy 188.8236 -121.6406) (xy 188.8236 -116.9416) (xy 188.5696 -116.6876)
			)
		)
	)
	(zone
		(net "GND")
		(layer "B.Cu")
		(hatch none 0.5)
		(connect_pads
			(clearance 0.5)
		)
		(min_thickness 0.25)
		(fill yes
			(thermal_gap 0.5)
			(thermal_bridge_width 0.5)
			(island_removal_mode 0)
		)
		(polygon
			(pts
				(xy 121.657872 -60.320936) (xy 121.440956 -60.537852) (xy 108.58373 -60.537852) (xy 108.455714 -60.665868)
				(xy 108.455714 -61.052964) (xy 108.49229 -61.08954) (xy 108.88599 -61.08954) (xy 108.983272 -61.186822)
				(xy 108.983272 -61.434472) (xy 109.011974 -61.463174) (xy 121.272808 -61.463174) (xy 121.567956 -61.758322)
				(xy 121.567956 -71.312278) (xy 121.372884 -71.50735) (xy 120.541034 -71.50735) (xy 120.403112 -71.369428)
				(xy 120.403112 -62.939168) (xy 120.235472 -62.771528) (xy 109.820456 -62.771528) (xy 109.546898 -63.045086)
				(xy 109.546898 -67.142868) (xy 109.65053 -67.2465) (xy 110.23473 -67.2465) (xy 110.3503 -67.13093)
				(xy 110.3503 -63.8683) (xy 110.5535 -63.6651) (xy 111.33836 -63.6651) (xy 112.04956 -64.3763) (xy 119.168672 -64.3763)
				(xy 119.4054 -64.613028) (xy 119.4054 -65.3796) (xy 119.191786 -65.593214) (xy 111.934498 -65.593214)
				(xy 111.767112 -65.7606) (xy 111.767112 -66.123312) (xy 111.8997 -66.2559) (xy 119.2657 -66.2559)
				(xy 119.339614 -66.329814) (xy 119.339614 -67.366134) (xy 119.248428 -67.45732) (xy 112.199166 -67.45732)
				(xy 111.77143 -67.885056) (xy 111.77143 -68.111624) (xy 112.223804 -68.563998) (xy 118.272306 -68.563998)
				(xy 118.31574 -68.607432) (xy 119.086884 -68.607432) (xy 119.5578 -69.078348) (xy 119.5578 -70.3072)
				(xy 119.435626 -70.429374) (xy 119.4308 -70.429374) (xy 119.38381 -70.476364) (xy 110.81004 -70.476364)
				(xy 110.188502 -69.854826) (xy 110.188502 -69.322696) (xy 109.633512 -68.767706) (xy 108.905294 -68.767706)
				(xy 108.7628 -68.9102) (xy 108.7628 -69.1388) (xy 109.4486 -69.8246) (xy 109.4486 -70.1802) (xy 107.8484 -71.7804)
				(xy 105.919524 -71.7804) (xy 105.785666 -71.914258) (xy 105.785666 -72.410066) (xy 105.869232 -72.493632)
				(xy 107.922568 -72.493632) (xy 108.5088 -71.9074) (xy 109.445552 -71.9074) (xy 109.826552 -71.5264)
				(xy 110.1852 -71.5264) (xy 110.4646 -71.8058) (xy 111.4298 -71.8058) (xy 111.7092 -71.5264) (xy 112.1664 -71.5264)
				(xy 112.4458 -71.8058) (xy 113.538 -71.8058) (xy 113.8174 -71.5264) (xy 114.155982 -71.5264) (xy 114.409728 -71.7804)
				(xy 116.459 -71.7804) (xy 116.713 -71.5264) (xy 117.168676 -71.5264) (xy 117.4496 -71.807324) (xy 118.441724 -71.807324)
				(xy 118.722648 -71.5264) (xy 119.1006 -71.5264) (xy 119.477282 -71.903082) (xy 119.689118 -71.903082)
				(xy 119.953786 -72.16775) (xy 121.190004 -72.16775) (xy 121.196354 -72.1614) (xy 121.687336 -72.1614)
				(xy 122.1486 -72.622664) (xy 122.1486 -72.624188) (xy 122.422412 -72.624188) (xy 122.4788 -72.5678)
				(xy 122.4788 -72.0852) (xy 122.3772 -71.9836) (xy 122.3772 -60.350654) (xy 122.347482 -60.320936)
			)
		)
		(polygon
			(pts
				(xy 121.4374 -71.6788) (xy 121.2342 -71.6788) (xy 121.2342 -71.882) (xy 121.4374 -71.882)
			)
		)
		(polygon
			(pts
				(xy 120.80748 -71.6788) (xy 120.60428 -71.6788) (xy 120.60428 -71.882) (xy 120.80748 -71.882)
			)
		)
		(polygon
			(pts
				(xy 120.45188 -71.6788) (xy 120.24868 -71.6788) (xy 120.24868 -71.882) (xy 120.45188 -71.882)
			)
		)
		(polygon
			(pts
				(xy 122.0978 -71.5899) (xy 121.8946 -71.5899) (xy 121.793 -71.6788) (xy 121.5898 -71.6788) (xy 121.5898 -71.882)
				(xy 121.793 -71.882) (xy 121.8946 -71.7931) (xy 122.0978 -71.7931)
			)
		)
		(polygon
			(pts
				(xy 109.5756 -71.4248) (xy 109.3724 -71.4248) (xy 109.3724 -71.628) (xy 109.5756 -71.628)
			)
		)
		(polygon
			(pts
				(xy 109.22 -71.4248) (xy 108.7882 -71.4248) (xy 108.7882 -71.628) (xy 109.22 -71.628)
			)
		)
		(polygon
			(pts
				(xy 108.6358 -71.4248) (xy 108.4326 -71.4248) (xy 108.4326 -71.628) (xy 108.6358 -71.628)
			)
		)
		(polygon
			(pts
				(xy 119.78386 -71.374) (xy 119.58066 -71.374) (xy 119.58066 -71.5772) (xy 119.78386 -71.5772)
			)
		)
		(polygon
			(pts
				(xy 118.237 -71.3232) (xy 117.7544 -71.3232) (xy 117.7544 -71.5264) (xy 118.237 -71.5264)
			)
		)
		(polygon
			(pts
				(xy 117.602 -71.3232) (xy 117.3988 -71.3232) (xy 117.3988 -71.5264) (xy 117.602 -71.5264)
			)
		)
		(polygon
			(pts
				(xy 113.3348 -71.3232) (xy 113.1316 -71.3232) (xy 113.1316 -71.5264) (xy 113.3348 -71.5264)
			)
		)
		(polygon
			(pts
				(xy 112.9792 -71.3232) (xy 112.776 -71.3232) (xy 112.776 -71.5264) (xy 112.9792 -71.5264)
			)
		)
		(polygon
			(pts
				(xy 112.6236 -71.3232) (xy 112.4204 -71.3232) (xy 112.4204 -71.5264) (xy 112.6236 -71.5264)
			)
		)
		(polygon
			(pts
				(xy 111.506 -71.3232) (xy 111.3028 -71.3232) (xy 111.3028 -71.5264) (xy 111.506 -71.5264)
			)
		)
		(polygon
			(pts
				(xy 111.1504 -71.3232) (xy 110.6678 -71.3232) (xy 110.6678 -71.5264) (xy 111.1504 -71.5264)
			)
		)
		(polygon
			(pts
				(xy 116.2812 -71.2978) (xy 116.078 -71.2978) (xy 116.0526 -71.298308) (xy 115.8494 -71.298308) (xy 115.8494 -71.501508)
				(xy 116.0526 -71.501508) (xy 116.078 -71.501) (xy 116.2812 -71.501)
			)
		)
		(polygon
			(pts
				(xy 115.4684 -71.2978) (xy 115.2652 -71.2978) (xy 115.2652 -71.501) (xy 115.4684 -71.501) (xy 115.4938 -71.501508)
				(xy 115.697 -71.501508) (xy 115.697 -71.298308) (xy 115.4938 -71.298308)
			)
		)
		(polygon
			(pts
				(xy 115.1128 -71.2978) (xy 114.681 -71.2978) (xy 114.681 -71.501) (xy 115.1128 -71.501)
			)
		)
		(polygon
			(pts
				(xy 114.5286 -71.2978) (xy 114.3254 -71.2978) (xy 114.3254 -71.501) (xy 114.5286 -71.501)
			)
		)
		(polygon
			(pts
				(xy 122.0978 -71.2343) (xy 121.8946 -71.2343) (xy 121.8946 -71.4375) (xy 122.0978 -71.4375)
			)
		)
		(polygon
			(pts
				(xy 119.8372 -70.993) (xy 119.634 -70.993) (xy 119.634 -71.1962) (xy 119.8372 -71.1962)
			)
		)
		(polygon
			(pts
				(xy 119.397272 -70.808596) (xy 119.194072 -70.808596) (xy 119.194072 -71.011796) (xy 119.397272 -71.011796)
			)
		)
		(polygon
			(pts
				(xy 119.041672 -70.808596) (xy 118.607332 -70.808596) (xy 118.607332 -71.011796) (xy 119.041672 -71.011796)
			)
		)
		(polygon
			(pts
				(xy 118.454932 -70.808596) (xy 118.251732 -70.808596) (xy 118.251732 -71.011796) (xy 118.454932 -71.011796)
			)
		)
		(polygon
			(pts
				(xy 116.7892 -70.7644) (xy 116.586 -70.7644) (xy 116.586 -70.9676) (xy 116.7892 -70.9676)
			)
		)
		(polygon
			(pts
				(xy 116.4336 -70.7644) (xy 116.2304 -70.7644) (xy 116.2304 -70.9676) (xy 116.4336 -70.9676)
			)
		)
		(polygon
			(pts
				(xy 115.7732 -70.7644) (xy 115.57 -70.7644) (xy 115.57 -70.9676) (xy 115.7732 -70.9676)
			)
		)
		(polygon
			(pts
				(xy 115.4176 -70.7644) (xy 115.2144 -70.7644) (xy 115.2144 -70.9676) (xy 115.4176 -70.9676)
			)
		)
		(polygon
			(pts
				(xy 114.5794 -70.7644) (xy 114.3762 -70.7644) (xy 114.3762 -70.9676) (xy 114.5794 -70.9676)
			)
		)
		(polygon
			(pts
				(xy 114.2238 -70.7644) (xy 113.7412 -70.7644) (xy 113.7412 -70.9676) (xy 114.2238 -70.9676)
			)
		)
		(polygon
			(pts
				(xy 113.5888 -70.7644) (xy 113.3856 -70.7644) (xy 113.3856 -70.9676) (xy 113.5888 -70.9676)
			)
		)
		(polygon
			(pts
				(xy 112.6744 -70.7644) (xy 112.4712 -70.7644) (xy 112.4712 -70.9676) (xy 112.6744 -70.9676)
			)
		)
		(polygon
			(pts
				(xy 112.3188 -70.7644) (xy 111.8362 -70.7644) (xy 111.8362 -70.9676) (xy 112.3188 -70.9676)
			)
		)
		(polygon
			(pts
				(xy 111.6838 -70.7644) (xy 111.4806 -70.7644) (xy 111.4806 -70.9676) (xy 111.6838 -70.9676)
			)
		)
		(polygon
			(pts
				(xy 117.767862 -70.75678) (xy 117.564662 -70.75678) (xy 117.564662 -70.95998) (xy 117.767862 -70.95998)
			)
		)
		(polygon
			(pts
				(xy 117.412262 -70.75678) (xy 117.209062 -70.75678) (xy 117.209062 -70.95998) (xy 117.412262 -70.95998)
			)
		)
		(polygon
			(pts
				(xy 122.0978 -70.5866) (xy 121.8946 -70.5866) (xy 121.8946 -70.7898) (xy 122.0978 -70.7898)
			)
		)
		(polygon
			(pts
				(xy 122.0978 -70.231) (xy 121.8946 -70.231) (xy 121.8946 -70.4342) (xy 122.0978 -70.4342)
			)
		)
		(polygon
			(pts
				(xy 122.0978 -69.5706) (xy 121.8946 -69.5706) (xy 121.8946 -69.7738) (xy 122.0978 -69.7738)
			)
		)
		(polygon
			(pts
				(xy 109.897418 -69.507862) (xy 109.694218 -69.507862) (xy 109.694218 -69.711062) (xy 109.897418 -69.711062)
			)
		)
		(polygon
			(pts
				(xy 122.0978 -69.215) (xy 121.8946 -69.215) (xy 121.8946 -69.4182) (xy 122.0978 -69.4182)
			)
		)
		(polygon
			(pts
				(xy 122.0978 -68.5673) (xy 121.8946 -68.5673) (xy 121.8946 -68.7705) (xy 122.0978 -68.7705)
			)
		)
		(polygon
			(pts
				(xy 119.8626 -68.326) (xy 119.6594 -68.326) (xy 119.6594 -68.5292) (xy 119.8626 -68.5292)
			)
		)
		(polygon
			(pts
				(xy 122.0978 -68.2117) (xy 121.8946 -68.2117) (xy 121.8946 -68.4149) (xy 122.0978 -68.4149)
			)
		)
		(polygon
			(pts
				(xy 117.6274 -68.072) (xy 117.4242 -68.072) (xy 117.4242 -68.2752) (xy 117.6274 -68.2752)
			)
		)
		(polygon
			(pts
				(xy 117.2718 -68.072) (xy 116.7892 -68.072) (xy 116.7892 -68.2752) (xy 117.2718 -68.2752)
			)
		)
		(polygon
			(pts
				(xy 116.6368 -68.072) (xy 116.4336 -68.072) (xy 116.4336 -68.2752) (xy 116.6368 -68.2752)
			)
		)
		(polygon
			(pts
				(xy 115.5954 -68.072) (xy 115.3922 -68.072) (xy 115.3922 -68.2752) (xy 115.5954 -68.2752)
			)
		)
		(polygon
			(pts
				(xy 115.2398 -68.072) (xy 114.7572 -68.072) (xy 114.7572 -68.2752) (xy 115.2398 -68.2752)
			)
		)
		(polygon
			(pts
				(xy 114.6048 -68.072) (xy 114.4016 -68.072) (xy 114.4016 -68.2752) (xy 114.6048 -68.2752)
			)
		)
		(polygon
			(pts
				(xy 113.5634 -68.072) (xy 113.3602 -68.072) (xy 113.3602 -68.2752) (xy 113.5634 -68.2752)
			)
		)
		(polygon
			(pts
				(xy 113.2078 -68.072) (xy 112.7252 -68.072) (xy 112.7252 -68.2752) (xy 113.2078 -68.2752)
			)
		)
		(polygon
			(pts
				(xy 112.5728 -68.072) (xy 112.3696 -68.072) (xy 112.3696 -68.2752) (xy 112.5728 -68.2752)
			)
		)
		(polygon
			(pts
				(xy 119.211598 -67.766184) (xy 119.008398 -67.766184) (xy 119.008398 -67.969384) (xy 119.211598 -67.969384)
			)
		)
		(polygon
			(pts
				(xy 118.500398 -67.766184) (xy 118.297198 -67.766184) (xy 118.297198 -67.969384) (xy 118.500398 -67.969384)
			)
		)
		(polygon
			(pts
				(xy 122.093228 -67.43573) (xy 121.890028 -67.43573) (xy 121.890028 -67.63893) (xy 122.093228 -67.63893)
			)
		)
		(polygon
			(pts
				(xy 119.8372 -66.8782) (xy 119.634 -66.8782) (xy 119.634 -67.0814) (xy 119.8372 -67.0814)
			)
		)
		(polygon
			(pts
				(xy 122.093228 -66.80073) (xy 121.890028 -66.80073) (xy 121.890028 -67.28333) (xy 122.093228 -67.28333)
			)
		)
		(polygon
			(pts
				(xy 122.093228 -66.44513) (xy 121.890028 -66.44513) (xy 121.890028 -66.64833) (xy 122.093228 -66.64833)
			)
		)
		(polygon
			(pts
				(xy 119.8372 -66.2686) (xy 119.634 -66.2686) (xy 119.634 -66.4718) (xy 119.8372 -66.4718)
			)
		)
		(polygon
			(pts
				(xy 117.6274 -65.7733) (xy 117.4242 -65.7733) (xy 117.4242 -65.9765) (xy 117.6274 -65.9765)
			)
		)
		(polygon
			(pts
				(xy 117.2718 -65.7733) (xy 116.7892 -65.7733) (xy 116.7892 -65.9765) (xy 117.2718 -65.9765)
			)
		)
		(polygon
			(pts
				(xy 116.6368 -65.7733) (xy 116.4336 -65.7733) (xy 116.4336 -65.9765) (xy 116.6368 -65.9765)
			)
		)
		(polygon
			(pts
				(xy 115.7351 -65.7733) (xy 115.5319 -65.7733) (xy 115.5319 -65.9765) (xy 115.7351 -65.9765)
			)
		)
		(polygon
			(pts
				(xy 115.3795 -65.7733) (xy 114.8969 -65.7733) (xy 114.8969 -65.9765) (xy 115.3795 -65.9765)
			)
		)
		(polygon
			(pts
				(xy 114.7445 -65.7733) (xy 114.5413 -65.7733) (xy 114.5413 -65.9765) (xy 114.7445 -65.9765)
			)
		)
		(polygon
			(pts
				(xy 113.538 -65.7733) (xy 113.3348 -65.7733) (xy 113.3348 -65.9765) (xy 113.538 -65.9765)
			)
		)
		(polygon
			(pts
				(xy 113.1824 -65.7733) (xy 112.6998 -65.7733) (xy 112.6998 -65.9765) (xy 113.1824 -65.9765)
			)
		)
		(polygon
			(pts
				(xy 112.5474 -65.7733) (xy 112.3442 -65.7733) (xy 112.3442 -65.9765) (xy 112.5474 -65.9765)
			)
		)
		(polygon
			(pts
				(xy 110.088172 -65.564258) (xy 109.884972 -65.564258) (xy 109.884972 -65.767458) (xy 110.088172 -65.767458)
			)
		)
		(polygon
			(pts
				(xy 122.0978 -65.5574) (xy 121.8946 -65.5574) (xy 121.8946 -65.7606) (xy 122.0978 -65.7606)
			)
		)
		(polygon
			(pts
				(xy 110.088172 -65.208658) (xy 109.884972 -65.208658) (xy 109.884972 -65.411858) (xy 110.088172 -65.411858)
			)
		)
		(polygon
			(pts
				(xy 122.0978 -65.2018) (xy 121.8946 -65.2018) (xy 121.8946 -65.405) (xy 122.0978 -65.405)
			)
		)
		(polygon
			(pts
				(xy 119.888 -64.9224) (xy 119.6848 -64.9224) (xy 119.6848 -65.1256) (xy 119.888 -65.1256)
			)
		)
		(polygon
			(pts
				(xy 122.0978 -64.5668) (xy 121.8946 -64.5668) (xy 121.8946 -64.77) (xy 122.0978 -64.77)
			)
		)
		(polygon
			(pts
				(xy 119.888 -64.3128) (xy 119.6848 -64.3128) (xy 119.6848 -64.516) (xy 119.888 -64.516)
			)
		)
		(polygon
			(pts
				(xy 122.0978 -64.2112) (xy 121.8946 -64.2112) (xy 121.8946 -64.4144) (xy 122.0978 -64.4144)
			)
		)
		(polygon
			(pts
				(xy 117.6147 -63.8937) (xy 117.4115 -63.8937) (xy 117.4115 -64.0969) (xy 117.6147 -64.0969)
			)
		)
		(polygon
			(pts
				(xy 117.2591 -63.8937) (xy 116.7765 -63.8937) (xy 116.7765 -64.0969) (xy 117.2591 -64.0969)
			)
		)
		(polygon
			(pts
				(xy 116.6241 -63.8937) (xy 116.4209 -63.8937) (xy 116.4209 -64.0969) (xy 116.6241 -64.0969)
			)
		)
		(polygon
			(pts
				(xy 115.5827 -63.8937) (xy 115.3795 -63.8937) (xy 115.3795 -64.0969) (xy 115.5827 -64.0969)
			)
		)
		(polygon
			(pts
				(xy 115.2271 -63.8937) (xy 114.7445 -63.8937) (xy 114.7445 -64.0969) (xy 115.2271 -64.0969)
			)
		)
		(polygon
			(pts
				(xy 114.5921 -63.8937) (xy 114.3889 -63.8937) (xy 114.3889 -64.0969) (xy 114.5921 -64.0969)
			)
		)
		(polygon
			(pts
				(xy 113.5634 -63.8937) (xy 113.3602 -63.8937) (xy 113.3602 -64.0969) (xy 113.5634 -64.0969)
			)
		)
		(polygon
			(pts
				(xy 113.2078 -63.8937) (xy 112.7252 -63.8937) (xy 112.7252 -64.0969) (xy 113.2078 -64.0969)
			)
		)
		(polygon
			(pts
				(xy 112.5728 -63.8937) (xy 112.3696 -63.8937) (xy 112.3696 -64.0969) (xy 112.5728 -64.0969)
			)
		)
		(polygon
			(pts
				(xy 119.210836 -63.6524) (xy 119.007636 -63.6524) (xy 119.007636 -63.8556) (xy 119.210836 -63.8556)
			)
		)
		(polygon
			(pts
				(xy 118.499636 -63.6524) (xy 118.296436 -63.6524) (xy 118.296436 -63.8556) (xy 118.499636 -63.8556)
			)
		)
		(polygon
			(pts
				(xy 122.0978 -63.5635) (xy 121.8946 -63.5635) (xy 121.8946 -63.7667) (xy 122.0978 -63.7667)
			)
		)
		(polygon
			(pts
				(xy 119.9134 -63.5) (xy 119.7102 -63.5) (xy 119.7102 -63.7032) (xy 119.9134 -63.7032)
			)
		)
		(polygon
			(pts
				(xy 122.0978 -63.2079) (xy 121.8946 -63.2079) (xy 121.8946 -63.4111) (xy 122.0978 -63.4111)
			)
		)
		(polygon
			(pts
				(xy 119.9134 -62.8904) (xy 119.7102 -62.8904) (xy 119.7102 -63.0936) (xy 119.9134 -63.0936)
			)
		)
		(polygon
			(pts
				(xy 122.0978 -62.5602) (xy 121.8946 -62.5602) (xy 121.8946 -62.7634) (xy 122.0978 -62.7634)
			)
		)
		(polygon
			(pts
				(xy 122.0978 -62.2046) (xy 121.8946 -62.2046) (xy 121.8946 -62.4078) (xy 122.0978 -62.4078)
			)
		)
		(polygon
			(pts
				(xy 122.0978 -61.5696) (xy 121.8946 -61.5696) (xy 121.8946 -61.7728) (xy 122.0978 -61.7728)
			)
		)
		(polygon
			(pts
				(xy 122.0978 -61.214) (xy 121.8946 -61.214) (xy 121.8946 -61.4172) (xy 122.0978 -61.4172)
			)
		)
		(polygon
			(pts
				(xy 122.0978 -60.5536) (xy 121.8946 -60.5536) (xy 121.8946 -60.7568) (xy 122.0978 -60.7568)
			)
		)
	)
	(zone
		(layer "B.Cu")
		(hatch none 0.5)
		(connect_pads
			(clearance 0)
		)
		(min_thickness 0.25)
		(keepout
			(tracks not_allowed)
			(vias allowed)
			(pads allowed)
			(copperpour not_allowed)
			(footprints allowed)
		)
		(placement
			(enabled no)
			(sheetname "")
		)
		(fill
			(thermal_gap 0.5)
			(thermal_bridge_width 0.5)
			(island_removal_mode 0)
		)
		(polygon
			(pts
				(arc
					(start 116.358162 -55.000144)
					(mid 116.000022 -54.642004)
					(end 115.641882 -55.000144)
				)
				(arc
					(start 115.641882 -55.241698)
					(mid 115.657487 -55.281508)
					(end 115.683284 -55.315612)
				)
				(arc
					(start 115.683284 -55.315612)
					(mid 115.719075 -55.339464)
					(end 115.761262 -55.34787)
				)
				(arc
					(start 115.911122 -55.34787)
					(mid 115.933573 -55.338571)
					(end 115.942872 -55.31612)
				)
				(arc
					(start 115.942872 -55.234586)
					(mid 116.000022 -54.758837)
					(end 116.057172 -55.234586)
				)
				(xy 116.057172 -55.339742)
				(arc
					(start 116.054886 -55.342028)
					(mid 116.014416 -55.419414)
					(end 115.93703 -55.459884)
				)
				(xy 115.934744 -55.46217) (xy 115.73764 -55.46217)
				(arc
					(start 115.736116 -55.460646)
					(mid 115.687164 -55.449546)
					(end 115.641882 -55.42788)
				)
				(arc
					(start 115.641882 -55.513732)
					(mid 115.700064 -55.532094)
					(end 115.760754 -55.53837)
				)
				(xy 115.934744 -55.53837)
				(arc
					(start 115.93703 -55.540656)
					(mid 116.014416 -55.581126)
					(end 116.054886 -55.658512)
				)
				(xy 116.057172 -55.660798)
				(arc
					(start 116.057172 -55.7657)
					(mid 116.000022 -56.241449)
					(end 115.942872 -55.7657)
				)
				(arc
					(start 115.942872 -55.68442)
					(mid 115.933573 -55.661969)
					(end 115.911122 -55.65267)
				)
				(xy 115.73764 -55.65267)
				(arc
					(start 115.736878 -55.651908)
					(mid 115.68889 -55.646299)
					(end 115.641882 -55.635144)
				)
				(arc
					(start 115.641882 -55.999888)
					(mid 115.999895 -56.358282)
					(end 116.358162 -56.000142)
				)
			)
		)
	)
	(zone
		(layer "B.Cu")
		(hatch none 0.5)
		(connect_pads
			(clearance 0)
		)
		(min_thickness 0.25)
		(keepout
			(tracks not_allowed)
			(vias allowed)
			(pads allowed)
			(copperpour not_allowed)
			(footprints allowed)
		)
		(placement
			(enabled no)
			(sheetname "")
		)
		(fill
			(thermal_gap 0.5)
			(thermal_bridge_width 0.5)
			(island_removal_mode 0)
		)
		(polygon
			(pts
				(arc
					(start 171.12996 -30.066234)
					(mid 170.827718 -30.085897)
					(end 170.64863 -30.33014)
				)
				(xy 170.64863 -30.559756) (xy 170.641772 -30.566614)
				(arc
					(start 170.642026 -31.199836)
					(mid 171.000166 -31.55823)
					(end 171.358306 -31.199836)
				)
				(xy 171.358306 -30.867604) (xy 171.358052 -30.73527)
				(arc
					(start 171.174156 -31.032958)
					(mid 170.873454 -31.405394)
					(end 171.07154 -30.969712)
				)
				(xy 171.330112 -30.550866)
				(arc
					(start 171.330112 -30.26156)
					(mid 171.296098 -30.198901)
					(end 171.250356 -30.144212)
				)
				(xy 171.250356 -30.234636)
				(arc
					(start 171.207684 -30.277562)
					(mid 170.829387 -30.570515)
					(end 171.12234 -30.192218)
				)
				(xy 171.12996 -30.184852)
			)
		)
	)
	(zone
		(net "SAS0_VDDH")
		(layer "B.Cu")
		(hatch none 0.5)
		(connect_pads
			(clearance 0.5)
		)
		(min_thickness 0.25)
		(fill yes
			(thermal_gap 0.5)
			(thermal_bridge_width 0.5)
			(island_removal_mode 0)
		)
		(polygon
			(pts
				(xy 157.5816 -27.3304) (xy 157.3276 -27.5844) (xy 157.3276 -32.9184) (xy 157.6832 -33.274) (xy 161.0106 -33.274)
				(xy 161.29 -33.5534) (xy 161.29 -37.973) (xy 162.4076 -39.0906) (xy 163.0172 -39.0906) (xy 163.1442 -38.9636)
				(xy 163.1442 -36.4744) (xy 163.195 -36.4236) (xy 163.195 -27.6352) (xy 162.8902 -27.3304)
			)
		)
		(polygon
			(pts
				(xy 162.6362 -37.9984) (xy 162.433 -37.9984) (xy 162.433 -38.2016) (xy 162.6362 -38.2016)
			)
		)
		(polygon
			(pts
				(xy 162.6362 -37.3888) (xy 162.433 -37.3888) (xy 162.433 -37.592) (xy 162.6362 -37.592)
			)
		)
		(polygon
			(pts
				(xy 162.642042 -37.010594) (xy 162.438842 -37.010594) (xy 162.438842 -37.213794) (xy 162.642042 -37.213794)
			)
		)
		(polygon
			(pts
				(xy 162.642042 -36.400994) (xy 162.438842 -36.400994) (xy 162.438842 -36.604194) (xy 162.642042 -36.604194)
			)
		)
		(polygon
			(pts
				(xy 162.6489 -34.4678) (xy 162.4457 -34.4678) (xy 162.4457 -34.671) (xy 162.6489 -34.671)
			)
		)
		(polygon
			(pts
				(xy 162.6362 -33.5534) (xy 162.433 -33.5534) (xy 162.433 -33.7566) (xy 162.4457 -33.8582) (xy 162.4457 -34.0614)
				(xy 162.6489 -34.0614) (xy 162.6489 -33.8582) (xy 162.6362 -33.7566)
			)
		)
		(polygon
			(pts
				(xy 162.6362 -32.8422) (xy 162.433 -32.8422) (xy 162.433 -33.0454) (xy 162.6362 -33.0454)
			)
		)
		(polygon
			(pts
				(xy 161.005774 -32.158432) (xy 160.802574 -32.158432) (xy 160.802574 -32.361632) (xy 161.005774 -32.361632)
			)
		)
		(polygon
			(pts
				(xy 160.142174 -32.158432) (xy 159.938974 -32.158432) (xy 159.938974 -32.361632) (xy 160.142174 -32.361632)
			)
		)
		(polygon
			(pts
				(xy 160.782 -27.7876) (xy 160.5788 -27.7876) (xy 160.5788 -27.9908) (xy 160.782 -27.9908)
			)
		)
		(polygon
			(pts
				(xy 160.2232 -27.7876) (xy 160.02 -27.7876) (xy 160.02 -27.9908) (xy 160.2232 -27.9908)
			)
		)
	)
	(zone
		(layer "B.Cu")
		(hatch none 0.5)
		(connect_pads
			(clearance 0)
		)
		(min_thickness 0.25)
		(keepout
			(tracks not_allowed)
			(vias allowed)
			(pads allowed)
			(copperpour not_allowed)
			(footprints allowed)
		)
		(placement
			(enabled no)
			(sheetname "")
		)
		(fill
			(thermal_gap 0.5)
			(thermal_bridge_width 0.5)
			(island_removal_mode 0)
		)
		(polygon
			(pts
				(arc
					(start 103.358188 -55.000144)
					(mid 103.040564 -54.644303)
					(end 102.651052 -54.919626)
				)
				(arc
					(start 102.651052 -55.237634)
					(mid 102.659428 -55.279834)
					(end 102.68331 -55.315612)
				)
				(arc
					(start 102.68331 -55.315612)
					(mid 102.719101 -55.339464)
					(end 102.761288 -55.34787)
				)
				(arc
					(start 102.911148 -55.34787)
					(mid 102.933599 -55.338571)
					(end 102.942898 -55.31612)
				)
				(arc
					(start 102.942898 -55.234586)
					(mid 103.000048 -54.758837)
					(end 103.057198 -55.234586)
				)
				(xy 103.057198 -55.339742)
				(arc
					(start 103.054912 -55.342028)
					(mid 103.014442 -55.419414)
					(end 102.937056 -55.459884)
				)
				(xy 102.93477 -55.46217) (xy 102.737666 -55.46217)
				(arc
					(start 102.736142 -55.460646)
					(mid 102.68719 -55.449546)
					(end 102.641908 -55.42788)
				)
				(arc
					(start 102.641908 -55.513732)
					(mid 102.70009 -55.532094)
					(end 102.76078 -55.53837)
				)
				(xy 102.93477 -55.53837)
				(arc
					(start 102.937056 -55.540656)
					(mid 103.014442 -55.581126)
					(end 103.054912 -55.658512)
				)
				(xy 103.057198 -55.660798)
				(arc
					(start 103.057198 -55.7657)
					(mid 103.000048 -56.241449)
					(end 102.942898 -55.7657)
				)
				(arc
					(start 102.942898 -55.68442)
					(mid 102.933599 -55.661969)
					(end 102.911148 -55.65267)
				)
				(xy 102.737666 -55.65267)
				(arc
					(start 102.736904 -55.651908)
					(mid 102.688916 -55.646299)
					(end 102.641908 -55.635144)
				)
				(arc
					(start 102.641908 -55.999888)
					(mid 102.999921 -56.358282)
					(end 103.358188 -56.000142)
				)
			)
		)
	)
	(zone
		(layer "B.Cu")
		(hatch none 0.5)
		(connect_pads
			(clearance 0)
		)
		(min_thickness 0.25)
		(keepout
			(tracks not_allowed)
			(vias allowed)
			(pads allowed)
			(copperpour not_allowed)
			(footprints allowed)
		)
		(placement
			(enabled no)
			(sheetname "")
		)
		(fill
			(thermal_gap 0.5)
			(thermal_bridge_width 0.5)
			(island_removal_mode 0)
		)
		(polygon
			(pts
				(arc
					(start 175.916336 -30.061662)
					(mid 175.630445 -30.084934)
					(end 175.453294 -30.310582)
				)
				(xy 175.453294 -30.537912) (xy 175.441864 -30.549342)
				(arc
					(start 175.441864 -31.199836)
					(mid 175.799877 -31.55823)
					(end 176.158144 -31.20009)
				)
				(xy 176.158144 -30.711394)
				(arc
					(start 175.970692 -31.029402)
					(mid 175.677996 -31.408018)
					(end 175.866552 -30.968188)
				)
				(xy 176.153064 -30.482032)
				(arc
					(start 176.153064 -30.340808)
					(mid 176.139831 -30.287151)
					(end 176.11852 -30.23616)
				)
				(xy 176.10074 -30.21838)
				(arc
					(start 176.10074 -30.20568)
					(mid 176.071518 -30.166551)
					(end 176.03724 -30.131766)
				)
				(xy 176.03724 -30.248352) (xy 176.036986 -30.248352)
				(arc
					(start 176.007776 -30.277816)
					(mid 175.631992 -30.573246)
					(end 175.916336 -30.188916)
				)
			)
		)
	)
	(zone
		(layer "B.Cu")
		(hatch none 0.5)
		(connect_pads
			(clearance 0)
		)
		(min_thickness 0.25)
		(keepout
			(tracks allowed)
			(vias allowed)
			(pads allowed)
			(copperpour allowed)
			(footprints allowed)
		)
		(placement
			(enabled no)
			(sheetname "")
		)
		(fill
			(thermal_gap 0.5)
			(thermal_bridge_width 0.5)
			(island_removal_mode 0)
		)
		(polygon
			(pts
				(xy 104.7496 -110.7694) (xy 104.7496 -109.9058) (xy 109.2962 -109.9058) (xy 109.2962 -110.7694)
			)
		)
	)
	(zone
		(net "P3V3")
		(layer "B.Cu")
		(hatch none 0.5)
		(connect_pads
			(clearance 0.5)
		)
		(min_thickness 0.25)
		(fill yes
			(thermal_gap 0.5)
			(thermal_bridge_width 0.5)
			(island_removal_mode 0)
		)
		(polygon
			(pts
				(xy 198.1962 -21.1074) (xy 197.993 -21.3106) (xy 197.993 -23.495) (xy 198.0946 -23.5966) (xy 199.6948 -23.5966)
				(xy 199.76465 -23.52675) (xy 199.76465 -22.037802) (xy 199.70496 -21.978112) (xy 199.028812 -21.978112)
				(xy 198.8947 -21.844) (xy 198.8947 -21.2217) (xy 198.7804 -21.1074)
			)
		)
		(polygon
			(pts
				(xy 199.3011 -22.9362) (xy 199.0979 -22.9362) (xy 199.0979 -23.1394) (xy 199.3011 -23.1394)
			)
		)
		(polygon
			(pts
				(xy 198.755 -22.9362) (xy 198.5518 -22.9362) (xy 198.5518 -23.1394) (xy 198.755 -23.1394)
			)
		)
		(polygon
			(pts
				(xy 199.3011 -22.4536) (xy 199.0979 -22.4536) (xy 199.0979 -22.6568) (xy 199.3011 -22.6568)
			)
		)
	)
	(zone
		(layer "B.Cu")
		(hatch none 0.5)
		(connect_pads
			(clearance 0)
		)
		(min_thickness 0.25)
		(keepout
			(tracks not_allowed)
			(vias allowed)
			(pads allowed)
			(copperpour not_allowed)
			(footprints allowed)
		)
		(placement
			(enabled no)
			(sheetname "")
		)
		(fill
			(thermal_gap 0.5)
			(thermal_bridge_width 0.5)
			(island_removal_mode 0)
		)
		(polygon
			(pts
				(arc
					(start 149.561296 -2.600198)
					(mid 148.999956 -2.038858)
					(end 148.438616 -2.600198)
				)
				(arc
					(start 148.438616 -3.028442)
					(mid 148.471568 -3.024751)
					(end 148.504656 -3.0226)
				)
				(xy 148.505418 -3.021838)
				(arc
					(start 148.88083 -3.021838)
					(mid 148.897743 -3.018474)
					(end 148.912072 -3.008884)
				)
				(arc
					(start 148.912072 -3.008884)
					(mid 148.919669 -2.99858)
					(end 148.92401 -2.986532)
				)
				(arc
					(start 148.92401 -2.986532)
					(mid 149.000982 -2.206422)
					(end 149.074886 -2.986786)
				)
				(xy 149.074886 -3.00863)
				(arc
					(start 149.071838 -3.011678)
					(mid 149.052907 -3.067209)
					(end 149.018244 -3.114548)
				)
				(arc
					(start 149.018244 -3.114548)
					(mid 148.970728 -3.149578)
					(end 148.914866 -3.16865)
				)
				(xy 148.911818 -3.171698)
				(arc
					(start 148.536406 -3.171698)
					(mid 148.487322 -3.17388)
					(end 148.438616 -3.180334)
				)
				(arc
					(start 148.438616 -3.44424)
					(mid 148.470741 -3.435359)
					(end 148.50364 -3.430016)
				)
				(xy 148.505418 -3.428238) (xy 148.911818 -3.428238)
				(arc
					(start 148.914866 -3.431286)
					(mid 148.970715 -3.450383)
					(end 149.018244 -3.485388)
				)
				(arc
					(start 149.018244 -3.485388)
					(mid 149.052932 -3.532714)
					(end 149.071838 -3.588258)
				)
				(xy 149.074886 -3.591306)
				(arc
					(start 149.074886 -3.613404)
					(mid 149.000858 -4.393726)
					(end 148.924264 -3.613658)
				)
				(arc
					(start 148.924264 -3.613658)
					(mid 148.919866 -3.601436)
					(end 148.912072 -3.591052)
				)
				(arc
					(start 148.912072 -3.591052)
					(mid 148.897738 -3.581474)
					(end 148.88083 -3.578098)
				)
				(arc
					(start 148.536406 -3.578098)
					(mid 148.484673 -3.586778)
					(end 148.438616 -3.61188)
				)
				(arc
					(start 148.438616 -3.999738)
					(mid 148.999829 -4.561332)
					(end 149.561296 -3.999992)
				)
			)
		)
	)
	(zone
		(layer "B.Cu")
		(hatch none 0.5)
		(connect_pads
			(clearance 0)
		)
		(min_thickness 0.25)
		(keepout
			(tracks not_allowed)
			(vias allowed)
			(pads allowed)
			(copperpour not_allowed)
			(footprints allowed)
		)
		(placement
			(enabled no)
			(sheetname "")
		)
		(fill
			(thermal_gap 0.5)
			(thermal_bridge_width 0.5)
			(island_removal_mode 0)
		)
		(polygon
			(pts
				(arc
					(start 113.561368 -2.600198)
					(mid 113.000028 -2.038858)
					(end 112.438688 -2.600198)
				)
				(arc
					(start 112.438688 -3.028442)
					(mid 112.47164 -3.024751)
					(end 112.504728 -3.0226)
				)
				(xy 112.50549 -3.021838)
				(arc
					(start 112.880902 -3.021838)
					(mid 112.897815 -3.018474)
					(end 112.912144 -3.008884)
				)
				(arc
					(start 112.912144 -3.008884)
					(mid 112.919741 -2.99858)
					(end 112.924082 -2.986532)
				)
				(arc
					(start 112.924082 -2.986532)
					(mid 113.001054 -2.206422)
					(end 113.074958 -2.986786)
				)
				(xy 113.074958 -3.00863)
				(arc
					(start 113.07191 -3.011678)
					(mid 113.052979 -3.067209)
					(end 113.018316 -3.114548)
				)
				(arc
					(start 113.018316 -3.114548)
					(mid 112.9708 -3.149578)
					(end 112.914938 -3.16865)
				)
				(xy 112.91189 -3.171698)
				(arc
					(start 112.536478 -3.171698)
					(mid 112.487394 -3.17388)
					(end 112.438688 -3.180334)
				)
				(arc
					(start 112.438688 -3.44424)
					(mid 112.470813 -3.435359)
					(end 112.503712 -3.430016)
				)
				(xy 112.50549 -3.428238) (xy 112.91189 -3.428238)
				(arc
					(start 112.914938 -3.431286)
					(mid 112.970787 -3.450383)
					(end 113.018316 -3.485388)
				)
				(arc
					(start 113.018316 -3.485388)
					(mid 113.053004 -3.532714)
					(end 113.07191 -3.588258)
				)
				(xy 113.074958 -3.591306)
				(arc
					(start 113.074958 -3.613404)
					(mid 113.00093 -4.393726)
					(end 112.924336 -3.613658)
				)
				(arc
					(start 112.924336 -3.613658)
					(mid 112.919938 -3.601436)
					(end 112.912144 -3.591052)
				)
				(arc
					(start 112.912144 -3.591052)
					(mid 112.89781 -3.581474)
					(end 112.880902 -3.578098)
				)
				(arc
					(start 112.536478 -3.578098)
					(mid 112.484745 -3.586778)
					(end 112.438688 -3.61188)
				)
				(arc
					(start 112.438688 -3.999738)
					(mid 112.999901 -4.561332)
					(end 113.561368 -3.999992)
				)
			)
		)
	)
	(zone
		(net "P1V8_C")
		(layer "B.Cu")
		(hatch none 0.5)
		(connect_pads
			(clearance 0.5)
		)
		(min_thickness 0.25)
		(fill yes
			(thermal_gap 0.5)
			(thermal_bridge_width 0.5)
			(island_removal_mode 0)
		)
		(polygon
			(pts
				(xy 151.3332 -66.929) (xy 150.46071 -67.80149) (xy 150.46071 -71.14794) (xy 150.67661 -71.36384)
				(xy 158.118556 -71.36384) (xy 160.143444 -69.338952) (xy 168.208706 -69.338952) (xy 168.385236 -69.162676)
				(xy 168.385236 -67.244468) (xy 168.069768 -66.929)
			)
		)
		(polygon
			(pts
				(xy 157.359604 -67.475608) (xy 157.156404 -67.475608) (xy 157.156404 -67.678808) (xy 157.359604 -67.678808)
			)
		)
		(polygon
			(pts
				(xy 156.800804 -67.475608) (xy 156.597604 -67.475608) (xy 156.597604 -67.678808) (xy 156.800804 -67.678808)
			)
		)
		(polygon
			(pts
				(xy 155.708604 -67.475608) (xy 155.505404 -67.475608) (xy 155.505404 -67.678808) (xy 155.708604 -67.678808)
			)
		)
		(polygon
			(pts
				(xy 155.149804 -67.475608) (xy 154.946604 -67.475608) (xy 154.946604 -67.678808) (xy 155.149804 -67.678808)
			)
		)
		(polygon
			(pts
				(xy 165.989 -67.3862) (xy 165.7858 -67.3862) (xy 165.7858 -67.5894) (xy 165.989 -67.5894)
			)
		)
		(polygon
			(pts
				(xy 165.4302 -67.3862) (xy 165.227 -67.3862) (xy 165.227 -67.5894) (xy 165.4302 -67.5894)
			)
		)
		(polygon
			(pts
				(xy 164.338 -67.3862) (xy 164.1348 -67.3862) (xy 164.1348 -67.5894) (xy 164.338 -67.5894)
			)
		)
		(polygon
			(pts
				(xy 163.7792 -67.3862) (xy 163.576 -67.3862) (xy 163.576 -67.5894) (xy 163.7792 -67.5894)
			)
		)
	)
	(zone
		(layer "B.Cu")
		(hatch none 0.5)
		(connect_pads
			(clearance 0)
		)
		(min_thickness 0.25)
		(keepout
			(tracks not_allowed)
			(vias allowed)
			(pads allowed)
			(copperpour not_allowed)
			(footprints allowed)
		)
		(placement
			(enabled no)
			(sheetname "")
		)
		(fill
			(thermal_gap 0.5)
			(thermal_bridge_width 0.5)
			(island_removal_mode 0)
		)
		(polygon
			(pts
				(arc
					(start 145.961354 -2.600198)
					(mid 145.400014 -2.038858)
					(end 144.838674 -2.600198)
				)
				(arc
					(start 144.838674 -3.028442)
					(mid 144.871626 -3.024751)
					(end 144.904714 -3.0226)
				)
				(xy 144.905476 -3.021838)
				(arc
					(start 145.280888 -3.021838)
					(mid 145.297801 -3.018474)
					(end 145.31213 -3.008884)
				)
				(arc
					(start 145.31213 -3.008884)
					(mid 145.319727 -2.99858)
					(end 145.324068 -2.986532)
				)
				(arc
					(start 145.324068 -2.986532)
					(mid 145.40104 -2.206422)
					(end 145.474944 -2.986786)
				)
				(xy 145.474944 -3.00863)
				(arc
					(start 145.471896 -3.011678)
					(mid 145.452965 -3.067209)
					(end 145.418302 -3.114548)
				)
				(arc
					(start 145.418302 -3.114548)
					(mid 145.370786 -3.149578)
					(end 145.314924 -3.16865)
				)
				(xy 145.311876 -3.171698)
				(arc
					(start 144.936464 -3.171698)
					(mid 144.88738 -3.17388)
					(end 144.838674 -3.180334)
				)
				(arc
					(start 144.838674 -3.44424)
					(mid 144.870799 -3.435359)
					(end 144.903698 -3.430016)
				)
				(xy 144.905476 -3.428238) (xy 145.311876 -3.428238)
				(arc
					(start 145.314924 -3.431286)
					(mid 145.370773 -3.450383)
					(end 145.418302 -3.485388)
				)
				(arc
					(start 145.418302 -3.485388)
					(mid 145.45299 -3.532714)
					(end 145.471896 -3.588258)
				)
				(xy 145.474944 -3.591306)
				(arc
					(start 145.474944 -3.613404)
					(mid 145.400916 -4.393726)
					(end 145.324322 -3.613658)
				)
				(arc
					(start 145.324322 -3.613658)
					(mid 145.319924 -3.601436)
					(end 145.31213 -3.591052)
				)
				(arc
					(start 145.31213 -3.591052)
					(mid 145.297796 -3.581474)
					(end 145.280888 -3.578098)
				)
				(arc
					(start 144.936464 -3.578098)
					(mid 144.884731 -3.586778)
					(end 144.838674 -3.61188)
				)
				(arc
					(start 144.838674 -3.999738)
					(mid 145.399887 -4.561332)
					(end 145.961354 -3.999992)
				)
			)
		)
	)
	(zone
		(layer "B.Cu")
		(hatch none 0.5)
		(connect_pads
			(clearance 0)
		)
		(min_thickness 0.25)
		(keepout
			(tracks not_allowed)
			(vias allowed)
			(pads allowed)
			(copperpour not_allowed)
			(footprints allowed)
		)
		(placement
			(enabled no)
			(sheetname "")
		)
		(fill
			(thermal_gap 0.5)
			(thermal_bridge_width 0.5)
			(island_removal_mode 0)
		)
		(polygon
			(pts
				(arc
					(start 114.358166 -55.000144)
					(mid 114.047177 -54.645121)
					(end 113.654332 -54.906672)
				)
				(arc
					(start 113.654332 -55.245508)
					(mid 113.661872 -55.283417)
					(end 113.683288 -55.315612)
				)
				(arc
					(start 113.683288 -55.315612)
					(mid 113.719079 -55.339464)
					(end 113.761266 -55.34787)
				)
				(arc
					(start 113.911126 -55.34787)
					(mid 113.933577 -55.338571)
					(end 113.942876 -55.31612)
				)
				(arc
					(start 113.942876 -55.234586)
					(mid 114.000026 -54.758837)
					(end 114.057176 -55.234586)
				)
				(xy 114.057176 -55.339742)
				(arc
					(start 114.05489 -55.342028)
					(mid 114.01442 -55.419414)
					(end 113.937034 -55.459884)
				)
				(xy 113.934748 -55.46217) (xy 113.737644 -55.46217)
				(arc
					(start 113.73612 -55.460646)
					(mid 113.687168 -55.449546)
					(end 113.641886 -55.42788)
				)
				(arc
					(start 113.641886 -55.513732)
					(mid 113.700068 -55.532094)
					(end 113.760758 -55.53837)
				)
				(xy 113.934748 -55.53837)
				(arc
					(start 113.937034 -55.540656)
					(mid 114.01442 -55.581126)
					(end 114.05489 -55.658512)
				)
				(xy 114.057176 -55.660798)
				(arc
					(start 114.057176 -55.7657)
					(mid 114.000026 -56.241449)
					(end 113.942876 -55.7657)
				)
				(arc
					(start 113.942876 -55.68442)
					(mid 113.933577 -55.661969)
					(end 113.911126 -55.65267)
				)
				(xy 113.737644 -55.65267)
				(arc
					(start 113.736882 -55.651908)
					(mid 113.688894 -55.646299)
					(end 113.641886 -55.635144)
				)
				(arc
					(start 113.641886 -55.999888)
					(mid 113.999899 -56.358282)
					(end 114.358166 -56.000142)
				)
			)
		)
	)
	(zone
		(net "GND")
		(layer "B.Cu")
		(hatch none 0.5)
		(connect_pads
			(clearance 0.5)
		)
		(min_thickness 0.25)
		(fill yes
			(thermal_gap 0.5)
			(thermal_bridge_width 0.5)
			(island_removal_mode 0)
		)
		(polygon
			(pts
				(xy 158.5722 -116.2812) (xy 158.4706 -116.3828) (xy 158.4706 -118.4656) (xy 158.5722 -118.5672)
				(xy 160.0962 -118.5672) (xy 160.3756 -118.2878) (xy 160.3756 -116.4082) (xy 160.2486 -116.2812)
			)
		)
	)
	(zone
		(net "GND")
		(layer "B.Cu")
		(hatch none 0.5)
		(connect_pads
			(clearance 0.5)
		)
		(min_thickness 0.25)
		(fill yes
			(thermal_gap 0.5)
			(thermal_bridge_width 0.5)
			(island_removal_mode 0)
		)
		(polygon
			(pts
				(xy 92.007182 -61.9252) (xy 91.613482 -62.3189) (xy 91.613482 -63.602616) (xy 91.702382 -63.691516)
				(xy 91.824556 -63.813436) (xy 95.699834 -63.813436) (xy 96.0628 -63.45047) (xy 96.0628 -62.1538)
				(xy 95.8342 -61.9252)
			)
		)
		(polygon
			(pts
				(xy 93.76156 -63.17996) (xy 93.55836 -63.17996) (xy 93.55836 -63.38316) (xy 93.76156 -63.38316)
			)
		)
		(polygon
			(pts
				(xy 93.05036 -63.17996) (xy 92.84716 -63.17996) (xy 92.84716 -63.38316) (xy 93.05036 -63.38316)
			)
		)
		(polygon
			(pts
				(xy 92.68714 -62.79896) (xy 92.48394 -62.79896) (xy 92.48394 -63.00216) (xy 92.68714 -63.00216)
			)
		)
	)
	(zone
		(layer "B.Cu")
		(hatch none 0.5)
		(connect_pads
			(clearance 0)
		)
		(min_thickness 0.25)
		(keepout
			(tracks not_allowed)
			(vias allowed)
			(pads allowed)
			(copperpour not_allowed)
			(footprints allowed)
		)
		(placement
			(enabled no)
			(sheetname "")
		)
		(fill
			(thermal_gap 0.5)
			(thermal_bridge_width 0.5)
			(island_removal_mode 0)
		)
		(polygon
			(pts
				(arc
					(start 126.000256 -68.641976)
					(mid 125.641862 -68.999989)
					(end 126.000002 -69.358256)
				)
				(arc
					(start 127 -69.358256)
					(mid 127.35566 -69.042193)
					(end 127.083566 -68.651882)
				)
				(arc
					(start 126.750318 -68.651882)
					(mid 126.68099 -68.680598)
					(end 126.652274 -68.749926)
				)
				(arc
					(start 126.652274 -68.90004)
					(mid 126.664847 -68.930393)
					(end 126.6952 -68.942966)
				)
				(arc
					(start 126.765558 -68.942966)
					(mid 127.241307 -69.000116)
					(end 126.765558 -69.057266)
				)
				(xy 126.671578 -69.057266)
				(arc
					(start 126.669292 -69.055234)
					(mid 126.583943 -69.011297)
					(end 126.540006 -68.925948)
				)
				(xy 126.537974 -68.923662) (xy 126.537974 -68.726304)
				(arc
					(start 126.539498 -68.72478)
					(mid 126.549185 -68.681935)
					(end 126.567438 -68.641976)
				)
				(arc
					(start 126.482602 -68.641976)
					(mid 126.466988 -68.694949)
					(end 126.461774 -68.749926)
				)
				(xy 126.461774 -68.923916)
				(arc
					(start 126.459742 -68.926202)
					(mid 126.415882 -69.011374)
					(end 126.33071 -69.055234)
				)
				(xy 126.328424 -69.057266)
				(arc
					(start 126.234444 -69.057266)
					(mid 125.758695 -69.000116)
					(end 126.234444 -68.942966)
				)
				(arc
					(start 126.304802 -68.942966)
					(mid 126.334976 -68.930468)
					(end 126.347474 -68.900294)
				)
				(xy 126.347474 -68.726304)
				(arc
					(start 126.348236 -68.725542)
					(mid 126.35303 -68.683393)
					(end 126.362206 -68.641976)
				)
			)
		)
	)
	(zone
		(net "P1V8_E_OUT")
		(layer "B.Cu")
		(hatch none 0.5)
		(connect_pads
			(clearance 0.5)
		)
		(min_thickness 0.25)
		(fill yes
			(thermal_gap 0.5)
			(thermal_bridge_width 0.5)
			(island_removal_mode 0)
		)
		(polygon
			(pts
				(xy 178.4096 -114.7826) (xy 178.2064 -114.9858) (xy 178.2064 -118.0719) (xy 177.7746 -118.5037)
				(xy 177.7746 -121.5136) (xy 178.1556 -121.8946) (xy 182.2196 -121.8946) (xy 182.9816 -121.1326)
				(xy 182.9816 -114.9096) (xy 182.8546 -114.7826)
			)
		)
	)
	(zone
		(layer "B.Cu")
		(hatch none 0.5)
		(connect_pads
			(clearance 0)
		)
		(min_thickness 0.25)
		(keepout
			(tracks not_allowed)
			(vias allowed)
			(pads allowed)
			(copperpour not_allowed)
			(footprints allowed)
		)
		(placement
			(enabled no)
			(sheetname "")
		)
		(fill
			(thermal_gap 0.5)
			(thermal_bridge_width 0.5)
			(island_removal_mode 0)
		)
		(polygon
			(pts
				(arc
					(start 111.761524 -3.800094)
					(mid 111.200184 -3.238754)
					(end 110.638844 -3.800094)
				)
				(arc
					(start 110.638844 -4.228592)
					(mid 110.671796 -4.224901)
					(end 110.704884 -4.22275)
				)
				(xy 110.705646 -4.221988)
				(arc
					(start 111.081058 -4.221988)
					(mid 111.097971 -4.218624)
					(end 111.1123 -4.209034)
				)
				(arc
					(start 111.1123 -4.209034)
					(mid 111.120066 -4.198635)
					(end 111.124492 -4.186428)
				)
				(arc
					(start 111.124492 -4.186428)
					(mid 111.201086 -3.406367)
					(end 111.275114 -4.186682)
				)
				(xy 111.275114 -4.20878)
				(arc
					(start 111.272066 -4.211828)
					(mid 111.253135 -4.267359)
					(end 111.218472 -4.314698)
				)
				(arc
					(start 111.218472 -4.314698)
					(mid 111.170956 -4.349728)
					(end 111.115094 -4.3688)
				)
				(xy 111.112046 -4.371848)
				(arc
					(start 110.736634 -4.371848)
					(mid 110.68755 -4.37403)
					(end 110.638844 -4.380484)
				)
				(arc
					(start 110.638844 -4.64439)
					(mid 110.670969 -4.635509)
					(end 110.703868 -4.630166)
				)
				(xy 110.705646 -4.628388) (xy 111.112046 -4.628388)
				(arc
					(start 111.115094 -4.631436)
					(mid 111.170943 -4.650533)
					(end 111.218472 -4.685538)
				)
				(arc
					(start 111.218472 -4.685538)
					(mid 111.25316 -4.732864)
					(end 111.272066 -4.788408)
				)
				(xy 111.275114 -4.791456)
				(arc
					(start 111.275114 -4.813554)
					(mid 111.201086 -5.593876)
					(end 111.124492 -4.813808)
				)
				(arc
					(start 111.124492 -4.813808)
					(mid 111.120094 -4.801586)
					(end 111.1123 -4.791202)
				)
				(arc
					(start 111.1123 -4.791202)
					(mid 111.097966 -4.781624)
					(end 111.081058 -4.778248)
				)
				(arc
					(start 110.736634 -4.778248)
					(mid 110.684901 -4.786928)
					(end 110.638844 -4.81203)
				)
				(arc
					(start 110.638844 -5.199888)
					(mid 111.200057 -5.761482)
					(end 111.761524 -5.200142)
				)
			)
		)
	)
	(zone
		(net "GND")
		(layer "B.Cu")
		(hatch none 0.5)
		(connect_pads
			(clearance 0.5)
		)
		(min_thickness 0.25)
		(fill yes
			(thermal_gap 0.5)
			(thermal_bridge_width 0.5)
			(island_removal_mode 0)
		)
		(polygon
			(pts
				(xy 156.7688 -33.655) (xy 156.591 -33.8328) (xy 156.591 -34.798) (xy 157.2006 -35.4076) (xy 160.6042 -35.4076)
				(xy 160.909 -35.1028) (xy 160.909 -33.782) (xy 160.782 -33.655)
			)
		)
		(polygon
			(pts
				(xy 160.142174 -34.444432) (xy 159.938974 -34.444432) (xy 159.938974 -34.647632) (xy 160.142174 -34.647632)
			)
		)
	)
	(zone
		(layer "B.Cu")
		(hatch none 0.5)
		(connect_pads
			(clearance 0)
		)
		(min_thickness 0.25)
		(keepout
			(tracks not_allowed)
			(vias allowed)
			(pads allowed)
			(copperpour not_allowed)
			(footprints allowed)
		)
		(placement
			(enabled no)
			(sheetname "")
		)
		(fill
			(thermal_gap 0.5)
			(thermal_bridge_width 0.5)
			(island_removal_mode 0)
		)
		(polygon
			(pts
				(arc
					(start 184.161176 -10.999978)
					(mid 183.599836 -10.438638)
					(end 183.038496 -10.999978)
				)
				(xy 183.038496 -11.464036) (xy 183.089296 -11.459464) (xy 183.090058 -11.458448) (xy 183.112664 -11.458448)
				(xy 183.125618 -11.458448) (xy 183.13019 -11.458448) (xy 183.419242 -11.458448)
				(arc
					(start 183.423814 -11.458448)
					(mid 183.481843 -11.437295)
					(end 183.512714 -11.383772)
				)
				(arc
					(start 183.512714 -11.383772)
					(mid 183.601515 -10.606309)
					(end 183.685688 -11.38428)
				)
				(xy 183.685688 -11.403838)
				(arc
					(start 183.682894 -11.406378)
					(mid 183.608982 -11.553446)
					(end 183.461914 -11.627358)
				)
				(xy 183.459374 -11.630152) (xy 183.431942 -11.630152) (xy 183.423814 -11.630152) (xy 183.419242 -11.630152)
				(xy 183.13019 -11.630152)
				(arc
					(start 183.125618 -11.630152)
					(mid 183.081889 -11.632041)
					(end 183.038496 -11.637772)
				)
				(arc
					(start 183.038496 -11.78052)
					(mid 183.063229 -11.775183)
					(end 183.08828 -11.77163)
				)
				(xy 183.090058 -11.769852) (xy 183.11622 -11.769852) (xy 183.125618 -11.769598) (xy 183.13019 -11.769852)
				(xy 183.418988 -11.769852) (xy 183.42356 -11.769598) (xy 183.431688 -11.769852) (xy 183.45912 -11.769852)
				(arc
					(start 183.46166 -11.772392)
					(mid 183.608905 -11.846381)
					(end 183.682894 -11.993626)
				)
				(xy 183.685688 -11.996166)
				(arc
					(start 183.685688 -12.015724)
					(mid 183.601515 -12.793689)
					(end 183.512714 -12.016232)
				)
				(arc
					(start 183.512714 -12.016232)
					(mid 183.481811 -11.962478)
					(end 183.42356 -11.941302)
				)
				(xy 183.418988 -11.941048) (xy 183.13019 -11.941048)
				(arc
					(start 183.125618 -11.941302)
					(mid 183.080716 -11.94686)
					(end 183.038496 -11.963146)
				)
				(arc
					(start 183.038496 -12.399772)
					(mid 183.599709 -12.961366)
					(end 184.161176 -12.400026)
				)
			)
		)
	)
	(zone
		(layer "B.Cu")
		(hatch none 0.5)
		(connect_pads
			(clearance 0)
		)
		(min_thickness 0.25)
		(keepout
			(tracks not_allowed)
			(vias allowed)
			(pads allowed)
			(copperpour not_allowed)
			(footprints allowed)
		)
		(placement
			(enabled no)
			(sheetname "")
		)
		(fill
			(thermal_gap 0.5)
			(thermal_bridge_width 0.5)
			(island_removal_mode 0)
		)
		(polygon
			(pts
				(arc
					(start 127.96139 -2.600198)
					(mid 127.40005 -2.038858)
					(end 126.83871 -2.600198)
				)
				(arc
					(start 126.83871 -3.028442)
					(mid 126.871662 -3.024751)
					(end 126.90475 -3.0226)
				)
				(xy 126.905512 -3.021838)
				(arc
					(start 127.280924 -3.021838)
					(mid 127.297837 -3.018474)
					(end 127.312166 -3.008884)
				)
				(arc
					(start 127.312166 -3.008884)
					(mid 127.319763 -2.99858)
					(end 127.324104 -2.986532)
				)
				(arc
					(start 127.324104 -2.986532)
					(mid 127.401076 -2.206422)
					(end 127.47498 -2.986786)
				)
				(xy 127.47498 -3.00863)
				(arc
					(start 127.471932 -3.011678)
					(mid 127.453001 -3.067209)
					(end 127.418338 -3.114548)
				)
				(arc
					(start 127.418338 -3.114548)
					(mid 127.370822 -3.149578)
					(end 127.31496 -3.16865)
				)
				(xy 127.311912 -3.171698)
				(arc
					(start 126.9365 -3.171698)
					(mid 126.887416 -3.17388)
					(end 126.83871 -3.180334)
				)
				(arc
					(start 126.83871 -3.44424)
					(mid 126.870835 -3.435359)
					(end 126.903734 -3.430016)
				)
				(xy 126.905512 -3.428238) (xy 127.311912 -3.428238)
				(arc
					(start 127.31496 -3.431286)
					(mid 127.370809 -3.450383)
					(end 127.418338 -3.485388)
				)
				(arc
					(start 127.418338 -3.485388)
					(mid 127.453026 -3.532714)
					(end 127.471932 -3.588258)
				)
				(xy 127.47498 -3.591306)
				(arc
					(start 127.47498 -3.613404)
					(mid 127.400952 -4.393726)
					(end 127.324358 -3.613658)
				)
				(arc
					(start 127.324358 -3.613658)
					(mid 127.31996 -3.601436)
					(end 127.312166 -3.591052)
				)
				(arc
					(start 127.312166 -3.591052)
					(mid 127.297832 -3.581474)
					(end 127.280924 -3.578098)
				)
				(arc
					(start 126.9365 -3.578098)
					(mid 126.884767 -3.586778)
					(end 126.83871 -3.61188)
				)
				(arc
					(start 126.83871 -3.999738)
					(mid 127.399923 -4.561332)
					(end 127.96139 -3.999992)
				)
			)
		)
	)
	(zone
		(layer "B.Cu")
		(hatch none 0.5)
		(connect_pads
			(clearance 0)
		)
		(min_thickness 0.25)
		(keepout
			(tracks not_allowed)
			(vias allowed)
			(pads allowed)
			(copperpour not_allowed)
			(footprints allowed)
		)
		(placement
			(enabled no)
			(sheetname "")
		)
		(fill
			(thermal_gap 0.5)
			(thermal_bridge_width 0.5)
			(island_removal_mode 0)
		)
		(polygon
			(pts
				(arc
					(start 126.000256 -67.641978)
					(mid 125.641862 -67.999991)
					(end 126.000002 -68.358258)
				)
				(arc
					(start 127 -68.358258)
					(mid 127.35566 -68.042195)
					(end 127.083566 -67.651884)
				)
				(arc
					(start 126.750318 -67.651884)
					(mid 126.68099 -67.6806)
					(end 126.652274 -67.749928)
				)
				(arc
					(start 126.652274 -67.900042)
					(mid 126.664847 -67.930395)
					(end 126.6952 -67.942968)
				)
				(arc
					(start 126.765558 -67.942968)
					(mid 127.241307 -68.000118)
					(end 126.765558 -68.057268)
				)
				(xy 126.671578 -68.057268)
				(arc
					(start 126.669292 -68.055236)
					(mid 126.583943 -68.011299)
					(end 126.540006 -67.92595)
				)
				(xy 126.537974 -67.923664) (xy 126.537974 -67.726306)
				(arc
					(start 126.539498 -67.724782)
					(mid 126.549185 -67.681937)
					(end 126.567438 -67.641978)
				)
				(arc
					(start 126.482602 -67.641978)
					(mid 126.466988 -67.694951)
					(end 126.461774 -67.749928)
				)
				(xy 126.461774 -67.923918)
				(arc
					(start 126.459742 -67.926204)
					(mid 126.415882 -68.011376)
					(end 126.33071 -68.055236)
				)
				(xy 126.328424 -68.057268)
				(arc
					(start 126.234444 -68.057268)
					(mid 125.758695 -68.000118)
					(end 126.234444 -67.942968)
				)
				(arc
					(start 126.304802 -67.942968)
					(mid 126.334976 -67.93047)
					(end 126.347474 -67.900296)
				)
				(xy 126.347474 -67.726306)
				(arc
					(start 126.348236 -67.725544)
					(mid 126.35303 -67.683395)
					(end 126.362206 -67.641978)
				)
			)
		)
	)
	(zone
		(net "GND")
		(layer "B.Cu")
		(hatch none 0.5)
		(connect_pads
			(clearance 0.5)
		)
		(min_thickness 0.25)
		(fill yes
			(thermal_gap 0.5)
			(thermal_bridge_width 0.5)
			(island_removal_mode 0)
		)
		(polygon
			(pts
				(xy 80.4164 -69.2785) (xy 80.33385 -69.36105) (xy 80.33385 -70.08495) (xy 80.4926 -70.2437) (xy 82.9818 -70.2437)
				(xy 83.06435 -70.16115) (xy 83.06435 -69.42455) (xy 82.9183 -69.2785)
			)
		)
		(polygon
			(pts
				(xy 82.419698 -69.53758) (xy 81.937098 -69.53758) (xy 81.937098 -69.74078) (xy 82.419698 -69.74078)
			)
		)
		(polygon
			(pts
				(xy 81.530698 -69.53758) (xy 81.327498 -69.53758) (xy 81.327498 -69.74078) (xy 81.530698 -69.74078)
			)
		)
	)
	(zone
		(layer "B.Cu")
		(hatch none 0.5)
		(connect_pads
			(clearance 0)
		)
		(min_thickness 0.25)
		(keepout
			(tracks allowed)
			(vias allowed)
			(pads allowed)
			(copperpour allowed)
			(footprints not_allowed)
		)
		(placement
			(enabled no)
			(sheetname "")
		)
		(fill
			(thermal_gap 0.5)
			(thermal_bridge_width 0.5)
			(island_removal_mode 0)
		)
		(polygon
			(pts
				(arc
					(start 131.99999 -94.309946)
					(mid 134.999984 -97.30994)
					(end 137.999978 -94.309946)
				)
				(arc
					(start 137.999978 -94.309946)
					(mid 134.999984 -91.309952)
					(end 131.99999 -94.309946)
				)
			)
		)
	)
	(zone
		(layer "B.Cu")
		(hatch none 0.5)
		(connect_pads
			(clearance 0)
		)
		(min_thickness 0.25)
		(keepout
			(tracks allowed)
			(vias allowed)
			(pads allowed)
			(copperpour allowed)
			(footprints not_allowed)
		)
		(placement
			(enabled no)
			(sheetname "")
		)
		(fill
			(thermal_gap 0.5)
			(thermal_bridge_width 0.5)
			(island_removal_mode 0)
		)
		(polygon
			(pts
				(arc
					(start 30.684978 -3.700018)
					(mid 29.480002 -2.495042)
					(end 28.275026 -3.700018)
				)
				(arc
					(start 28.275026 -3.700018)
					(mid 29.480002 -4.904994)
					(end 30.684978 -3.700018)
				)
			)
		)
	)
	(zone
		(layer "B.Cu")
		(hatch none 0.5)
		(connect_pads
			(clearance 0)
		)
		(min_thickness 0.25)
		(keepout
			(tracks not_allowed)
			(vias allowed)
			(pads allowed)
			(copperpour not_allowed)
			(footprints allowed)
		)
		(placement
			(enabled no)
			(sheetname "")
		)
		(fill
			(thermal_gap 0.5)
			(thermal_bridge_width 0.5)
			(island_removal_mode 0)
		)
		(polygon
			(pts
				(arc
					(start 107.35818 -55.000144)
					(mid 107.040556 -54.644303)
					(end 106.651044 -54.919626)
				)
				(arc
					(start 106.651044 -55.237634)
					(mid 106.65942 -55.279834)
					(end 106.683302 -55.315612)
				)
				(arc
					(start 106.683302 -55.315612)
					(mid 106.719093 -55.339464)
					(end 106.76128 -55.34787)
				)
				(arc
					(start 106.91114 -55.34787)
					(mid 106.933591 -55.338571)
					(end 106.94289 -55.31612)
				)
				(arc
					(start 106.94289 -55.234586)
					(mid 107.00004 -54.758837)
					(end 107.05719 -55.234586)
				)
				(xy 107.05719 -55.339742)
				(arc
					(start 107.054904 -55.342028)
					(mid 107.014434 -55.419414)
					(end 106.937048 -55.459884)
				)
				(xy 106.934762 -55.46217) (xy 106.737658 -55.46217)
				(arc
					(start 106.736134 -55.460646)
					(mid 106.687182 -55.449546)
					(end 106.6419 -55.42788)
				)
				(arc
					(start 106.6419 -55.513732)
					(mid 106.700082 -55.532094)
					(end 106.760772 -55.53837)
				)
				(xy 106.934762 -55.53837)
				(arc
					(start 106.937048 -55.540656)
					(mid 107.014434 -55.581126)
					(end 107.054904 -55.658512)
				)
				(xy 107.05719 -55.660798)
				(arc
					(start 107.05719 -55.7657)
					(mid 107.00004 -56.241449)
					(end 106.94289 -55.7657)
				)
				(arc
					(start 106.94289 -55.68442)
					(mid 106.933591 -55.661969)
					(end 106.91114 -55.65267)
				)
				(xy 106.737658 -55.65267)
				(arc
					(start 106.736896 -55.651908)
					(mid 106.688908 -55.646299)
					(end 106.6419 -55.635144)
				)
				(arc
					(start 106.6419 -55.999888)
					(mid 106.999913 -56.358282)
					(end 107.35818 -56.000142)
				)
			)
		)
	)
	(zone
		(net "GND")
		(layer "B.Cu")
		(hatch none 0.5)
		(connect_pads
			(clearance 0.5)
		)
		(min_thickness 0.25)
		(fill yes
			(thermal_gap 0.5)
			(thermal_bridge_width 0.5)
			(island_removal_mode 0)
		)
		(polygon
			(pts
				(xy 163.540186 -27.497024) (xy 163.3347 -27.70251) (xy 163.3347 -31.1277) (xy 163.449 -31.242) (xy 163.449 -38.1254)
				(xy 163.6014 -38.2778) (xy 164.0586 -38.2778) (xy 164.465 -38.6842) (xy 165.6334 -38.6842) (xy 165.735 -38.5826)
				(xy 165.735 -37.3253) (xy 165.6715 -37.2618) (xy 165.1762 -37.2618) (xy 164.9476 -37.0332) (xy 164.9476 -31.1404)
				(xy 164.6301 -30.8229) (xy 164.6301 -28.993338) (xy 165.0873 -28.536138) (xy 165.0873 -27.5463)
				(xy 165.038024 -27.497024)
			)
		)
		(polygon
			(pts
				(xy 164.1602 -37.3888) (xy 163.957 -37.3888) (xy 163.957 -37.592) (xy 164.1602 -37.592)
			)
		)
		(polygon
			(pts
				(xy 164.166042 -37.010594) (xy 163.962842 -37.010594) (xy 163.962842 -37.213794) (xy 164.166042 -37.213794)
			)
		)
		(polygon
			(pts
				(xy 164.166042 -36.400994) (xy 163.962842 -36.400994) (xy 163.962842 -36.604194) (xy 164.166042 -36.604194)
			)
		)
		(polygon
			(pts
				(xy 164.300916 -35.405314) (xy 164.097716 -35.405314) (xy 164.097716 -35.608514) (xy 164.300916 -35.608514)
			)
		)
		(polygon
			(pts
				(xy 164.300916 -34.795714) (xy 164.097716 -34.795714) (xy 164.097716 -34.998914) (xy 164.300916 -34.998914)
			)
		)
		(polygon
			(pts
				(xy 164.1729 -34.4678) (xy 163.9697 -34.4678) (xy 163.9697 -34.671) (xy 164.1729 -34.671)
			)
		)
		(polygon
			(pts
				(xy 164.1602 -33.5534) (xy 163.957 -33.5534) (xy 163.957 -33.7566) (xy 163.9697 -33.8582) (xy 163.9697 -34.0614)
				(xy 164.1729 -34.0614) (xy 164.1729 -33.8582) (xy 164.1602 -33.7566)
			)
		)
		(polygon
			(pts
				(xy 164.1602 -32.8422) (xy 163.957 -32.8422) (xy 163.957 -33.0454) (xy 164.1602 -33.0454)
			)
		)
		(polygon
			(pts
				(xy 164.3126 -32.2199) (xy 164.1094 -32.2199) (xy 164.1094 -32.4231) (xy 164.3126 -32.4231)
			)
		)
		(polygon
			(pts
				(xy 164.3126 -31.5087) (xy 164.1094 -31.5087) (xy 164.1094 -31.7119) (xy 164.3126 -31.7119)
			)
		)
		(polygon
			(pts
				(xy 164.062918 -30.585156) (xy 163.859718 -30.585156) (xy 163.859718 -30.788356) (xy 164.062918 -30.788356)
			)
		)
		(polygon
			(pts
				(xy 164.062918 -29.696156) (xy 163.859718 -29.696156) (xy 163.859718 -30.178756) (xy 164.062918 -30.178756)
			)
		)
		(polygon
			(pts
				(xy 164.062918 -29.086556) (xy 163.859718 -29.086556) (xy 163.859718 -29.289756) (xy 164.062918 -29.289756)
			)
		)
		(polygon
			(pts
				(xy 164.816282 -28.345384) (xy 164.613082 -28.345384) (xy 164.613082 -28.548584) (xy 164.816282 -28.548584)
			)
		)
		(polygon
			(pts
				(xy 164.816282 -27.761184) (xy 164.613082 -27.761184) (xy 164.613082 -28.192984) (xy 164.816282 -28.192984)
			)
		)
	)
	(zone
		(net "P1V8_C")
		(layer "B.Cu")
		(hatch none 0.5)
		(connect_pads
			(clearance 0.5)
		)
		(min_thickness 0.25)
		(fill yes
			(thermal_gap 0.5)
			(thermal_bridge_width 0.5)
			(island_removal_mode 0)
		)
		(polygon
			(pts
				(xy 203.220828 -30.758892) (xy 202.97521 -31.00451) (xy 202.97521 -33.873694) (xy 203.521818 -34.420302)
				(xy 203.521818 -35.129216) (xy 203.569316 -35.176714) (xy 204.735938 -35.176714) (xy 204.837284 -35.075368)
				(xy 204.837284 -30.936692) (xy 204.659484 -30.758892)
			)
		)
		(polygon
			(pts
				(xy 204.265784 -34.5186) (xy 204.062584 -34.5186) (xy 204.062584 -34.7218) (xy 204.265784 -34.7218)
			)
		)
		(polygon
			(pts
				(xy 203.633578 -33.348422) (xy 203.430378 -33.348422) (xy 203.430378 -33.551622) (xy 203.633578 -33.551622)
			)
		)
		(polygon
			(pts
				(xy 203.633578 -32.789622) (xy 203.430378 -32.789622) (xy 203.430378 -32.992822) (xy 203.633578 -32.992822)
			)
		)
	)
	(zone
		(layer "B.Cu")
		(hatch none 0.5)
		(connect_pads
			(clearance 0)
		)
		(min_thickness 0.25)
		(keepout
			(tracks not_allowed)
			(vias allowed)
			(pads allowed)
			(copperpour not_allowed)
			(footprints allowed)
		)
		(placement
			(enabled no)
			(sheetname "")
		)
		(fill
			(thermal_gap 0.5)
			(thermal_bridge_width 0.5)
			(island_removal_mode 0)
		)
		(polygon
			(pts
				(arc
					(start 118.358158 -55.000144)
					(mid 118.042615 -54.644546)
					(end 117.652038 -54.915562)
				)
				(arc
					(start 117.652038 -55.240174)
					(mid 117.660159 -55.280999)
					(end 117.68328 -55.315612)
				)
				(arc
					(start 117.68328 -55.315612)
					(mid 117.719071 -55.339464)
					(end 117.761258 -55.34787)
				)
				(arc
					(start 117.911118 -55.34787)
					(mid 117.933569 -55.338571)
					(end 117.942868 -55.31612)
				)
				(arc
					(start 117.942868 -55.234586)
					(mid 118.000018 -54.758837)
					(end 118.057168 -55.234586)
				)
				(xy 118.057168 -55.339742)
				(arc
					(start 118.054882 -55.342028)
					(mid 118.014412 -55.419414)
					(end 117.937026 -55.459884)
				)
				(xy 117.93474 -55.46217) (xy 117.737636 -55.46217)
				(arc
					(start 117.736112 -55.460646)
					(mid 117.68716 -55.449546)
					(end 117.641878 -55.42788)
				)
				(arc
					(start 117.641878 -55.513732)
					(mid 117.70006 -55.532094)
					(end 117.76075 -55.53837)
				)
				(xy 117.93474 -55.53837)
				(arc
					(start 117.937026 -55.540656)
					(mid 118.014412 -55.581126)
					(end 118.054882 -55.658512)
				)
				(xy 118.057168 -55.660798)
				(arc
					(start 118.057168 -55.7657)
					(mid 118.000018 -56.241449)
					(end 117.942868 -55.7657)
				)
				(arc
					(start 117.942868 -55.68442)
					(mid 117.933569 -55.661969)
					(end 117.911118 -55.65267)
				)
				(xy 117.737636 -55.65267)
				(arc
					(start 117.736874 -55.651908)
					(mid 117.688886 -55.646299)
					(end 117.641878 -55.635144)
				)
				(arc
					(start 117.641878 -55.999888)
					(mid 117.999891 -56.358282)
					(end 118.358158 -56.000142)
				)
			)
		)
	)
	(zone
		(layer "B.Cu")
		(hatch none 0.5)
		(connect_pads
			(clearance 0)
		)
		(min_thickness 0.25)
		(keepout
			(tracks allowed)
			(vias allowed)
			(pads allowed)
			(copperpour allowed)
			(footprints not_allowed)
		)
		(placement
			(enabled no)
			(sheetname "")
		)
		(fill
			(thermal_gap 0.5)
			(thermal_bridge_width 0.5)
			(island_removal_mode 0)
		)
		(polygon
			(pts
				(xy 85.002624 -125.000004)
				(arc
					(start 85.002624 -121.000012)
					(mid 85.588409 -119.585801)
					(end 87.00262 -119.000016)
				)
				(arc
					(start 123.002548 -119.000016)
					(mid 124.416759 -119.585801)
					(end 125.002544 -121.000012)
				)
				(xy 125.002544 -125.000004) (xy 189.999874 -125.000004) (xy 189.999874 -105.000044) (xy 205.000098 -105.000044)
				(xy 205.000098 0) (xy 4.99999 0) (xy 4.99999 -105.000044) (xy 19.99996 -105.000044) (xy 19.99996 -125.000004)
			)
		)
	)
	(zone
		(net "P3V3_LL")
		(layer "B.Cu")
		(hatch none 0.5)
		(connect_pads
			(clearance 0.5)
		)
		(min_thickness 0.25)
		(fill yes
			(thermal_gap 0.5)
			(thermal_bridge_width 0.5)
			(island_removal_mode 0)
		)
		(polygon
			(pts
				(xy 57.277 -103.251) (xy 57.15 -103.378) (xy 57.15 -106.529124) (xy 57.453784 -106.832908) (xy 63.74384 -106.832908)
				(xy 64.135 -106.441748) (xy 64.135 -103.632) (xy 63.754 -103.251)
			)
		)
		(polygon
			(pts
				(xy 63.6016 -105.6132) (xy 63.3984 -105.6132) (xy 63.3984 -105.8164) (xy 63.6016 -105.8164)
			)
		)
		(polygon
			(pts
				(xy 63.6016 -105.0036) (xy 63.3984 -105.0036) (xy 63.3984 -105.2068) (xy 63.6016 -105.2068)
			)
		)
	)
	(zone
		(layer "B.Cu")
		(hatch none 0.5)
		(connect_pads
			(clearance 0)
		)
		(min_thickness 0.25)
		(keepout
			(tracks not_allowed)
			(vias allowed)
			(pads allowed)
			(copperpour not_allowed)
			(footprints allowed)
		)
		(placement
			(enabled no)
			(sheetname "")
		)
		(fill
			(thermal_gap 0.5)
			(thermal_bridge_width 0.5)
			(island_removal_mode 0)
		)
		(polygon
			(pts
				(arc
					(start 140.561314 -3.800094)
					(mid 139.999974 -3.238754)
					(end 139.438634 -3.800094)
				)
				(arc
					(start 139.438634 -4.228592)
					(mid 139.471586 -4.224901)
					(end 139.504674 -4.22275)
				)
				(xy 139.505436 -4.221988)
				(arc
					(start 139.880848 -4.221988)
					(mid 139.897761 -4.218624)
					(end 139.91209 -4.209034)
				)
				(arc
					(start 139.91209 -4.209034)
					(mid 139.919856 -4.198635)
					(end 139.924282 -4.186428)
				)
				(arc
					(start 139.924282 -4.186428)
					(mid 140.000876 -3.406367)
					(end 140.074904 -4.186682)
				)
				(xy 140.074904 -4.20878)
				(arc
					(start 140.071856 -4.211828)
					(mid 140.052925 -4.267359)
					(end 140.018262 -4.314698)
				)
				(arc
					(start 140.018262 -4.314698)
					(mid 139.970746 -4.349728)
					(end 139.914884 -4.3688)
				)
				(xy 139.911836 -4.371848)
				(arc
					(start 139.536424 -4.371848)
					(mid 139.48734 -4.37403)
					(end 139.438634 -4.380484)
				)
				(arc
					(start 139.438634 -4.64439)
					(mid 139.470759 -4.635509)
					(end 139.503658 -4.630166)
				)
				(xy 139.505436 -4.628388) (xy 139.911836 -4.628388)
				(arc
					(start 139.914884 -4.631436)
					(mid 139.970733 -4.650533)
					(end 140.018262 -4.685538)
				)
				(arc
					(start 140.018262 -4.685538)
					(mid 140.05295 -4.732864)
					(end 140.071856 -4.788408)
				)
				(xy 140.074904 -4.791456)
				(arc
					(start 140.074904 -4.813554)
					(mid 140.000876 -5.593876)
					(end 139.924282 -4.813808)
				)
				(arc
					(start 139.924282 -4.813808)
					(mid 139.919884 -4.801586)
					(end 139.91209 -4.791202)
				)
				(arc
					(start 139.91209 -4.791202)
					(mid 139.897756 -4.781624)
					(end 139.880848 -4.778248)
				)
				(arc
					(start 139.536424 -4.778248)
					(mid 139.484691 -4.786928)
					(end 139.438634 -4.81203)
				)
				(arc
					(start 139.438634 -5.199888)
					(mid 139.999847 -5.761482)
					(end 140.561314 -5.200142)
				)
			)
		)
	)
	(zone
		(layer "B.Cu")
		(hatch none 0.5)
		(connect_pads
			(clearance 0)
		)
		(min_thickness 0.25)
		(keepout
			(tracks not_allowed)
			(vias allowed)
			(pads allowed)
			(copperpour not_allowed)
			(footprints allowed)
		)
		(placement
			(enabled no)
			(sheetname "")
		)
		(fill
			(thermal_gap 0.5)
			(thermal_bridge_width 0.5)
			(island_removal_mode 0)
		)
		(polygon
			(pts
				(arc
					(start 138.76147 -2.600198)
					(mid 138.20013 -2.038858)
					(end 137.63879 -2.600198)
				)
				(arc
					(start 137.63879 -3.028442)
					(mid 137.671742 -3.024751)
					(end 137.70483 -3.0226)
				)
				(xy 137.705592 -3.021838)
				(arc
					(start 138.081004 -3.021838)
					(mid 138.097917 -3.018474)
					(end 138.112246 -3.008884)
				)
				(arc
					(start 138.112246 -3.008884)
					(mid 138.119843 -2.99858)
					(end 138.124184 -2.986532)
				)
				(arc
					(start 138.124184 -2.986532)
					(mid 138.201156 -2.206422)
					(end 138.27506 -2.986786)
				)
				(xy 138.27506 -3.00863)
				(arc
					(start 138.272012 -3.011678)
					(mid 138.253081 -3.067209)
					(end 138.218418 -3.114548)
				)
				(arc
					(start 138.218418 -3.114548)
					(mid 138.170902 -3.149578)
					(end 138.11504 -3.16865)
				)
				(xy 138.111992 -3.171698)
				(arc
					(start 137.73658 -3.171698)
					(mid 137.687496 -3.17388)
					(end 137.63879 -3.180334)
				)
				(arc
					(start 137.63879 -3.44424)
					(mid 137.670915 -3.435359)
					(end 137.703814 -3.430016)
				)
				(xy 137.705592 -3.428238) (xy 138.111992 -3.428238)
				(arc
					(start 138.11504 -3.431286)
					(mid 138.170889 -3.450383)
					(end 138.218418 -3.485388)
				)
				(arc
					(start 138.218418 -3.485388)
					(mid 138.253106 -3.532714)
					(end 138.272012 -3.588258)
				)
				(xy 138.27506 -3.591306)
				(arc
					(start 138.27506 -3.613404)
					(mid 138.201032 -4.393726)
					(end 138.124438 -3.613658)
				)
				(arc
					(start 138.124438 -3.613658)
					(mid 138.12004 -3.601436)
					(end 138.112246 -3.591052)
				)
				(arc
					(start 138.112246 -3.591052)
					(mid 138.097912 -3.581474)
					(end 138.081004 -3.578098)
				)
				(arc
					(start 137.73658 -3.578098)
					(mid 137.684847 -3.586778)
					(end 137.63879 -3.61188)
				)
				(arc
					(start 137.63879 -3.999738)
					(mid 138.200003 -4.561332)
					(end 138.76147 -3.999992)
				)
			)
		)
	)
	(zone
		(net "GND")
		(layer "B.Cu")
		(hatch none 0.5)
		(connect_pads
			(clearance 0.5)
		)
		(min_thickness 0.25)
		(fill yes
			(thermal_gap 0.5)
			(thermal_bridge_width 0.5)
			(island_removal_mode 0)
		)
		(polygon
			(pts
				(xy 166.9415 -58.8518) (xy 166.8145 -58.9788) (xy 166.8145 -64.1985) (xy 167.072564 -64.456564)
				(xy 170.366436 -64.456564) (xy 170.434 -64.389) (xy 170.434 -63.246) (xy 170.3324 -63.1444) (xy 168.9354 -63.1444)
				(xy 168.783 -62.992) (xy 168.783 -58.9788) (xy 168.656 -58.8518)
			)
		)
		(polygon
			(pts
				(xy 169.7228 -63.6524) (xy 169.5196 -63.6524) (xy 169.5196 -63.8556) (xy 169.7228 -63.8556)
			)
		)
		(polygon
			(pts
				(xy 167.9956 -63.4746) (xy 167.7924 -63.4746) (xy 167.7924 -63.6778) (xy 167.9956 -63.6778)
			)
		)
		(polygon
			(pts
				(xy 167.132 -63.4746) (xy 166.9288 -63.4746) (xy 166.9288 -63.6778) (xy 167.132 -63.6778)
			)
		)
		(polygon
			(pts
				(xy 167.5384 -60.7568) (xy 167.3352 -60.7568) (xy 167.3352 -60.96) (xy 167.5384 -60.96)
			)
		)
		(polygon
			(pts
				(xy 167.4876 -59.8678) (xy 167.2844 -59.8678) (xy 167.2844 -60.071) (xy 167.3352 -60.1472) (xy 167.3352 -60.3504)
				(xy 167.5384 -60.3504) (xy 167.5384 -60.1472) (xy 167.4876 -60.071)
			)
		)
		(polygon
			(pts
				(xy 167.4876 -59.1566) (xy 167.2844 -59.1566) (xy 167.2844 -59.3598) (xy 167.4876 -59.3598)
			)
		)
	)
	(zone
		(net "GND")
		(layer "B.Cu")
		(hatch none 0.5)
		(connect_pads
			(clearance 0.5)
		)
		(min_thickness 0.25)
		(fill yes
			(thermal_gap 0.5)
			(thermal_bridge_width 0.5)
			(island_removal_mode 0)
		)
		(polygon
			(pts
				(xy 170.105832 -33.3248) (xy 169.897044 -33.533588) (xy 169.897044 -37.577268) (xy 169.89806 -37.578284)
				(xy 169.89806 -37.80917) (xy 169.969688 -37.880798) (xy 170.295316 -37.880798) (xy 171.298108 -36.878006)
				(xy 171.298108 -35.765486) (xy 171.541694 -35.5219) (xy 178.943 -35.5219) (xy 179.5145 -36.0934)
				(xy 179.5145 -44.1325) (xy 180.2384 -44.8564) (xy 180.2384 -45.847) (xy 179.9717 -46.1137) (xy 179.259484 -46.1137)
				(xy 179.170584 -46.2026) (xy 173.9392 -46.2026) (xy 173.6598 -45.9232) (xy 173.6598 -45.4406) (xy 173.56201 -45.34281)
				(xy 172.522642 -45.34281) (xy 172.344842 -45.52061) (xy 172.344842 -48.405542) (xy 172.306488 -48.443896)
				(xy 170.961304 -48.443896) (xy 170.447716 -47.930308) (xy 170.447716 -40.783002) (xy 170.915076 -40.315642)
				(xy 171.216828 -40.315642) (xy 171.3484 -40.18407) (xy 171.3484 -38.0365) (xy 171.292266 -37.980366)
				(xy 170.7007 -37.980366) (xy 170.561254 -38.119812) (xy 170.561254 -38.683946) (xy 170.3578 -38.8874)
				(xy 168.4274 -38.8874) (xy 168.1988 -38.6588) (xy 167.534082 -38.6588) (xy 167.419274 -38.773608)
				(xy 167.419274 -39.987474) (xy 168.478708 -41.046908) (xy 168.478708 -42.569892) (xy 168.245536 -42.803064)
				(xy 168.245536 -47.375064) (xy 167.4622 -48.1584) (xy 167.4622 -50.459386) (xy 168.437814 -51.435)
				(xy 168.437814 -52.361338) (xy 168.861486 -52.78501) (xy 171.945808 -52.78501) (xy 172.119036 -52.612036)
				(xy 172.119036 -50.130964) (xy 172.3136 -49.9364) (xy 173.3804 -49.9364) (xy 173.5582 -49.7586)
				(xy 173.5582 -49.027842) (xy 173.614842 -48.9712) (xy 173.614842 -48.82261) (xy 173.945042 -48.49241)
				(xy 173.9519 -48.49241) (xy 174.1297 -48.31461) (xy 174.1297 -47.879) (xy 174.2059 -47.8028) (xy 174.7901 -47.8028)
				(xy 174.9171 -47.9298) (xy 174.9171 -48.5013) (xy 174.714916 -48.703484) (xy 174.714916 -49.033684)
				(xy 174.757842 -49.07661) (xy 175.138842 -49.07661) (xy 175.436276 -48.779176) (xy 175.436276 -47.994824)
				(xy 175.6156 -47.8155) (xy 175.9712 -47.8155) (xy 176.234852 -48.079152) (xy 176.234852 -49.669954)
				(xy 176.41443 -49.849532) (xy 177.11674 -49.849532) (xy 177.258726 -49.707546) (xy 177.258726 -49.31537)
				(xy 177.836576 -48.73752) (xy 177.836576 -47.994824) (xy 177.9778 -47.8536) (xy 178.4477 -47.8536)
				(xy 178.669442 -48.075342) (xy 178.669442 -49.00168) (xy 178.372516 -49.298606) (xy 178.372516 -49.85258)
				(xy 178.456336 -49.9364) (xy 179.088796 -49.9364) (xy 179.199032 -49.826164) (xy 179.199032 -49.288954)
				(xy 179.3113 -49.176686) (xy 179.3113 -47.9933) (xy 179.4764 -47.8282) (xy 179.9463 -47.8282) (xy 180.2003 -48.0822)
				(xy 180.2003 -49.850294) (xy 180.309774 -49.959768) (xy 180.910992 -49.959768) (xy 181.00929 -49.86147)
				(xy 181.00929 -49.08169) (xy 180.9242 -48.9966) (xy 180.9242 -48.61179) (xy 181.267608 -48.268382)
				(xy 181.267608 -47.650654) (xy 181.354222 -47.56404) (xy 182.273448 -47.56404) (xy 182.433214 -47.723806)
				(xy 182.433214 -48.413924) (xy 182.140606 -48.706532) (xy 182.140606 -49.867058) (xy 182.209948 -49.9364)
				(xy 182.83936 -49.9364) (xy 182.926482 -49.849278) (xy 182.926482 -49.153318) (xy 183.1086 -48.9712)
				(xy 183.1086 -48.7172) (xy 183.0324 -48.641) (xy 183.0324 -47.7266) (xy 183.261 -47.498) (xy 183.261 -47.1932)
				(xy 183.0324 -46.9646) (xy 183.0324 -46.101) (xy 183.261 -45.8724) (xy 183.261 -45.5676) (xy 183.0324 -45.339)
				(xy 183.0324 -44.6532) (xy 183.261 -44.4246) (xy 183.261 -43.9547) (xy 183.0578 -43.7515) (xy 183.0578 -43.015154)
				(xy 183.273954 -42.799) (xy 183.273954 -37.5666) (xy 183.0578 -37.350446) (xy 183.0578 -36.640008)
				(xy 183.280304 -36.417504) (xy 183.3118 -36.385754) (xy 183.3118 -35.318446) (xy 183.273954 -35.2806)
				(xy 182.9181 -35.2806) (xy 182.8419 -35.3568) (xy 182.8419 -35.56) (xy 182.6895 -35.7124) (xy 181.9275 -35.7124)
				(xy 181.8005 -35.8394) (xy 181.8005 -36.3093) (xy 181.6989 -36.4109) (xy 181.1147 -36.4109) (xy 180.9623 -36.2585)
				(xy 180.9623 -35.8013) (xy 180.4289 -35.2679) (xy 179.8955 -35.2679) (xy 179.6288 -35.0012) (xy 179.6288 -34.4551)
				(xy 179.5399 -34.3662) (xy 178.0032 -34.3662) (xy 177.8 -34.163) (xy 175.962818 -34.163) (xy 175.911256 -34.214562)
				(xy 170.945556 -34.214562) (xy 170.7388 -34.007806) (xy 170.7388 -33.505648) (xy 170.557952 -33.3248)
			)
		)
		(polygon
			(pts
				(xy 170.828208 -51.64201) (xy 170.625008 -51.64201) (xy 170.625008 -51.84521) (xy 170.828208 -51.84521)
			)
		)
		(polygon
			(pts
				(xy 170.472608 -51.64201) (xy 170.269408 -51.64201) (xy 170.269408 -51.84521) (xy 170.472608 -51.84521)
			)
		)
		(polygon
			(pts
				(xy 171.778168 -49.91481) (xy 171.574968 -49.91481) (xy 171.574968 -50.11801) (xy 171.778168 -50.11801)
			)
		)
		(polygon
			(pts
				(xy 169.827448 -49.91227) (xy 169.624248 -49.91227) (xy 169.624248 -50.11547) (xy 169.827448 -50.11547)
			)
		)
		(polygon
			(pts
				(xy 167.928798 -49.557432) (xy 167.725598 -49.557432) (xy 167.725598 -49.760632) (xy 167.928798 -49.760632)
			)
		)
		(polygon
			(pts
				(xy 173.248828 -49.37633) (xy 173.045628 -49.37633) (xy 173.045628 -49.57953) (xy 173.248828 -49.57953)
			)
		)
		(polygon
			(pts
				(xy 171.778168 -49.30521) (xy 171.574968 -49.30521) (xy 171.574968 -49.50841) (xy 171.778168 -49.50841)
			)
		)
		(polygon
			(pts
				(xy 169.827448 -49.30267) (xy 169.624248 -49.30267) (xy 169.624248 -49.50587) (xy 169.827448 -49.50587)
			)
		)
		(polygon
			(pts
				(xy 167.928798 -49.201832) (xy 167.725598 -49.201832) (xy 167.725598 -49.405032) (xy 167.928798 -49.405032)
			)
		)
		(polygon
			(pts
				(xy 176.594008 -49.09693) (xy 176.390808 -49.09693) (xy 176.390808 -49.30013) (xy 176.594008 -49.30013)
			)
		)
		(polygon
			(pts
				(xy 177.542952 -48.286924) (xy 177.339752 -48.286924) (xy 177.339752 -48.490124) (xy 177.542952 -48.490124)
			)
		)
		(polygon
			(pts
				(xy 179.02809 -48.279558) (xy 178.82489 -48.279558) (xy 178.82489 -48.482758) (xy 179.02809 -48.482758)
			)
		)
		(polygon
			(pts
				(xy 182.763668 -48.12919) (xy 182.560468 -48.12919) (xy 182.560468 -48.33239) (xy 182.763668 -48.33239)
			)
		)
		(polygon
			(pts
				(xy 177.542952 -47.931324) (xy 177.339752 -47.931324) (xy 177.339752 -48.134524) (xy 177.542952 -48.134524)
			)
		)
		(polygon
			(pts
				(xy 179.02809 -47.923958) (xy 178.82489 -47.923958) (xy 178.82489 -48.127158) (xy 179.02809 -48.127158)
			)
		)
		(polygon
			(pts
				(xy 173.835568 -47.915322) (xy 173.632368 -47.915322) (xy 173.632368 -48.118522) (xy 173.835568 -48.118522)
			)
		)
		(polygon
			(pts
				(xy 182.763668 -47.77359) (xy 182.560468 -47.77359) (xy 182.560468 -47.97679) (xy 182.763668 -47.97679)
			)
		)
		(polygon
			(pts
				(xy 168.810178 -47.21352) (xy 168.606978 -47.21352) (xy 168.606978 -47.41672) (xy 168.810178 -47.41672)
			)
		)
		(polygon
			(pts
				(xy 182.401718 -46.767242) (xy 182.198518 -46.767242) (xy 182.198518 -46.970442) (xy 182.401718 -46.970442)
			)
		)
		(polygon
			(pts
				(xy 181.792118 -46.767242) (xy 181.588918 -46.767242) (xy 181.588918 -46.970442) (xy 181.792118 -46.970442)
			)
		)
		(polygon
			(pts
				(xy 182.763668 -46.50613) (xy 182.560468 -46.50613) (xy 182.560468 -46.70933) (xy 182.763668 -46.70933)
			)
		)
		(polygon
			(pts
				(xy 182.763668 -46.15053) (xy 182.560468 -46.15053) (xy 182.560468 -46.35373) (xy 182.763668 -46.35373)
			)
		)
		(polygon
			(pts
				(xy 169.911522 -43.85564) (xy 169.708322 -43.85564) (xy 169.708322 -44.05884) (xy 169.911522 -44.05884)
			)
		)
		(polygon
			(pts
				(xy 169.555922 -43.85564) (xy 169.352722 -43.85564) (xy 169.352722 -44.05884) (xy 169.555922 -44.05884)
			)
		)
		(polygon
			(pts
				(xy 182.763668 -43.27271) (xy 182.560468 -43.27271) (xy 182.560468 -43.47591) (xy 182.763668 -43.47591)
			)
		)
		(polygon
			(pts
				(xy 182.763668 -42.91711) (xy 182.560468 -42.91711) (xy 182.560468 -43.12031) (xy 182.763668 -43.12031)
			)
		)
		(polygon
			(pts
				(xy 180.54574 -42.733468) (xy 180.34254 -42.733468) (xy 180.34254 -42.936668) (xy 180.54574 -42.936668)
			)
		)
		(polygon
			(pts
				(xy 180.025548 -41.964102) (xy 179.822348 -41.964102) (xy 179.822348 -42.167302) (xy 180.025548 -42.167302)
			)
		)
		(polygon
			(pts
				(xy 182.9816 -41.783) (xy 182.7784 -41.783) (xy 182.7784 -41.9862) (xy 182.9816 -41.9862)
			)
		)
		(polygon
			(pts
				(xy 182.9816 -41.4274) (xy 182.7784 -41.4274) (xy 182.7784 -41.6306) (xy 182.9816 -41.6306)
			)
		)
		(polygon
			(pts
				(xy 180.025548 -41.405302) (xy 179.822348 -41.405302) (xy 179.822348 -41.811702) (xy 180.025548 -41.811702)
			)
		)
		(polygon
			(pts
				(xy 180.025548 -41.049702) (xy 179.822348 -41.049702) (xy 179.822348 -41.252902) (xy 180.025548 -41.252902)
			)
		)
		(polygon
			(pts
				(xy 180.015134 -40.365426) (xy 179.811934 -40.365426) (xy 179.811934 -40.568626) (xy 180.015134 -40.568626)
			)
		)
		(polygon
			(pts
				(xy 182.789068 -40.13581) (xy 182.585868 -40.13581) (xy 182.585868 -40.33901) (xy 182.789068 -40.33901)
			)
		)
		(polygon
			(pts
				(xy 180.015134 -39.806626) (xy 179.811934 -39.806626) (xy 179.811934 -40.213026) (xy 180.015134 -40.213026)
			)
		)
		(polygon
			(pts
				(xy 182.789068 -39.78021) (xy 182.585868 -39.78021) (xy 182.585868 -39.98341) (xy 182.789068 -39.98341)
			)
		)
		(polygon
			(pts
				(xy 169.291 -39.497) (xy 169.0878 -39.497) (xy 169.0878 -39.7002) (xy 169.291 -39.7002)
			)
		)
		(polygon
			(pts
				(xy 180.015134 -39.451026) (xy 179.811934 -39.451026) (xy 179.811934 -39.654226) (xy 180.015134 -39.654226)
			)
		)
		(polygon
			(pts
				(xy 170.777408 -39.42461) (xy 170.574208 -39.42461) (xy 170.574208 -39.62781) (xy 170.777408 -39.62781)
			)
		)
		(polygon
			(pts
				(xy 168.1226 -39.2176) (xy 167.9194 -39.2176) (xy 167.9194 -39.4208) (xy 168.1226 -39.4208)
			)
		)
		(polygon
			(pts
				(xy 170.777408 -38.81501) (xy 170.574208 -38.81501) (xy 170.574208 -39.01821) (xy 170.777408 -39.01821)
			)
		)
		(polygon
			(pts
				(xy 180.023008 -38.74389) (xy 179.819808 -38.74389) (xy 179.819808 -38.94709) (xy 180.023008 -38.94709)
			)
		)
		(polygon
			(pts
				(xy 182.763668 -38.47465) (xy 182.560468 -38.47465) (xy 182.560468 -38.67785) (xy 182.763668 -38.67785)
			)
		)
		(polygon
			(pts
				(xy 180.023008 -38.18509) (xy 179.819808 -38.18509) (xy 179.819808 -38.59149) (xy 180.023008 -38.59149)
			)
		)
		(polygon
			(pts
				(xy 182.763668 -38.11905) (xy 182.560468 -38.11905) (xy 182.560468 -38.32225) (xy 182.763668 -38.32225)
			)
		)
		(polygon
			(pts
				(xy 180.023008 -37.82949) (xy 179.819808 -37.82949) (xy 179.819808 -38.03269) (xy 180.023008 -38.03269)
			)
		)
		(polygon
			(pts
				(xy 180.387752 -37.116258) (xy 180.184552 -37.116258) (xy 180.184552 -37.319458) (xy 180.387752 -37.319458)
			)
		)
		(polygon
			(pts
				(xy 182.763668 -36.94811) (xy 182.560468 -36.94811) (xy 182.560468 -37.15131) (xy 182.763668 -37.15131)
			)
		)
		(polygon
			(pts
				(xy 182.763668 -36.59251) (xy 182.560468 -36.59251) (xy 182.560468 -36.79571) (xy 182.763668 -36.79571)
			)
		)
		(polygon
			(pts
				(xy 180.387752 -36.506658) (xy 180.184552 -36.506658) (xy 180.184552 -36.709858) (xy 180.387752 -36.709858)
			)
		)
		(polygon
			(pts
				(xy 170.768772 -36.22675) (xy 170.565572 -36.22675) (xy 170.565572 -36.42995) (xy 170.768772 -36.42995)
			)
		)
		(polygon
			(pts
				(xy 170.768772 -35.61715) (xy 170.565572 -35.61715) (xy 170.565572 -35.82035) (xy 170.768772 -35.82035)
			)
		)
		(polygon
			(pts
				(xy 177.169572 -35.053016) (xy 176.966372 -35.053016) (xy 176.966372 -35.256216) (xy 177.169572 -35.256216)
			)
		)
		(polygon
			(pts
				(xy 176.604168 -35.052762) (xy 176.400968 -35.052762) (xy 176.400968 -35.255962) (xy 176.604168 -35.255962)
				(xy 176.610772 -35.256216) (xy 176.813972 -35.256216) (xy 176.813972 -35.053016) (xy 176.610772 -35.053016)
			)
		)
		(polygon
			(pts
				(xy 176.248568 -35.052762) (xy 176.045368 -35.052762) (xy 176.045368 -35.255962) (xy 176.248568 -35.255962)
			)
		)
		(polygon
			(pts
				(xy 174.649892 -34.978848) (xy 174.446692 -34.978848) (xy 174.446692 -35.182048) (xy 174.649892 -35.182048)
			)
		)
		(polygon
			(pts
				(xy 173.938692 -34.97707) (xy 173.735492 -34.97707) (xy 173.735492 -35.18027) (xy 173.938692 -35.18027)
			)
		)
		(polygon
			(pts
				(xy 173.583092 -34.97707) (xy 173.379892 -34.97707) (xy 173.379892 -35.18027) (xy 173.583092 -35.18027)
			)
		)
		(polygon
			(pts
				(xy 175.5648 -34.9758) (xy 175.3616 -34.9758) (xy 175.3616 -35.179) (xy 175.5648 -35.179)
			)
		)
		(polygon
			(pts
				(xy 175.2092 -34.9758) (xy 175.006 -34.9758) (xy 175.005492 -34.978848) (xy 174.802292 -34.978848)
				(xy 174.802292 -35.182048) (xy 175.005492 -35.182048) (xy 175.006 -35.179) (xy 175.2092 -35.179)
			)
		)
		(polygon
			(pts
				(xy 179.158138 -34.774124) (xy 178.954938 -34.774124) (xy 178.954938 -34.977324) (xy 179.158138 -34.977324)
			)
		)
		(polygon
			(pts
				(xy 170.783758 -34.573972) (xy 170.580558 -34.573972) (xy 170.580558 -34.777172) (xy 170.783758 -34.777172)
			)
		)
		(polygon
			(pts
				(xy 174.684944 -34.504884) (xy 174.481744 -34.504884) (xy 174.481744 -34.708084) (xy 174.684944 -34.708084)
			)
		)
		(polygon
			(pts
				(xy 174.329344 -34.504884) (xy 174.126144 -34.504884) (xy 174.126144 -34.708084) (xy 174.329344 -34.708084)
			)
		)
		(polygon
			(pts
				(xy 173.169834 -34.501328) (xy 172.966634 -34.501328) (xy 172.966634 -34.704528) (xy 173.169834 -34.704528)
			)
		)
		(polygon
			(pts
				(xy 172.814234 -34.501328) (xy 172.611034 -34.501328) (xy 172.611034 -34.704528) (xy 172.814234 -34.704528)
			)
		)
		(polygon
			(pts
				(xy 171.446698 -34.489644) (xy 171.243498 -34.489644) (xy 171.243498 -34.692844) (xy 171.446698 -34.692844)
			)
		)
		(polygon
			(pts
				(xy 171.091098 -34.489644) (xy 170.887898 -34.489644) (xy 170.887898 -34.692844) (xy 171.091098 -34.692844)
			)
		)
	)
	(zone
		(net "GND")
		(layer "B.Cu")
		(hatch none 0.5)
		(connect_pads
			(clearance 0.5)
		)
		(min_thickness 0.25)
		(fill yes
			(thermal_gap 0.5)
			(thermal_bridge_width 0.5)
			(island_removal_mode 0)
		)
		(polygon
			(pts
				(xy 158.115 -59.182) (xy 157.8991 -59.3979) (xy 157.8991 -64.4271) (xy 158.115 -64.643) (xy 162.687 -64.643)
				(xy 163.0426 -64.2874) (xy 163.0426 -59.3217) (xy 162.9029 -59.182)
			)
		)
		(polygon
			(pts
				(xy 159.112204 -63.589408) (xy 158.909004 -63.589408) (xy 158.909004 -63.792608) (xy 159.112204 -63.792608)
			)
		)
		(polygon
			(pts
				(xy 158.248604 -63.589408) (xy 158.045404 -63.589408) (xy 158.045404 -63.792608) (xy 158.248604 -63.792608)
			)
		)
		(polygon
			(pts
				(xy 162.8902 -63.4746) (xy 162.687 -63.4746) (xy 162.687 -63.6778) (xy 162.8902 -63.6778)
			)
		)
		(polygon
			(pts
				(xy 162.0266 -63.4746) (xy 161.8234 -63.4746) (xy 161.8234 -63.6778) (xy 162.0266 -63.6778)
			)
		)
		(polygon
			(pts
				(xy 158.604204 -60.871608) (xy 158.401004 -60.871608) (xy 158.401004 -61.074808) (xy 158.604204 -61.074808)
			)
		)
		(polygon
			(pts
				(xy 162.5092 -60.7568) (xy 162.306 -60.7568) (xy 162.306 -60.96) (xy 162.5092 -60.96)
			)
		)
		(polygon
			(pts
				(xy 158.604204 -59.881008) (xy 158.401004 -59.881008) (xy 158.401004 -60.363608) (xy 158.604204 -60.363608)
			)
		)
		(polygon
			(pts
				(xy 162.5346 -59.8678) (xy 162.3314 -59.8678) (xy 162.3314 -60.071) (xy 162.306 -60.1472) (xy 162.306 -60.3504)
				(xy 162.5092 -60.3504) (xy 162.5092 -60.1472) (xy 162.5346 -60.071)
			)
		)
	)
	(zone
		(layer "B.Cu")
		(hatch none 0.5)
		(connect_pads
			(clearance 0)
		)
		(min_thickness 0.25)
		(keepout
			(tracks not_allowed)
			(vias allowed)
			(pads allowed)
			(copperpour not_allowed)
			(footprints allowed)
		)
		(placement
			(enabled no)
			(sheetname "")
		)
		(fill
			(thermal_gap 0.5)
			(thermal_bridge_width 0.5)
			(island_removal_mode 0)
		)
		(polygon
			(pts
				(arc
					(start 154.500072 -29.500068)
					(mid 151.500078 -26.500074)
					(end 148.500084 -29.500068)
				)
				(arc
					(start 148.500084 -29.500068)
					(mid 151.500078 -32.500062)
					(end 154.500072 -29.500068)
				)
			)
		)
	)
	(zone
		(layer "B.Cu")
		(hatch none 0.5)
		(connect_pads
			(clearance 0)
		)
		(min_thickness 0.25)
		(keepout
			(tracks not_allowed)
			(vias allowed)
			(pads allowed)
			(copperpour not_allowed)
			(footprints allowed)
		)
		(placement
			(enabled no)
			(sheetname "")
		)
		(fill
			(thermal_gap 0.5)
			(thermal_bridge_width 0.5)
			(island_removal_mode 0)
		)
		(polygon
			(pts
				(arc
					(start 187.761118 -10.999978)
					(mid 187.199778 -10.438638)
					(end 186.638438 -10.999978)
				)
				(xy 186.638438 -11.464036) (xy 186.689238 -11.459464) (xy 186.69 -11.458448) (xy 186.712606 -11.458448)
				(xy 186.72556 -11.458448) (xy 186.730132 -11.458448) (xy 187.019184 -11.458448)
				(arc
					(start 187.023756 -11.458448)
					(mid 187.081785 -11.437295)
					(end 187.112656 -11.383772)
				)
				(arc
					(start 187.112656 -11.383772)
					(mid 187.201079 -10.606365)
					(end 187.285376 -11.38428)
				)
				(xy 187.285376 -11.403838)
				(arc
					(start 187.282836 -11.406378)
					(mid 187.208924 -11.553446)
					(end 187.061856 -11.627358)
				)
				(xy 187.059316 -11.630152) (xy 187.031884 -11.630152) (xy 187.023756 -11.630152) (xy 187.019184 -11.630152)
				(xy 186.730132 -11.630152)
				(arc
					(start 186.72556 -11.630152)
					(mid 186.681831 -11.63204)
					(end 186.638438 -11.637772)
				)
				(arc
					(start 186.638438 -11.78052)
					(mid 186.663171 -11.775187)
					(end 186.688222 -11.77163)
				)
				(xy 186.69 -11.769852) (xy 186.716162 -11.769852) (xy 186.72556 -11.769598) (xy 186.730132 -11.769852)
				(xy 187.01893 -11.769852) (xy 187.023502 -11.769598) (xy 187.03163 -11.769852) (xy 187.059062 -11.769852)
				(arc
					(start 187.061602 -11.772392)
					(mid 187.208847 -11.846381)
					(end 187.282836 -11.993626)
				)
				(xy 187.285376 -11.996166)
				(arc
					(start 187.285376 -12.015724)
					(mid 187.201079 -12.793689)
					(end 187.112656 -12.016232)
				)
				(arc
					(start 187.112656 -12.016232)
					(mid 187.081753 -11.962478)
					(end 187.023502 -11.941302)
				)
				(xy 187.01893 -11.941048) (xy 186.730132 -11.941048)
				(arc
					(start 186.72556 -11.941302)
					(mid 186.680651 -11.946846)
					(end 186.638438 -11.963146)
				)
				(arc
					(start 186.638438 -12.399772)
					(mid 187.199651 -12.961366)
					(end 187.761118 -12.400026)
				)
			)
		)
	)
	(zone
		(layer "B.Cu")
		(hatch none 0.5)
		(connect_pads
			(clearance 0)
		)
		(min_thickness 0.25)
		(keepout
			(tracks not_allowed)
			(vias allowed)
			(pads allowed)
			(copperpour not_allowed)
			(footprints allowed)
		)
		(placement
			(enabled no)
			(sheetname "")
		)
		(fill
			(thermal_gap 0.5)
			(thermal_bridge_width 0.5)
			(island_removal_mode 0)
		)
		(polygon
			(pts
				(arc
					(start 104.358186 -55.000144)
					(mid 104.040562 -54.644303)
					(end 103.65105 -54.919626)
				)
				(arc
					(start 103.65105 -55.237634)
					(mid 103.659426 -55.279834)
					(end 103.683308 -55.315612)
				)
				(arc
					(start 103.683308 -55.315612)
					(mid 103.719099 -55.339464)
					(end 103.761286 -55.34787)
				)
				(arc
					(start 103.911146 -55.34787)
					(mid 103.933597 -55.338571)
					(end 103.942896 -55.31612)
				)
				(arc
					(start 103.942896 -55.234586)
					(mid 104.000046 -54.758837)
					(end 104.057196 -55.234586)
				)
				(xy 104.057196 -55.339742)
				(arc
					(start 104.05491 -55.342028)
					(mid 104.01444 -55.419414)
					(end 103.937054 -55.459884)
				)
				(xy 103.934768 -55.46217) (xy 103.737664 -55.46217)
				(arc
					(start 103.73614 -55.460646)
					(mid 103.687188 -55.449546)
					(end 103.641906 -55.42788)
				)
				(arc
					(start 103.641906 -55.513732)
					(mid 103.700088 -55.532094)
					(end 103.760778 -55.53837)
				)
				(xy 103.934768 -55.53837)
				(arc
					(start 103.937054 -55.540656)
					(mid 104.01444 -55.581126)
					(end 104.05491 -55.658512)
				)
				(xy 104.057196 -55.660798)
				(arc
					(start 104.057196 -55.7657)
					(mid 104.000046 -56.241449)
					(end 103.942896 -55.7657)
				)
				(arc
					(start 103.942896 -55.68442)
					(mid 103.933597 -55.661969)
					(end 103.911146 -55.65267)
				)
				(xy 103.737664 -55.65267)
				(arc
					(start 103.736902 -55.651908)
					(mid 103.688914 -55.646299)
					(end 103.641906 -55.635144)
				)
				(arc
					(start 103.641906 -55.999888)
					(mid 103.999919 -56.358282)
					(end 104.358186 -56.000142)
				)
			)
		)
	)
	(zone
		(net "P3V3")
		(layer "B.Cu")
		(hatch none 0.5)
		(connect_pads
			(clearance 0.5)
		)
		(min_thickness 0.25)
		(fill yes
			(thermal_gap 0.5)
			(thermal_bridge_width 0.5)
			(island_removal_mode 0)
		)
		(polygon
			(pts
				(xy 169.8498 -116.6876) (xy 169.1894 -117.348) (xy 169.1894 -121.6914) (xy 169.7736 -122.2756) (xy 174.1297 -122.2756)
				(xy 174.1678 -122.2375) (xy 174.1678 -116.8908) (xy 173.9646 -116.6876)
			)
		)
		(polygon
			(pts
				(xy 173.662848 -121.569734) (xy 173.459648 -121.569734) (xy 173.459648 -121.772934) (xy 173.662848 -121.772934)
			)
		)
	)
	(zone
		(layer "B.Cu")
		(hatch none 0.5)
		(connect_pads
			(clearance 0)
		)
		(min_thickness 0.25)
		(keepout
			(tracks not_allowed)
			(vias allowed)
			(pads allowed)
			(copperpour not_allowed)
			(footprints allowed)
		)
		(placement
			(enabled no)
			(sheetname "")
		)
		(fill
			(thermal_gap 0.5)
			(thermal_bridge_width 0.5)
			(island_removal_mode 0)
		)
		(polygon
			(pts
				(arc
					(start 102.761542 -2.600198)
					(mid 102.200202 -2.038858)
					(end 101.638862 -2.600198)
				)
				(arc
					(start 101.638862 -3.028442)
					(mid 101.671814 -3.024751)
					(end 101.704902 -3.0226)
				)
				(xy 101.705664 -3.021838)
				(arc
					(start 102.081076 -3.021838)
					(mid 102.097989 -3.018474)
					(end 102.112318 -3.008884)
				)
				(arc
					(start 102.112318 -3.008884)
					(mid 102.119915 -2.99858)
					(end 102.124256 -2.986532)
				)
				(arc
					(start 102.124256 -2.986532)
					(mid 102.201228 -2.206422)
					(end 102.275132 -2.986786)
				)
				(xy 102.275132 -3.00863)
				(arc
					(start 102.272084 -3.011678)
					(mid 102.253153 -3.067209)
					(end 102.21849 -3.114548)
				)
				(arc
					(start 102.21849 -3.114548)
					(mid 102.170974 -3.149578)
					(end 102.115112 -3.16865)
				)
				(xy 102.112064 -3.171698)
				(arc
					(start 101.736652 -3.171698)
					(mid 101.687568 -3.17388)
					(end 101.638862 -3.180334)
				)
				(arc
					(start 101.638862 -3.44424)
					(mid 101.670987 -3.435359)
					(end 101.703886 -3.430016)
				)
				(xy 101.705664 -3.428238) (xy 102.112064 -3.428238)
				(arc
					(start 102.115112 -3.431286)
					(mid 102.170961 -3.450383)
					(end 102.21849 -3.485388)
				)
				(arc
					(start 102.21849 -3.485388)
					(mid 102.253178 -3.532714)
					(end 102.272084 -3.588258)
				)
				(xy 102.275132 -3.591306)
				(arc
					(start 102.275132 -3.613404)
					(mid 102.201104 -4.393726)
					(end 102.12451 -3.613658)
				)
				(arc
					(start 102.12451 -3.613658)
					(mid 102.120112 -3.601436)
					(end 102.112318 -3.591052)
				)
				(arc
					(start 102.112318 -3.591052)
					(mid 102.097984 -3.581474)
					(end 102.081076 -3.578098)
				)
				(arc
					(start 101.736652 -3.578098)
					(mid 101.684919 -3.586778)
					(end 101.638862 -3.61188)
				)
				(arc
					(start 101.638862 -3.999738)
					(mid 102.200075 -4.561332)
					(end 102.761542 -3.999992)
				)
			)
		)
	)
	(zone
		(net "GND")
		(layer "B.Cu")
		(hatch none 0.5)
		(connect_pads
			(clearance 0.5)
		)
		(min_thickness 0.25)
		(fill yes
			(thermal_gap 0.5)
			(thermal_bridge_width 0.5)
			(island_removal_mode 0)
		)
		(polygon
			(pts
				(xy 108.708698 -58.534554) (xy 108.55706 -58.686192) (xy 108.55706 -59.306714) (xy 108.660438 -59.410092)
				(xy 122.594878 -59.410092) (xy 122.747278 -59.257692) (xy 122.747278 -58.690002) (xy 122.59183 -58.534554)
			)
		)
		(polygon
			(pts
				(xy 122.453908 -58.871612) (xy 122.250708 -58.871612) (xy 122.250708 -59.074812) (xy 122.453908 -59.074812)
			)
		)
		(polygon
			(pts
				(xy 121.666 -58.8645) (xy 121.4628 -58.8645) (xy 121.4628 -59.0677) (xy 121.666 -59.0677)
			)
		)
		(polygon
			(pts
				(xy 121.3104 -58.8645) (xy 120.8278 -58.8645) (xy 120.8278 -59.0677) (xy 121.3104 -59.0677)
			)
		)
		(polygon
			(pts
				(xy 120.6754 -58.8645) (xy 120.4722 -58.8645) (xy 120.4722 -59.0677) (xy 120.6754 -59.0677)
			)
		)
		(polygon
			(pts
				(xy 119.6848 -58.8645) (xy 119.4816 -58.8645) (xy 119.4816 -59.0677) (xy 119.6848 -59.0677)
			)
		)
		(polygon
			(pts
				(xy 119.3292 -58.8645) (xy 118.8466 -58.8645) (xy 118.8466 -59.0677) (xy 119.3292 -59.0677)
			)
		)
		(polygon
			(pts
				(xy 118.6942 -58.8645) (xy 118.491 -58.8645) (xy 118.491 -59.0677) (xy 118.6942 -59.0677)
			)
		)
		(polygon
			(pts
				(xy 117.6782 -58.8645) (xy 117.475 -58.8645) (xy 117.475 -59.0677) (xy 117.6782 -59.0677)
			)
		)
		(polygon
			(pts
				(xy 117.3226 -58.8645) (xy 116.84 -58.8645) (xy 116.84 -59.0677) (xy 117.3226 -59.0677)
			)
		)
		(polygon
			(pts
				(xy 116.6876 -58.8645) (xy 116.4844 -58.8645) (xy 116.4844 -59.0677) (xy 116.6876 -59.0677)
			)
		)
		(polygon
			(pts
				(xy 115.68176 -58.8645) (xy 115.47856 -58.8645) (xy 115.47856 -59.0677) (xy 115.68176 -59.0677)
			)
		)
		(polygon
			(pts
				(xy 115.32616 -58.8645) (xy 114.84356 -58.8645) (xy 114.84356 -59.0677) (xy 115.32616 -59.0677)
			)
		)
		(polygon
			(pts
				(xy 114.69116 -58.8645) (xy 114.48796 -58.8645) (xy 114.48796 -59.0677) (xy 114.69116 -59.0677)
			)
		)
		(polygon
			(pts
				(xy 113.665 -58.8645) (xy 113.4618 -58.8645) (xy 113.4618 -59.0677) (xy 113.665 -59.0677)
			)
		)
		(polygon
			(pts
				(xy 113.3094 -58.8645) (xy 112.8268 -58.8645) (xy 112.8268 -59.0677) (xy 113.3094 -59.0677)
			)
		)
		(polygon
			(pts
				(xy 112.6744 -58.8645) (xy 112.4712 -58.8645) (xy 112.4712 -59.0677) (xy 112.6744 -59.0677)
			)
		)
		(polygon
			(pts
				(xy 111.6584 -58.8645) (xy 111.4552 -58.8645) (xy 111.4552 -59.0677) (xy 111.6584 -59.0677)
			)
		)
		(polygon
			(pts
				(xy 111.3028 -58.8645) (xy 110.8202 -58.8645) (xy 110.8202 -59.0677) (xy 111.3028 -59.0677)
			)
		)
		(polygon
			(pts
				(xy 110.6678 -58.8645) (xy 110.4646 -58.8645) (xy 110.4646 -59.0677) (xy 110.6678 -59.0677)
			)
		)
		(polygon
			(pts
				(xy 109.7661 -58.8645) (xy 109.5629 -58.8645) (xy 109.5629 -59.0677) (xy 109.7661 -59.0677)
			)
		)
		(polygon
			(pts
				(xy 109.4105 -58.8645) (xy 108.9279 -58.8645) (xy 108.9279 -59.0677) (xy 109.4105 -59.0677)
			)
		)
	)
	(zone
		(layer "B.Cu")
		(hatch none 0.5)
		(connect_pads
			(clearance 0)
		)
		(min_thickness 0.25)
		(keepout
			(tracks not_allowed)
			(vias allowed)
			(pads allowed)
			(copperpour not_allowed)
			(footprints allowed)
		)
		(placement
			(enabled no)
			(sheetname "")
		)
		(fill
			(thermal_gap 0.5)
			(thermal_bridge_width 0.5)
			(island_removal_mode 0)
		)
		(polygon
			(pts
				(arc
					(start 137.999978 -94.309946)
					(mid 134.999984 -91.309952)
					(end 131.99999 -94.309946)
				)
				(arc
					(start 131.99999 -94.309946)
					(mid 134.999984 -97.30994)
					(end 137.999978 -94.309946)
				)
			)
		)
	)
	(zone
		(net "SHELL_PLL_VDD")
		(layer "B.Cu")
		(hatch none 0.5)
		(connect_pads
			(clearance 0.5)
		)
		(min_thickness 0.25)
		(fill yes
			(thermal_gap 0.5)
			(thermal_bridge_width 0.5)
			(island_removal_mode 0)
		)
		(polygon
			(pts
				(xy 156.482288 -58.5978) (xy 156.337 -58.743088) (xy 156.337 -66.548) (xy 156.5021 -66.7131) (xy 159.2199 -66.7131)
				(xy 159.385 -66.548) (xy 159.385 -65.151) (xy 159.258 -65.024) (xy 157.861 -65.024) (xy 157.5816 -64.7446)
				(xy 157.5816 -58.731404) (xy 157.447996 -58.5978)
			)
		)
		(polygon
			(pts
				(xy 157.359604 -66.053208) (xy 157.156404 -66.053208) (xy 157.156404 -66.256408) (xy 157.359604 -66.256408)
			)
		)
		(polygon
			(pts
				(xy 156.800804 -66.053208) (xy 156.597604 -66.053208) (xy 156.597604 -66.256408) (xy 156.800804 -66.256408)
			)
		)
		(polygon
			(pts
				(xy 156.826204 -64.453008) (xy 156.623004 -64.453008) (xy 156.623004 -64.656208) (xy 156.826204 -64.656208)
			)
		)
		(polygon
			(pts
				(xy 156.826204 -63.589408) (xy 156.623004 -63.589408) (xy 156.623004 -63.792608) (xy 156.826204 -63.792608)
			)
		)
		(polygon
			(pts
				(xy 157.080204 -60.871608) (xy 156.877004 -60.871608) (xy 156.877004 -61.074808) (xy 157.080204 -61.074808)
			)
		)
		(polygon
			(pts
				(xy 157.080204 -59.881008) (xy 156.877004 -59.881008) (xy 156.877004 -60.363608) (xy 157.080204 -60.363608)
			)
		)
		(polygon
			(pts
				(xy 157.080204 -59.271408) (xy 156.877004 -59.271408) (xy 156.877004 -59.474608) (xy 157.080204 -59.474608)
			)
		)
	)
	(zone
		(net "GND")
		(layer "B.Cu")
		(hatch none 0.5)
		(connect_pads
			(clearance 0.5)
		)
		(min_thickness 0.25)
		(fill yes
			(thermal_gap 0.5)
			(thermal_bridge_width 0.5)
			(island_removal_mode 0)
		)
		(polygon
			(pts
				(xy 128.032002 -111.543592) (xy 127.8382 -111.737394) (xy 127.8382 -121.0056) (xy 128.2446 -121.412)
				(xy 131.318 -121.412) (xy 131.5212 -121.2088) (xy 131.5212 -112.179862) (xy 130.88493 -111.543592)
			)
		)
		(polygon
			(pts
				(xy 131.0767 -121.0818) (xy 130.8735 -121.0818) (xy 130.8735 -121.285) (xy 131.0767 -121.285)
			)
		)
		(polygon
			(pts
				(xy 131.0767 -120.523) (xy 130.8735 -120.523) (xy 130.8735 -120.7262) (xy 131.0767 -120.7262)
			)
		)
		(polygon
			(pts
				(xy 131.0132 -116.2304) (xy 130.81 -116.2304) (xy 130.81 -116.4336) (xy 131.0132 -116.4336)
			)
		)
		(polygon
			(pts
				(xy 131.0132 -115.6208) (xy 130.81 -115.6208) (xy 130.81 -115.824) (xy 131.0132 -115.824)
			)
		)
	)
	(zone
		(net "SAS0_AVDD")
		(layer "B.Cu")
		(hatch none 0.5)
		(connect_pads
			(clearance 0.5)
		)
		(min_thickness 0.25)
		(fill yes
			(thermal_gap 0.5)
			(thermal_bridge_width 0.5)
			(island_removal_mode 0)
		)
		(polygon
			(pts
				(xy 168.49344 -33.3248) (xy 168.33342 -33.48482) (xy 168.33342 -33.95218) (xy 168.11625 -34.16935)
				(xy 166.97325 -34.16935) (xy 166.751 -34.3916) (xy 166.751 -37.9476) (xy 166.8018 -37.9984) (xy 167.132 -37.9984)
				(xy 167.386 -38.2524) (xy 167.386 -38.4556) (xy 167.4622 -38.5318) (xy 168.3004 -38.5318) (xy 168.4528 -38.6842)
				(xy 169.7482 -38.6842) (xy 169.8244 -38.608) (xy 169.8244 -38.068758) (xy 169.696384 -37.940742)
				(xy 169.696384 -36.409376) (xy 169.8244 -36.28136) (xy 169.8244 -33.7058) (xy 169.4434 -33.3248)
			)
		)
		(polygon
			(pts
				(xy 169.291 -37.973) (xy 169.0878 -37.973) (xy 169.0878 -38.1762) (xy 169.291 -38.1762)
			)
		)
		(polygon
			(pts
				(xy 168.1226 -37.6936) (xy 167.9194 -37.6936) (xy 167.9194 -37.8968) (xy 168.1226 -37.8968)
			)
		)
		(polygon
			(pts
				(xy 167.513 -37.6936) (xy 167.3098 -37.6936) (xy 167.3098 -37.8968) (xy 167.513 -37.8968)
			)
		)
		(polygon
			(pts
				(xy 169.259758 -33.964372) (xy 169.056558 -33.964372) (xy 169.056558 -34.167572) (xy 169.259758 -34.167572)
			)
		)
	)
	(zone
		(net "P1V8_E")
		(layer "B.Cu")
		(hatch none 0.5)
		(connect_pads
			(clearance 0.5)
		)
		(min_thickness 0.25)
		(fill yes
			(thermal_gap 0.5)
			(thermal_bridge_width 0.5)
			(island_removal_mode 0)
		)
		(polygon
			(pts
				(xy 115.57 -87.1474) (xy 115.5446 -87.1728) (xy 115.5446 -88.4174) (xy 115.972844 -88.845644) (xy 115.972844 -91.353386)
				(xy 116.186458 -91.567) (xy 117.729 -91.567) (xy 118.11 -91.186) (xy 118.11 -90.5256) (xy 118.3386 -90.297)
				(xy 119.0498 -90.297) (xy 119.1514 -90.1954) (xy 119.1514 -89.789) (xy 119.0498 -89.6874) (xy 118.491 -89.6874)
				(xy 117.9068 -89.1032) (xy 117.9068 -89.10066) (xy 116.81714 -88.011) (xy 116.4082 -88.011) (xy 116.205 -87.8078)
				(xy 116.205 -87.1982) (xy 116.1542 -87.1474)
			)
		)
		(polygon
			(pts
				(xy 116.647214 -90.69197) (xy 116.444014 -90.69197) (xy 116.444014 -90.89517) (xy 116.647214 -90.89517)
			)
		)
		(polygon
			(pts
				(xy 116.647214 -90.13317) (xy 116.444014 -90.13317) (xy 116.444014 -90.33637) (xy 116.647214 -90.33637)
			)
		)
	)
	(zone
		(layer "B.Cu")
		(hatch none 0.5)
		(connect_pads
			(clearance 0)
		)
		(min_thickness 0.25)
		(keepout
			(tracks not_allowed)
			(vias allowed)
			(pads allowed)
			(copperpour not_allowed)
			(footprints allowed)
		)
		(placement
			(enabled no)
			(sheetname "")
		)
		(fill
			(thermal_gap 0.5)
			(thermal_bridge_width 0.5)
			(island_removal_mode 0)
		)
		(polygon
			(pts
				(arc
					(start 167.954452 -30.076902)
					(mid 167.608735 -30.096971)
					(end 167.441626 -30.400244)
				)
				(arc
					(start 167.44188 -31.199582)
					(mid 167.80002 -31.557976)
					(end 168.15816 -31.199582)
				)
				(xy 168.15816 -31.03245) (xy 168.15816 -30.911546) (xy 168.157906 -30.732222)
				(arc
					(start 167.973756 -31.03245)
					(mid 167.673703 -31.405375)
					(end 167.870886 -30.969204)
				)
				(xy 168.139618 -30.531562) (xy 168.139618 -30.443424) (xy 168.139364 -30.44317) (xy 168.139364 -30.418278)
				(xy 168.139364 -30.39999) (xy 168.139364 -30.393386)
				(arc
					(start 168.139364 -30.286706)
					(mid 168.112514 -30.225782)
					(end 168.074848 -30.170882)
				)
				(xy 168.074848 -30.209744) (xy 168.016936 -30.26791) (xy 168.016936 -30.268672)
				(arc
					(start 168.007792 -30.277562)
					(mid 167.629086 -30.57067)
					(end 167.922194 -30.191964)
				)
				(xy 167.927528 -30.18663) (xy 167.954452 -30.15996)
			)
		)
	)
	(zone
		(layer "B.Cu")
		(hatch none 0.5)
		(connect_pads
			(clearance 0)
		)
		(min_thickness 0.25)
		(keepout
			(tracks allowed)
			(vias allowed)
			(pads allowed)
			(copperpour allowed)
			(footprints allowed)
		)
		(placement
			(enabled no)
			(sheetname "")
		)
		(fill
			(thermal_gap 0.5)
			(thermal_bridge_width 0.5)
			(island_removal_mode 0)
		)
		(polygon
			(pts
				(xy 201.245978 -73.785984) (xy 201.245978 -67.000374) (xy 200.41362 -67.000374) (xy 200.41362 -62.46622)
				(xy 201.245978 -62.46622) (xy 201.245978 -61.341) (xy 203.962 -61.341) (xy 203.962 -59.817) (xy 204.597 -59.817)
				(xy 204.597 -62.357) (xy 203.962 -62.357) (xy 203.962 -73.785984)
			)
		)
	)
	(zone
		(layer "B.Cu")
		(hatch none 0.5)
		(connect_pads
			(clearance 0)
		)
		(min_thickness 0.25)
		(keepout
			(tracks allowed)
			(vias allowed)
			(pads allowed)
			(copperpour allowed)
			(footprints not_allowed)
		)
		(placement
			(enabled no)
			(sheetname "")
		)
		(fill
			(thermal_gap 0.5)
			(thermal_bridge_width 0.5)
			(island_removal_mode 0)
		)
		(polygon
			(pts
				(arc
					(start 137.999978 -94.309946)
					(mid 134.999984 -91.309952)
					(end 131.99999 -94.309946)
				)
				(arc
					(start 131.99999 -94.309946)
					(mid 134.999984 -97.30994)
					(end 137.999978 -94.309946)
				)
			)
		)
	)
	(zone
		(layer "B.Cu")
		(hatch none 0.5)
		(connect_pads
			(clearance 0)
		)
		(min_thickness 0.25)
		(keepout
			(tracks not_allowed)
			(vias allowed)
			(pads allowed)
			(copperpour not_allowed)
			(footprints allowed)
		)
		(placement
			(enabled no)
			(sheetname "")
		)
		(fill
			(thermal_gap 0.5)
			(thermal_bridge_width 0.5)
			(island_removal_mode 0)
		)
		(polygon
			(pts
				(arc
					(start 106.358182 -55.000144)
					(mid 106.040558 -54.644303)
					(end 105.651046 -54.919626)
				)
				(arc
					(start 105.651046 -55.237634)
					(mid 105.659422 -55.279834)
					(end 105.683304 -55.315612)
				)
				(arc
					(start 105.683304 -55.315612)
					(mid 105.719095 -55.339464)
					(end 105.761282 -55.34787)
				)
				(arc
					(start 105.911142 -55.34787)
					(mid 105.933593 -55.338571)
					(end 105.942892 -55.31612)
				)
				(arc
					(start 105.942892 -55.234586)
					(mid 106.000042 -54.758837)
					(end 106.057192 -55.234586)
				)
				(xy 106.057192 -55.339742)
				(arc
					(start 106.054906 -55.342028)
					(mid 106.014436 -55.419414)
					(end 105.93705 -55.459884)
				)
				(xy 105.934764 -55.46217) (xy 105.73766 -55.46217)
				(arc
					(start 105.736136 -55.460646)
					(mid 105.687184 -55.449546)
					(end 105.641902 -55.42788)
				)
				(arc
					(start 105.641902 -55.513732)
					(mid 105.700084 -55.532094)
					(end 105.760774 -55.53837)
				)
				(xy 105.934764 -55.53837)
				(arc
					(start 105.93705 -55.540656)
					(mid 106.014436 -55.581126)
					(end 106.054906 -55.658512)
				)
				(xy 106.057192 -55.660798)
				(arc
					(start 106.057192 -55.7657)
					(mid 106.000042 -56.241449)
					(end 105.942892 -55.7657)
				)
				(arc
					(start 105.942892 -55.68442)
					(mid 105.933593 -55.661969)
					(end 105.911142 -55.65267)
				)
				(xy 105.73766 -55.65267)
				(arc
					(start 105.736898 -55.651908)
					(mid 105.68891 -55.646299)
					(end 105.641902 -55.635144)
				)
				(arc
					(start 105.641902 -55.999888)
					(mid 105.999915 -56.358282)
					(end 106.358182 -56.000142)
				)
			)
		)
	)
	(zone
		(net "HM40ADC_VDDA")
		(layer "B.Cu")
		(hatch none 0.5)
		(connect_pads
			(clearance 0.5)
		)
		(min_thickness 0.25)
		(fill yes
			(thermal_gap 0.5)
			(thermal_bridge_width 0.5)
			(island_removal_mode 0)
		)
		(polygon
			(pts
				(xy 165.354 -59.182) (xy 165.1 -59.436) (xy 165.1 -66.4845) (xy 165.2397 -66.6242) (xy 167.6908 -66.6242)
				(xy 167.894 -66.421) (xy 167.894 -65.024) (xy 167.64 -64.77) (xy 166.878 -64.77) (xy 166.497 -64.389)
				(xy 166.497 -59.309) (xy 166.37 -59.182)
			)
		)
		(polygon
			(pts
				(xy 165.989 -65.9638) (xy 165.7858 -65.9638) (xy 165.7858 -66.167) (xy 165.989 -66.167)
			)
		)
		(polygon
			(pts
				(xy 165.4302 -65.9638) (xy 165.227 -65.9638) (xy 165.227 -66.167) (xy 165.4302 -66.167)
			)
		)
		(polygon
			(pts
				(xy 165.7096 -64.3382) (xy 165.5064 -64.3382) (xy 165.5064 -64.5414) (xy 165.7096 -64.5414)
			)
		)
		(polygon
			(pts
				(xy 165.7096 -63.4746) (xy 165.5064 -63.4746) (xy 165.5064 -63.6778) (xy 165.7096 -63.6778)
			)
		)
		(polygon
			(pts
				(xy 166.0144 -60.7568) (xy 165.8112 -60.7568) (xy 165.8112 -60.96) (xy 166.0144 -60.96)
			)
		)
		(polygon
			(pts
				(xy 165.9636 -59.8678) (xy 165.7604 -59.8678) (xy 165.7604 -60.071) (xy 165.8112 -60.1472) (xy 165.8112 -60.3504)
				(xy 166.0144 -60.3504) (xy 166.0144 -60.1472) (xy 165.9636 -60.071)
			)
		)
	)
	(zone
		(net "GND")
		(layer "B.Cu")
		(hatch none 0.5)
		(connect_pads
			(clearance 0.5)
		)
		(min_thickness 0.25)
		(fill yes
			(thermal_gap 0.5)
			(thermal_bridge_width 0.5)
			(island_removal_mode 0)
		)
		(polygon
			(pts
				(xy 91.85529 -74.934318) (xy 91.65336 -75.136248) (xy 91.65336 -77.96403) (xy 91.851988 -78.162658)
				(xy 93.6371 -78.162658) (xy 94.38132 -77.418438) (xy 95.90405 -77.418438) (xy 96.2406 -77.081888)
				(xy 96.2406 -75.2729) (xy 95.902018 -74.934318)
			)
		)
		(polygon
			(pts
				(xy 93.720158 -77.460348) (xy 93.516958 -77.460348) (xy 93.516958 -77.663548) (xy 93.720158 -77.663548)
			)
		)
		(polygon
			(pts
				(xy 93.008958 -77.460348) (xy 92.805758 -77.460348) (xy 92.805758 -77.663548) (xy 93.008958 -77.663548)
			)
		)
		(polygon
			(pts
				(xy 92.653358 -77.003148) (xy 92.450158 -77.003148) (xy 92.450158 -77.206348) (xy 92.653358 -77.206348)
			)
		)
		(polygon
			(pts
				(xy 92.656406 -75.804014) (xy 92.453206 -75.804014) (xy 92.453206 -76.007214) (xy 92.656406 -76.007214)
			)
		)
		(polygon
			(pts
				(xy 94.409006 -75.448414) (xy 94.205806 -75.448414) (xy 94.205806 -75.651614) (xy 94.409006 -75.651614)
			)
		)
		(polygon
			(pts
				(xy 93.697806 -75.448414) (xy 93.494606 -75.448414) (xy 93.494606 -75.651614) (xy 93.697806 -75.651614)
			)
		)
	)
	(zone
		(net "PCE_AVDD")
		(layer "B.Cu")
		(hatch none 0.5)
		(connect_pads
			(clearance 0.5)
		)
		(min_thickness 0.25)
		(fill yes
			(thermal_gap 0.5)
			(thermal_bridge_width 0.5)
			(island_removal_mode 0)
		)
		(polygon
			(pts
				(xy 170.988482 -33.335976) (xy 170.90644 -33.418018) (xy 170.90644 -33.972246) (xy 170.95343 -34.019236)
				(xy 175.225456 -34.019236) (xy 175.25492 -33.989772) (xy 175.25492 -33.371536) (xy 175.21936 -33.335976)
			)
		)
		(polygon
			(pts
				(xy 174.684944 -33.539684) (xy 174.481744 -33.539684) (xy 174.481744 -33.742884) (xy 174.684944 -33.742884)
			)
		)
		(polygon
			(pts
				(xy 174.329344 -33.539684) (xy 174.126144 -33.539684) (xy 174.126144 -33.742884) (xy 174.329344 -33.742884)
			)
		)
		(polygon
			(pts
				(xy 173.169834 -33.536128) (xy 172.966634 -33.536128) (xy 172.966634 -33.739328) (xy 173.169834 -33.739328)
			)
		)
		(polygon
			(pts
				(xy 172.814234 -33.536128) (xy 172.611034 -33.536128) (xy 172.611034 -33.739328) (xy 172.814234 -33.739328)
			)
		)
		(polygon
			(pts
				(xy 171.446698 -33.524444) (xy 171.243498 -33.524444) (xy 171.243498 -33.727644) (xy 171.446698 -33.727644)
			)
		)
	)
	(zone
		(net "P5V")
		(layer "B.Cu")
		(hatch none 0.5)
		(connect_pads
			(clearance 0.5)
		)
		(min_thickness 0.25)
		(fill yes
			(thermal_gap 0.5)
			(thermal_bridge_width 0.5)
			(island_removal_mode 0)
		)
		(polygon
			(pts
				(xy 36.10102 -105.28554) (xy 35.45078 -105.93578) (xy 35.45078 -113.416588) (xy 35.912552 -113.87836)
				(xy 39.53256 -113.87836) (xy 39.65956 -113.75136) (xy 39.65956 -111.47552) (xy 39.42842 -111.24438)
				(xy 38.904672 -111.24438) (xy 38.3921 -110.731808) (xy 38.3921 -105.71988) (xy 37.95776 -105.28554)
			)
		)
		(polygon
			(pts
				(xy 37.860732 -106.44378) (xy 37.657532 -106.44378) (xy 37.657532 -106.64698) (xy 37.860732 -106.64698)
			)
		)
		(polygon
			(pts
				(xy 37.860732 -105.83418) (xy 37.657532 -105.83418) (xy 37.657532 -106.03738) (xy 37.860732 -106.03738)
			)
		)
	)
	(zone
		(layer "B.Cu")
		(hatch none 0.5)
		(connect_pads
			(clearance 0)
		)
		(min_thickness 0.25)
		(keepout
			(tracks not_allowed)
			(vias allowed)
			(pads allowed)
			(copperpour not_allowed)
			(footprints allowed)
		)
		(placement
			(enabled no)
			(sheetname "")
		)
		(fill
			(thermal_gap 0.5)
			(thermal_bridge_width 0.5)
			(island_removal_mode 0)
		)
		(polygon
			(pts
				(arc
					(start 131.28117 -44.290488)
					(mid 131.252772 -44.283784)
					(end 131.23037 -44.265088)
				)
				(arc
					(start 131.23037 -44.493688)
					(mid 131.252772 -44.474992)
					(end 131.28117 -44.468288)
				)
				(arc
					(start 131.48437 -44.468288)
					(mid 131.512768 -44.474992)
					(end 131.53517 -44.493688)
				)
				(arc
					(start 131.53517 -44.265088)
					(mid 131.512768 -44.283784)
					(end 131.48437 -44.290488)
				)
			)
		)
	)
	(zone
		(layer "B.Cu")
		(hatch none 0.5)
		(connect_pads
			(clearance 0)
		)
		(min_thickness 0.25)
		(keepout
			(tracks not_allowed)
			(vias allowed)
			(pads allowed)
			(copperpour not_allowed)
			(footprints allowed)
		)
		(placement
			(enabled no)
			(sheetname "")
		)
		(fill
			(thermal_gap 0.5)
			(thermal_bridge_width 0.5)
			(island_removal_mode 0)
		)
		(polygon
			(pts
				(arc
					(start 109.961426 -2.600198)
					(mid 109.400086 -2.038858)
					(end 108.838746 -2.600198)
				)
				(arc
					(start 108.838746 -3.028442)
					(mid 108.871698 -3.024751)
					(end 108.904786 -3.0226)
				)
				(xy 108.905548 -3.021838)
				(arc
					(start 109.28096 -3.021838)
					(mid 109.297873 -3.018474)
					(end 109.312202 -3.008884)
				)
				(arc
					(start 109.312202 -3.008884)
					(mid 109.319799 -2.99858)
					(end 109.32414 -2.986532)
				)
				(arc
					(start 109.32414 -2.986532)
					(mid 109.401112 -2.206422)
					(end 109.475016 -2.986786)
				)
				(xy 109.475016 -3.00863)
				(arc
					(start 109.471968 -3.011678)
					(mid 109.453037 -3.067209)
					(end 109.418374 -3.114548)
				)
				(arc
					(start 109.418374 -3.114548)
					(mid 109.370858 -3.149578)
					(end 109.314996 -3.16865)
				)
				(xy 109.311948 -3.171698)
				(arc
					(start 108.936536 -3.171698)
					(mid 108.887452 -3.17388)
					(end 108.838746 -3.180334)
				)
				(arc
					(start 108.838746 -3.44424)
					(mid 108.870871 -3.435359)
					(end 108.90377 -3.430016)
				)
				(xy 108.905548 -3.428238) (xy 109.311948 -3.428238)
				(arc
					(start 109.314996 -3.431286)
					(mid 109.370845 -3.450383)
					(end 109.418374 -3.485388)
				)
				(arc
					(start 109.418374 -3.485388)
					(mid 109.453062 -3.532714)
					(end 109.471968 -3.588258)
				)
				(xy 109.475016 -3.591306)
				(arc
					(start 109.475016 -3.613404)
					(mid 109.400988 -4.393726)
					(end 109.324394 -3.613658)
				)
				(arc
					(start 109.324394 -3.613658)
					(mid 109.319996 -3.601436)
					(end 109.312202 -3.591052)
				)
				(arc
					(start 109.312202 -3.591052)
					(mid 109.297868 -3.581474)
					(end 109.28096 -3.578098)
				)
				(arc
					(start 108.936536 -3.578098)
					(mid 108.884803 -3.586778)
					(end 108.838746 -3.61188)
				)
				(arc
					(start 108.838746 -3.999738)
					(mid 109.399959 -4.561332)
					(end 109.961426 -3.999992)
				)
			)
		)
	)
	(zone
		(layer "B.Cu")
		(hatch none 0.5)
		(connect_pads
			(clearance 0)
		)
		(min_thickness 0.25)
		(keepout
			(tracks not_allowed)
			(vias allowed)
			(pads allowed)
			(copperpour not_allowed)
			(footprints allowed)
		)
		(placement
			(enabled no)
			(sheetname "")
		)
		(fill
			(thermal_gap 0.5)
			(thermal_bridge_width 0.5)
			(island_removal_mode 0)
		)
		(polygon
			(pts
				(arc
					(start 88.36152 -2.600198)
					(mid 87.80018 -2.038858)
					(end 87.23884 -2.600198)
				)
				(arc
					(start 87.23884 -3.028442)
					(mid 87.271792 -3.024751)
					(end 87.30488 -3.0226)
				)
				(xy 87.305642 -3.021838)
				(arc
					(start 87.681054 -3.021838)
					(mid 87.697967 -3.018474)
					(end 87.712296 -3.008884)
				)
				(arc
					(start 87.712296 -3.008884)
					(mid 87.719893 -2.99858)
					(end 87.724234 -2.986532)
				)
				(arc
					(start 87.724234 -2.986532)
					(mid 87.801206 -2.206422)
					(end 87.87511 -2.986786)
				)
				(xy 87.87511 -3.00863)
				(arc
					(start 87.872062 -3.011678)
					(mid 87.853131 -3.067209)
					(end 87.818468 -3.114548)
				)
				(arc
					(start 87.818468 -3.114548)
					(mid 87.770952 -3.149578)
					(end 87.71509 -3.16865)
				)
				(xy 87.712042 -3.171698)
				(arc
					(start 87.33663 -3.171698)
					(mid 87.287546 -3.17388)
					(end 87.23884 -3.180334)
				)
				(arc
					(start 87.23884 -3.44424)
					(mid 87.270965 -3.435359)
					(end 87.303864 -3.430016)
				)
				(xy 87.305642 -3.428238) (xy 87.712042 -3.428238)
				(arc
					(start 87.71509 -3.431286)
					(mid 87.770939 -3.450383)
					(end 87.818468 -3.485388)
				)
				(arc
					(start 87.818468 -3.485388)
					(mid 87.853156 -3.532714)
					(end 87.872062 -3.588258)
				)
				(xy 87.87511 -3.591306)
				(arc
					(start 87.87511 -3.613404)
					(mid 87.801082 -4.393726)
					(end 87.724488 -3.613658)
				)
				(arc
					(start 87.724488 -3.613658)
					(mid 87.72009 -3.601436)
					(end 87.712296 -3.591052)
				)
				(arc
					(start 87.712296 -3.591052)
					(mid 87.697962 -3.581474)
					(end 87.681054 -3.578098)
				)
				(arc
					(start 87.33663 -3.578098)
					(mid 87.284897 -3.586778)
					(end 87.23884 -3.61188)
				)
				(arc
					(start 87.23884 -3.999738)
					(mid 87.800053 -4.561332)
					(end 88.36152 -3.999992)
				)
			)
		)
	)
	(zone
		(layer "B.Cu")
		(hatch none 0.5)
		(connect_pads
			(clearance 0)
		)
		(min_thickness 0.25)
		(keepout
			(tracks not_allowed)
			(vias allowed)
			(pads allowed)
			(copperpour not_allowed)
			(footprints allowed)
		)
		(placement
			(enabled no)
			(sheetname "")
		)
		(fill
			(thermal_gap 0.5)
			(thermal_bridge_width 0.5)
			(island_removal_mode 0)
		)
		(polygon
			(pts
				(arc
					(start 130.72237 -44.290488)
					(mid 130.693972 -44.283784)
					(end 130.67157 -44.265088)
				)
				(arc
					(start 130.67157 -44.493688)
					(mid 130.693972 -44.474992)
					(end 130.72237 -44.468288)
				)
				(arc
					(start 130.92557 -44.468288)
					(mid 130.953968 -44.474992)
					(end 130.97637 -44.493688)
				)
				(arc
					(start 130.97637 -44.265088)
					(mid 130.953968 -44.283784)
					(end 130.92557 -44.290488)
				)
			)
		)
	)
	(zone
		(layer "B.Cu")
		(hatch none 0.5)
		(connect_pads
			(clearance 0)
		)
		(min_thickness 0.25)
		(keepout
			(tracks not_allowed)
			(vias allowed)
			(pads allowed)
			(copperpour not_allowed)
			(footprints allowed)
		)
		(placement
			(enabled no)
			(sheetname "")
		)
		(fill
			(thermal_gap 0.5)
			(thermal_bridge_width 0.5)
			(island_removal_mode 0)
		)
		(polygon
			(pts
				(arc
					(start 111.358172 -55.000144)
					(mid 111.042109 -54.644484)
					(end 110.651798 -54.916578)
				)
				(arc
					(start 110.651798 -55.239412)
					(mid 110.659996 -55.280625)
					(end 110.683294 -55.315612)
				)
				(arc
					(start 110.683294 -55.315612)
					(mid 110.719085 -55.339464)
					(end 110.761272 -55.34787)
				)
				(arc
					(start 110.911132 -55.34787)
					(mid 110.933583 -55.338571)
					(end 110.942882 -55.31612)
				)
				(arc
					(start 110.942882 -55.234586)
					(mid 111.000032 -54.758837)
					(end 111.057182 -55.234586)
				)
				(xy 111.057182 -55.339742)
				(arc
					(start 111.054896 -55.342028)
					(mid 111.014426 -55.419414)
					(end 110.93704 -55.459884)
				)
				(xy 110.934754 -55.46217) (xy 110.73765 -55.46217)
				(arc
					(start 110.736126 -55.460646)
					(mid 110.687174 -55.449546)
					(end 110.641892 -55.42788)
				)
				(arc
					(start 110.641892 -55.513732)
					(mid 110.700074 -55.532094)
					(end 110.760764 -55.53837)
				)
				(xy 110.934754 -55.53837)
				(arc
					(start 110.93704 -55.540656)
					(mid 111.014426 -55.581126)
					(end 111.054896 -55.658512)
				)
				(xy 111.057182 -55.660798)
				(arc
					(start 111.057182 -55.7657)
					(mid 111.000032 -56.241449)
					(end 110.942882 -55.7657)
				)
				(arc
					(start 110.942882 -55.68442)
					(mid 110.933583 -55.661969)
					(end 110.911132 -55.65267)
				)
				(xy 110.73765 -55.65267)
				(arc
					(start 110.736888 -55.651908)
					(mid 110.6889 -55.646299)
					(end 110.641892 -55.635144)
				)
				(arc
					(start 110.641892 -55.999888)
					(mid 110.999905 -56.358282)
					(end 111.358172 -56.000142)
				)
			)
		)
	)
	(zone
		(layer "B.Cu")
		(hatch none 0.5)
		(connect_pads
			(clearance 0)
		)
		(min_thickness 0.25)
		(keepout
			(tracks not_allowed)
			(vias allowed)
			(pads allowed)
			(copperpour not_allowed)
			(footprints allowed)
		)
		(placement
			(enabled no)
			(sheetname "")
		)
		(fill
			(thermal_gap 0.5)
			(thermal_bridge_width 0.5)
			(island_removal_mode 0)
		)
		(polygon
			(pts
				(arc
					(start 106.361484 -2.600198)
					(mid 105.800144 -2.038858)
					(end 105.238804 -2.600198)
				)
				(arc
					(start 105.238804 -3.028442)
					(mid 105.271756 -3.024751)
					(end 105.304844 -3.0226)
				)
				(xy 105.305606 -3.021838)
				(arc
					(start 105.681018 -3.021838)
					(mid 105.697931 -3.018474)
					(end 105.71226 -3.008884)
				)
				(arc
					(start 105.71226 -3.008884)
					(mid 105.719857 -2.99858)
					(end 105.724198 -2.986532)
				)
				(arc
					(start 105.724198 -2.986532)
					(mid 105.80117 -2.206422)
					(end 105.875074 -2.986786)
				)
				(xy 105.875074 -3.00863)
				(arc
					(start 105.872026 -3.011678)
					(mid 105.853095 -3.067209)
					(end 105.818432 -3.114548)
				)
				(arc
					(start 105.818432 -3.114548)
					(mid 105.770916 -3.149578)
					(end 105.715054 -3.16865)
				)
				(xy 105.712006 -3.171698)
				(arc
					(start 105.336594 -3.171698)
					(mid 105.28751 -3.17388)
					(end 105.238804 -3.180334)
				)
				(arc
					(start 105.238804 -3.44424)
					(mid 105.270929 -3.435359)
					(end 105.303828 -3.430016)
				)
				(xy 105.305606 -3.428238) (xy 105.712006 -3.428238)
				(arc
					(start 105.715054 -3.431286)
					(mid 105.770903 -3.450383)
					(end 105.818432 -3.485388)
				)
				(arc
					(start 105.818432 -3.485388)
					(mid 105.85312 -3.532714)
					(end 105.872026 -3.588258)
				)
				(xy 105.875074 -3.591306)
				(arc
					(start 105.875074 -3.613404)
					(mid 105.801046 -4.393726)
					(end 105.724452 -3.613658)
				)
				(arc
					(start 105.724452 -3.613658)
					(mid 105.720054 -3.601436)
					(end 105.71226 -3.591052)
				)
				(arc
					(start 105.71226 -3.591052)
					(mid 105.697926 -3.581474)
					(end 105.681018 -3.578098)
				)
				(arc
					(start 105.336594 -3.578098)
					(mid 105.284861 -3.586778)
					(end 105.238804 -3.61188)
				)
				(arc
					(start 105.238804 -3.999738)
					(mid 105.800017 -4.561332)
					(end 106.361484 -3.999992)
				)
			)
		)
	)
	(zone
		(layer "B.Cu")
		(hatch none 0.5)
		(connect_pads
			(clearance 0)
		)
		(min_thickness 0.25)
		(keepout
			(tracks not_allowed)
			(vias allowed)
			(pads allowed)
			(copperpour not_allowed)
			(footprints allowed)
		)
		(placement
			(enabled no)
			(sheetname "")
		)
		(fill
			(thermal_gap 0.5)
			(thermal_bridge_width 0.5)
			(island_removal_mode 0)
		)
		(polygon
			(pts
				(arc
					(start 173.453044 -30.045914)
					(mid 173.193916 -30.107185)
					(end 173.048676 -30.330394)
				)
				(xy 173.048676 -30.544008) (xy 173.041818 -30.550866)
				(arc
					(start 173.042072 -31.199836)
					(mid 173.400212 -31.55823)
					(end 173.758352 -31.199836)
				)
				(xy 173.758352 -31.029402) (xy 173.758098 -30.711648)
				(arc
					(start 173.5709 -31.029402)
					(mid 173.277571 -31.408004)
					(end 173.467014 -30.968188)
				)
				(xy 173.749716 -30.488636)
				(arc
					(start 173.749716 -30.322266)
					(mid 173.68686 -30.185613)
					(end 173.57344 -30.086808)
				)
				(arc
					(start 173.57344 -30.23235)
					(mid 173.28121 -30.610338)
					(end 173.453044 -30.164532)
				)
			)
		)
	)
	(zone
		(net "GND")
		(layer "B.Cu")
		(hatch none 0.5)
		(connect_pads
			(clearance 0.5)
		)
		(min_thickness 0.25)
		(fill yes
			(thermal_gap 0.5)
			(thermal_bridge_width 0.5)
			(island_removal_mode 0)
		)
		(polygon
			(pts
				(xy 174.5742 -114.6429) (xy 174.4726 -114.7445) (xy 174.4726 -121.7676) (xy 174.47895 -121.77395)
				(xy 174.47895 -122.25655) (xy 174.5488 -122.3264) (xy 176.4538 -122.3264) (xy 177.2666 -121.5136)
				(xy 177.2666 -118.3767) (xy 177.8127 -117.8306) (xy 177.8127 -114.9223) (xy 177.5333 -114.6429)
			)
		)
		(polygon
			(pts
				(xy 175.186848 -121.569734) (xy 174.983648 -121.569734) (xy 174.983648 -121.772934) (xy 175.186848 -121.772934)
			)
		)
	)
	(zone
		(layer "B.Cu")
		(hatch none 0.5)
		(connect_pads
			(clearance 0)
		)
		(min_thickness 0.25)
		(keepout
			(tracks not_allowed)
			(vias allowed)
			(pads allowed)
			(copperpour not_allowed)
			(footprints allowed)
		)
		(placement
			(enabled no)
			(sheetname "")
		)
		(fill
			(thermal_gap 0.5)
			(thermal_bridge_width 0.5)
			(island_removal_mode 0)
		)
		(polygon
			(pts
				(arc
					(start 110.358174 -55.000144)
					(mid 110.047704 -54.645191)
					(end 109.654594 -54.905656)
				)
				(arc
					(start 109.654594 -55.24627)
					(mid 109.662057 -55.28379)
					(end 109.683296 -55.315612)
				)
				(arc
					(start 109.683296 -55.315612)
					(mid 109.719087 -55.339464)
					(end 109.761274 -55.34787)
				)
				(arc
					(start 109.911134 -55.34787)
					(mid 109.933585 -55.338571)
					(end 109.942884 -55.31612)
				)
				(arc
					(start 109.942884 -55.234586)
					(mid 110.000034 -54.758837)
					(end 110.057184 -55.234586)
				)
				(xy 110.057184 -55.339742)
				(arc
					(start 110.054898 -55.342028)
					(mid 110.014428 -55.419414)
					(end 109.937042 -55.459884)
				)
				(xy 109.934756 -55.46217) (xy 109.737652 -55.46217)
				(arc
					(start 109.736128 -55.460646)
					(mid 109.687176 -55.449546)
					(end 109.641894 -55.42788)
				)
				(arc
					(start 109.641894 -55.513732)
					(mid 109.700076 -55.532094)
					(end 109.760766 -55.53837)
				)
				(xy 109.934756 -55.53837)
				(arc
					(start 109.937042 -55.540656)
					(mid 110.014428 -55.581126)
					(end 110.054898 -55.658512)
				)
				(xy 110.057184 -55.660798)
				(arc
					(start 110.057184 -55.7657)
					(mid 110.000034 -56.241449)
					(end 109.942884 -55.7657)
				)
				(arc
					(start 109.942884 -55.68442)
					(mid 109.933585 -55.661969)
					(end 109.911134 -55.65267)
				)
				(xy 109.737652 -55.65267)
				(arc
					(start 109.73689 -55.651908)
					(mid 109.688902 -55.646299)
					(end 109.641894 -55.635144)
				)
				(arc
					(start 109.641894 -55.999888)
					(mid 109.999907 -56.358282)
					(end 110.358174 -56.000142)
				)
			)
		)
	)
	(zone
		(net "P0V9")
		(layer "B.Cu")
		(hatch none 0.5)
		(connect_pads
			(clearance 0.5)
		)
		(min_thickness 0.25)
		(fill yes
			(thermal_gap 0.5)
			(thermal_bridge_width 0.5)
			(island_removal_mode 0)
		)
		(polygon
			(pts
				(xy 87.894668 -73.71207) (xy 87.6935 -73.913238) (xy 87.6935 -74.3331) (xy 87.7316 -74.3712) (xy 87.7316 -75.9206)
				(xy 88.4936 -76.6826) (xy 88.4936 -78.017624) (xy 88.6206 -78.144624) (xy 91.27871 -78.144624) (xy 91.343734 -78.0796)
				(xy 91.343734 -75.052174) (xy 91.222322 -74.930762) (xy 88.646762 -74.930762) (xy 88.4174 -74.7014)
				(xy 88.4174 -73.85939) (xy 88.27008 -73.71207)
			)
		)
		(polygon
			(pts
				(xy 90.808556 -77.511148) (xy 90.605356 -77.511148) (xy 90.605356 -77.714348) (xy 90.808556 -77.714348)
			)
		)
		(polygon
			(pts
				(xy 90.810588 -75.372214) (xy 90.607388 -75.372214) (xy 90.607388 -75.575414) (xy 90.810588 -75.575414)
			)
		)
	)
	(zone
		(net "GND")
		(layer "B.Cu")
		(hatch none 0.5)
		(connect_pads
			(clearance 0.5)
		)
		(min_thickness 0.25)
		(fill yes
			(thermal_gap 0.5)
			(thermal_bridge_width 0.5)
			(island_removal_mode 0)
		)
		(polygon
			(pts
				(xy 152.9334 -108.3564) (xy 151.9682 -109.3216) (xy 151.9682 -118.8466) (xy 152.0063 -118.8847)
				(xy 154.9146 -118.8847) (xy 155.0797 -118.7196) (xy 155.0797 -111.0996) (xy 155.3083 -110.871) (xy 159.999934 -110.871)
				(xy 160.229296 -110.641638) (xy 160.229296 -108.490766) (xy 160.09493 -108.3564)
			)
		)
	)
	(zone
		(net "P1V8_E")
		(layer "B.Cu")
		(hatch none 0.5)
		(connect_pads
			(clearance 0.5)
		)
		(min_thickness 0.25)
		(fill yes
			(thermal_gap 0.5)
			(thermal_bridge_width 0.5)
			(island_removal_mode 0)
		)
		(polygon
			(pts
				(xy 126.0475 -87.4141) (xy 125.8951 -87.5665) (xy 125.8951 -88.4809) (xy 126.2507 -88.8365) (xy 126.7206 -88.8365)
				(xy 126.8476 -88.7095) (xy 126.8476 -88.1126) (xy 126.9873 -87.9729) (xy 129.8956 -87.9729) (xy 130.1496 -88.2269)
				(xy 130.1496 -89.6747) (xy 129.9337 -89.8906) (xy 128.2954 -89.8906) (xy 128.2065 -89.9795) (xy 128.2065 -91.2495)
				(xy 128.649476 -91.692476) (xy 130.532124 -91.692476) (xy 130.9497 -91.2749) (xy 130.9497 -90.0303)
				(xy 131.2164 -89.7636) (xy 134.6073 -89.7636) (xy 134.8867 -89.4842) (xy 134.8867 -87.503) (xy 134.7978 -87.4141)
			)
		)
		(polygon
			(pts
				(xy 129.921 -90.3478) (xy 129.7178 -90.3478) (xy 129.7178 -90.551) (xy 129.921 -90.551)
			)
		)
		(polygon
			(pts
				(xy 129.3622 -90.3478) (xy 129.159 -90.3478) (xy 129.159 -90.551) (xy 129.3622 -90.551)
			)
		)
		(polygon
			(pts
				(xy 128.905 -90.3478) (xy 128.7018 -90.3478) (xy 128.7018 -90.551) (xy 128.905 -90.551)
			)
		)
		(polygon
			(pts
				(xy 133.096 -89.1032) (xy 132.8928 -89.1032) (xy 132.8928 -89.3064) (xy 133.096 -89.3064)
			)
		)
		(polygon
			(pts
				(xy 132.5372 -89.1032) (xy 132.334 -89.1032) (xy 132.334 -89.3064) (xy 132.5372 -89.3064)
			)
		)
		(polygon
			(pts
				(xy 132.08 -89.1032) (xy 131.8768 -89.1032) (xy 131.8768 -89.3064) (xy 132.08 -89.3064)
			)
		)
		(polygon
			(pts
				(xy 131.5212 -89.1032) (xy 131.318 -89.1032) (xy 131.318 -89.3064) (xy 131.5212 -89.3064)
			)
		)
		(polygon
			(pts
				(xy 134.346188 -87.870284) (xy 134.142988 -87.870284) (xy 134.142988 -88.073484) (xy 134.346188 -88.073484)
			)
		)
		(polygon
			(pts
				(xy 133.863588 -87.870284) (xy 133.660388 -87.870284) (xy 133.660388 -88.073484) (xy 133.863588 -88.073484)
			)
		)
		(polygon
			(pts
				(xy 133.304788 -87.870284) (xy 133.101588 -87.870284) (xy 133.101588 -88.073484) (xy 133.304788 -88.073484)
			)
		)
		(polygon
			(pts
				(xy 132.847588 -87.870284) (xy 132.644388 -87.870284) (xy 132.644388 -88.073484) (xy 132.847588 -88.073484)
			)
		)
		(polygon
			(pts
				(xy 132.288788 -87.870284) (xy 132.085588 -87.870284) (xy 132.085588 -88.073484) (xy 132.288788 -88.073484)
			)
		)
		(polygon
			(pts
				(xy 131.830318 -87.870284) (xy 131.627118 -87.870284) (xy 131.627118 -88.073484) (xy 131.830318 -88.073484)
			)
		)
		(polygon
			(pts
				(xy 131.271518 -87.870284) (xy 131.068318 -87.870284) (xy 131.068318 -88.073484) (xy 131.271518 -88.073484)
			)
		)
		(polygon
			(pts
				(xy 130.814318 -87.870284) (xy 130.611118 -87.870284) (xy 130.611118 -88.073484) (xy 130.814318 -88.073484)
			)
		)
		(polygon
			(pts
				(xy 126.671324 -87.866474) (xy 126.468124 -87.866474) (xy 126.468124 -88.069674) (xy 126.671324 -88.069674)
			)
		)
	)
	(zone
		(layer "B.Cu")
		(hatch none 0.5)
		(connect_pads
			(clearance 0)
		)
		(min_thickness 0.25)
		(keepout
			(tracks not_allowed)
			(vias allowed)
			(pads allowed)
			(copperpour not_allowed)
			(footprints allowed)
		)
		(placement
			(enabled no)
			(sheetname "")
		)
		(fill
			(thermal_gap 0.5)
			(thermal_bridge_width 0.5)
			(island_removal_mode 0)
		)
		(polygon
			(pts
				(arc
					(start 126.000256 -71.64197)
					(mid 125.641862 -71.999983)
					(end 126.000002 -72.35825)
				)
				(arc
					(start 127 -72.35825)
					(mid 127.355023 -72.047261)
					(end 127.093472 -71.654416)
				)
				(arc
					(start 126.747778 -71.654416)
					(mid 126.680246 -71.682388)
					(end 126.652274 -71.74992)
				)
				(arc
					(start 126.652274 -71.900034)
					(mid 126.664847 -71.930387)
					(end 126.6952 -71.94296)
				)
				(arc
					(start 126.765558 -71.94296)
					(mid 127.241307 -72.00011)
					(end 126.765558 -72.05726)
				)
				(xy 126.671578 -72.05726)
				(arc
					(start 126.669292 -72.055228)
					(mid 126.583943 -72.011291)
					(end 126.540006 -71.925942)
				)
				(xy 126.537974 -71.923656) (xy 126.537974 -71.726298)
				(arc
					(start 126.539498 -71.724774)
					(mid 126.549332 -71.681861)
					(end 126.567946 -71.64197)
				)
				(arc
					(start 126.482856 -71.64197)
					(mid 126.467091 -71.694923)
					(end 126.461774 -71.74992)
				)
				(xy 126.461774 -71.92391)
				(arc
					(start 126.459742 -71.926196)
					(mid 126.415882 -72.011368)
					(end 126.33071 -72.055228)
				)
				(xy 126.328424 -72.05726)
				(arc
					(start 126.234444 -72.05726)
					(mid 125.758695 -72.00011)
					(end 126.234444 -71.94296)
				)
				(arc
					(start 126.304802 -71.94296)
					(mid 126.334976 -71.930462)
					(end 126.347474 -71.900288)
				)
				(xy 126.347474 -71.726298)
				(arc
					(start 126.348236 -71.725536)
					(mid 126.353007 -71.683383)
					(end 126.362206 -71.64197)
				)
			)
		)
	)
	(zone
		(net "P0V975")
		(layer "B.Cu")
		(hatch none 0.5)
		(connect_pads
			(clearance 0.5)
		)
		(min_thickness 0.25)
		(fill yes
			(thermal_gap 0.5)
			(thermal_bridge_width 0.5)
			(island_removal_mode 0)
		)
		(polygon
			(pts
				(xy 171.661582 -35.656012) (xy 171.5008 -35.816794) (xy 171.5008 -39.895018) (xy 171.496736 -39.899336)
				(xy 171.496736 -40.327326) (xy 171.353226 -40.470836) (xy 170.984164 -40.470836) (xy 170.688 -40.767)
				(xy 170.688 -47.966122) (xy 171.03471 -48.312832) (xy 172.188886 -48.312832) (xy 172.216318 -48.2854)
				(xy 172.216318 -45.402246) (xy 172.234098 -45.384466) (xy 172.453808 -45.16501) (xy 173.61281 -45.16501)
				(xy 173.7868 -45.339) (xy 173.7868 -45.7454) (xy 173.9773 -45.9359) (xy 179.8447 -45.9359) (xy 179.935632 -45.844968)
				(xy 179.935632 -44.8564) (xy 179.3748 -44.295568) (xy 179.3748 -43.832018) (xy 179.376832 -43.829732)
				(xy 179.376832 -36.2204) (xy 178.812444 -35.656012)
			)
		)
		(polygon
			(pts
				(xy 172.706538 -43.55465) (xy 172.503338 -43.55465) (xy 172.503338 -43.75785) (xy 172.706538 -43.75785)
			)
		)
		(polygon
			(pts
				(xy 176.7459 -43.5483) (xy 176.5427 -43.5483) (xy 176.5427 -43.7515) (xy 176.7459 -43.7515)
			)
		)
		(polygon
			(pts
				(xy 175.7807 -43.5483) (xy 175.5775 -43.5483) (xy 175.5775 -43.7515) (xy 175.7807 -43.7515)
			)
		)
		(polygon
			(pts
				(xy 174.3583 -43.54322) (xy 174.1551 -43.54322) (xy 174.1551 -43.74642) (xy 174.3583 -43.74642)
			)
		)
		(polygon
			(pts
				(xy 173.3931 -43.54322) (xy 173.1899 -43.54322) (xy 173.1899 -43.74642) (xy 173.3931 -43.74642)
			)
		)
		(polygon
			(pts
				(xy 172.706538 -42.99585) (xy 172.503338 -42.99585) (xy 172.503338 -43.40225) (xy 172.706538 -43.40225)
			)
		)
		(polygon
			(pts
				(xy 176.7459 -42.9895) (xy 176.5427 -42.9895) (xy 176.5427 -43.3959) (xy 176.7459 -43.3959)
			)
		)
		(polygon
			(pts
				(xy 175.7807 -42.9895) (xy 175.5775 -42.9895) (xy 175.5775 -43.3959) (xy 175.7807 -43.3959)
			)
		)
		(polygon
			(pts
				(xy 174.3583 -42.98442) (xy 174.1551 -42.98442) (xy 174.1551 -43.39082) (xy 174.3583 -43.39082)
			)
		)
		(polygon
			(pts
				(xy 173.3931 -42.98442) (xy 173.1899 -42.98442) (xy 173.1899 -43.39082) (xy 173.3931 -43.39082)
			)
		)
		(polygon
			(pts
				(xy 172.706538 -42.64025) (xy 172.503338 -42.64025) (xy 172.503338 -42.84345) (xy 172.706538 -42.84345)
			)
		)
		(polygon
			(pts
				(xy 176.7459 -42.6339) (xy 176.5427 -42.6339) (xy 176.5427 -42.8371) (xy 176.7459 -42.8371)
			)
		)
		(polygon
			(pts
				(xy 175.7807 -42.6339) (xy 175.5775 -42.6339) (xy 175.5775 -42.8371) (xy 175.7807 -42.8371)
			)
		)
		(polygon
			(pts
				(xy 174.3583 -42.62882) (xy 174.1551 -42.62882) (xy 174.1551 -42.83202) (xy 174.3583 -42.83202)
			)
		)
		(polygon
			(pts
				(xy 173.3931 -42.62882) (xy 173.1899 -42.62882) (xy 173.1899 -42.83202) (xy 173.3931 -42.83202)
			)
		)
		(polygon
			(pts
				(xy 178.390042 -41.964356) (xy 178.186842 -41.964356) (xy 178.186842 -42.167556) (xy 178.390042 -42.167556)
			)
		)
		(polygon
			(pts
				(xy 177.424842 -41.964356) (xy 177.221642 -41.964356) (xy 177.221642 -42.167556) (xy 177.424842 -42.167556)
			)
		)
		(polygon
			(pts
				(xy 179.060348 -41.964102) (xy 178.857148 -41.964102) (xy 178.857148 -42.167302) (xy 179.060348 -42.167302)
			)
		)
		(polygon
			(pts
				(xy 175.821848 -41.95191) (xy 175.618648 -41.95191) (xy 175.618648 -42.15511) (xy 175.821848 -42.15511)
			)
		)
		(polygon
			(pts
				(xy 174.371 -41.94302) (xy 174.1678 -41.94302) (xy 174.1678 -42.14622) (xy 174.371 -42.14622)
			)
		)
		(polygon
			(pts
				(xy 173.4058 -41.94302) (xy 173.2026 -41.94302) (xy 173.2026 -42.14622) (xy 173.4058 -42.14622)
			)
		)
		(polygon
			(pts
				(xy 178.390042 -41.405556) (xy 178.186842 -41.405556) (xy 178.186842 -41.811956) (xy 178.390042 -41.811956)
			)
		)
		(polygon
			(pts
				(xy 177.424842 -41.405556) (xy 177.221642 -41.405556) (xy 177.221642 -41.811956) (xy 177.424842 -41.811956)
			)
		)
		(polygon
			(pts
				(xy 179.060348 -41.405302) (xy 178.857148 -41.405302) (xy 178.857148 -41.811702) (xy 179.060348 -41.811702)
			)
		)
		(polygon
			(pts
				(xy 175.821848 -41.39311) (xy 175.618648 -41.39311) (xy 175.618648 -41.79951) (xy 175.821848 -41.79951)
			)
		)
		(polygon
			(pts
				(xy 174.371 -41.38422) (xy 174.1678 -41.38422) (xy 174.1678 -41.79062) (xy 174.371 -41.79062)
			)
		)
		(polygon
			(pts
				(xy 173.4058 -41.38422) (xy 173.2026 -41.38422) (xy 173.2026 -41.79062) (xy 173.4058 -41.79062)
			)
		)
		(polygon
			(pts
				(xy 178.390042 -41.049956) (xy 178.186842 -41.049956) (xy 178.186842 -41.253156) (xy 178.390042 -41.253156)
			)
		)
		(polygon
			(pts
				(xy 177.424842 -41.049956) (xy 177.221642 -41.049956) (xy 177.221642 -41.253156) (xy 177.424842 -41.253156)
			)
		)
		(polygon
			(pts
				(xy 179.060348 -41.049702) (xy 178.857148 -41.049702) (xy 178.857148 -41.252902) (xy 179.060348 -41.252902)
			)
		)
		(polygon
			(pts
				(xy 175.821848 -41.03751) (xy 175.618648 -41.03751) (xy 175.618648 -41.24071) (xy 175.821848 -41.24071)
			)
		)
		(polygon
			(pts
				(xy 174.371 -41.02862) (xy 174.1678 -41.02862) (xy 174.1678 -41.23182) (xy 174.371 -41.23182)
			)
		)
		(polygon
			(pts
				(xy 173.4058 -41.02862) (xy 173.2026 -41.02862) (xy 173.2026 -41.23182) (xy 173.4058 -41.23182)
			)
		)
		(polygon
			(pts
				(xy 179.049934 -40.365426) (xy 178.846734 -40.365426) (xy 178.846734 -40.568626) (xy 179.049934 -40.568626)
			)
		)
		(polygon
			(pts
				(xy 178.395376 -40.346122) (xy 178.192176 -40.346122) (xy 178.192176 -40.549322) (xy 178.395376 -40.549322)
			)
		)
		(polygon
			(pts
				(xy 177.430176 -40.346122) (xy 177.226976 -40.346122) (xy 177.226976 -40.549322) (xy 177.430176 -40.549322)
			)
		)
		(polygon
			(pts
				(xy 175.84039 -40.344344) (xy 175.63719 -40.344344) (xy 175.63719 -40.547544) (xy 175.84039 -40.547544)
			)
		)
		(polygon
			(pts
				(xy 174.6758 -40.1701) (xy 174.4726 -40.1701) (xy 174.4726 -40.3733) (xy 174.6758 -40.3733)
			)
		)
		(polygon
			(pts
				(xy 179.049934 -39.806626) (xy 178.846734 -39.806626) (xy 178.846734 -40.213026) (xy 179.049934 -40.213026)
			)
		)
		(polygon
			(pts
				(xy 178.395376 -39.787322) (xy 178.192176 -39.787322) (xy 178.192176 -40.193722) (xy 178.395376 -40.193722)
			)
		)
		(polygon
			(pts
				(xy 177.430176 -39.787322) (xy 177.226976 -39.787322) (xy 177.226976 -40.193722) (xy 177.430176 -40.193722)
			)
		)
		(polygon
			(pts
				(xy 175.84039 -39.785544) (xy 175.63719 -39.785544) (xy 175.63719 -40.191944) (xy 175.84039 -40.191944)
			)
		)
		(polygon
			(pts
				(xy 174.6758 -39.5605) (xy 174.4726 -39.5605) (xy 174.4726 -39.7637) (xy 174.6758 -39.7637)
			)
		)
		(polygon
			(pts
				(xy 179.049934 -39.451026) (xy 178.846734 -39.451026) (xy 178.846734 -39.654226) (xy 179.049934 -39.654226)
			)
		)
		(polygon
			(pts
				(xy 178.395376 -39.431722) (xy 178.192176 -39.431722) (xy 178.192176 -39.634922) (xy 178.395376 -39.634922)
			)
		)
		(polygon
			(pts
				(xy 177.430176 -39.431722) (xy 177.226976 -39.431722) (xy 177.226976 -39.634922) (xy 177.430176 -39.634922)
			)
		)
		(polygon
			(pts
				(xy 175.84039 -39.429944) (xy 175.63719 -39.429944) (xy 175.63719 -39.633144) (xy 175.84039 -39.633144)
			)
		)
		(polygon
			(pts
				(xy 172.301408 -39.42461) (xy 172.098208 -39.42461) (xy 172.098208 -39.62781) (xy 172.301408 -39.62781)
			)
		)
		(polygon
			(pts
				(xy 175.8188 -38.7477) (xy 175.6156 -38.7477) (xy 175.6156 -38.9509) (xy 175.8188 -38.9509)
			)
		)
		(polygon
			(pts
				(xy 178.3969 -38.74516) (xy 178.1937 -38.74516) (xy 178.1937 -38.94836) (xy 178.3969 -38.94836)
			)
		)
		(polygon
			(pts
				(xy 177.4317 -38.74516) (xy 177.2285 -38.74516) (xy 177.2285 -38.94836) (xy 177.4317 -38.94836)
			)
		)
		(polygon
			(pts
				(xy 179.057808 -38.74389) (xy 178.854608 -38.74389) (xy 178.854608 -38.94709) (xy 179.057808 -38.94709)
			)
		)
		(polygon
			(pts
				(xy 174.7012 -38.5826) (xy 174.498 -38.5826) (xy 174.498 -38.7858) (xy 174.7012 -38.7858)
			)
		)
		(polygon
			(pts
				(xy 172.301408 -38.53561) (xy 172.098208 -38.53561) (xy 172.098208 -39.01821) (xy 172.301408 -39.01821)
			)
		)
		(polygon
			(pts
				(xy 175.8188 -38.1889) (xy 175.6156 -38.1889) (xy 175.6156 -38.5953) (xy 175.8188 -38.5953)
			)
		)
		(polygon
			(pts
				(xy 178.3969 -38.18636) (xy 178.1937 -38.18636) (xy 178.1937 -38.59276) (xy 178.3969 -38.59276)
			)
		)
		(polygon
			(pts
				(xy 177.4317 -38.18636) (xy 177.2285 -38.18636) (xy 177.2285 -38.59276) (xy 177.4317 -38.59276)
			)
		)
		(polygon
			(pts
				(xy 179.057808 -38.18509) (xy 178.854608 -38.18509) (xy 178.854608 -38.59149) (xy 179.057808 -38.59149)
			)
		)
		(polygon
			(pts
				(xy 172.301408 -37.92601) (xy 172.098208 -37.92601) (xy 172.098208 -38.12921) (xy 172.301408 -38.12921)
			)
		)
		(polygon
			(pts
				(xy 175.8188 -37.8333) (xy 175.6156 -37.8333) (xy 175.6156 -38.0365) (xy 175.8188 -38.0365)
			)
		)
		(polygon
			(pts
				(xy 178.3969 -37.83076) (xy 178.1937 -37.83076) (xy 178.1937 -38.03396) (xy 178.3969 -38.03396)
			)
		)
		(polygon
			(pts
				(xy 177.4317 -37.83076) (xy 177.2285 -37.83076) (xy 177.2285 -38.03396) (xy 177.4317 -38.03396)
			)
		)
		(polygon
			(pts
				(xy 179.057808 -37.82949) (xy 178.854608 -37.82949) (xy 178.854608 -38.03269) (xy 179.057808 -38.03269)
			)
		)
		(polygon
			(pts
				(xy 178.397408 -37.12591) (xy 178.194208 -37.12591) (xy 178.194208 -37.32911) (xy 178.397408 -37.32911)
			)
		)
		(polygon
			(pts
				(xy 177.432208 -37.12591) (xy 177.229008 -37.12591) (xy 177.229008 -37.32911) (xy 177.432208 -37.32911)
			)
		)
		(polygon
			(pts
				(xy 175.819308 -37.11321) (xy 175.616108 -37.11321) (xy 175.616108 -37.31641) (xy 175.819308 -37.31641)
			)
		)
		(polygon
			(pts
				(xy 177.432208 -36.77031) (xy 177.229008 -36.77031) (xy 177.229008 -36.97351) (xy 177.432208 -36.97351)
			)
		)
		(polygon
			(pts
				(xy 175.819308 -36.75761) (xy 175.616108 -36.75761) (xy 175.616108 -36.96081) (xy 175.819308 -36.96081)
			)
		)
		(polygon
			(pts
				(xy 174.701708 -36.50361) (xy 174.498508 -36.50361) (xy 174.498508 -36.70681) (xy 174.701708 -36.70681)
			)
		)
		(polygon
			(pts
				(xy 177.169572 -36.018216) (xy 176.966372 -36.018216) (xy 176.966372 -36.221416) (xy 177.169572 -36.221416)
			)
		)
		(polygon
			(pts
				(xy 176.604168 -36.017962) (xy 176.400968 -36.017962) (xy 176.400968 -36.221162) (xy 176.604168 -36.221162)
				(xy 176.610772 -36.221416) (xy 176.813972 -36.221416) (xy 176.813972 -36.018216) (xy 176.610772 -36.018216)
			)
		)
		(polygon
			(pts
				(xy 176.248568 -36.017962) (xy 176.045368 -36.017962) (xy 176.045368 -36.221162) (xy 176.248568 -36.221162)
			)
		)
		(polygon
			(pts
				(xy 174.649892 -35.944048) (xy 174.446692 -35.944048) (xy 174.446692 -36.147248) (xy 174.649892 -36.147248)
			)
		)
		(polygon
			(pts
				(xy 173.938692 -35.94227) (xy 173.735492 -35.94227) (xy 173.735492 -36.14547) (xy 173.938692 -36.14547)
			)
		)
		(polygon
			(pts
				(xy 173.583092 -35.94227) (xy 173.379892 -35.94227) (xy 173.379892 -36.14547) (xy 173.583092 -36.14547)
			)
		)
		(polygon
			(pts
				(xy 175.5648 -35.941) (xy 175.3616 -35.941) (xy 175.3616 -36.1442) (xy 175.5648 -36.1442)
			)
		)
		(polygon
			(pts
				(xy 175.2092 -35.941) (xy 175.006 -35.941) (xy 175.005492 -35.944048) (xy 174.802292 -35.944048)
				(xy 174.802292 -36.147248) (xy 175.005492 -36.147248) (xy 175.006 -36.1442) (xy 175.2092 -36.1442)
			)
		)
	)
	(zone
		(net "GND")
		(layer "B.Cu")
		(hatch none 0.5)
		(connect_pads
			(clearance 0.5)
		)
		(min_thickness 0.25)
		(fill yes
			(thermal_gap 0.5)
			(thermal_bridge_width 0.5)
			(island_removal_mode 0)
		)
		(polygon
			(pts
				(xy 38.911784 -104.801416) (xy 38.6715 -105.0417) (xy 38.6715 -110.5535) (xy 38.9763 -110.8583)
				(xy 39.472616 -110.8583) (xy 40.019732 -111.405416) (xy 40.019732 -115.850416) (xy 39.130732 -116.739416)
				(xy 39.130732 -119.533416) (xy 39.257732 -119.660416) (xy 42.940732 -119.660416) (xy 43.067732 -119.533416)
				(xy 43.067732 -116.485416) (xy 42.1767 -115.594384) (xy 42.1767 -110.8456) (xy 42.635678 -110.386622)
				(xy 42.635678 -105.043478) (xy 42.398442 -104.806242) (xy 41.675558 -104.806242) (xy 41.670732 -104.801416)
			)
		)
		(polygon
			(pts
				(xy 41.868852 -110.27918) (xy 41.665652 -110.27918) (xy 41.665652 -110.48238) (xy 41.868852 -110.48238)
			)
		)
		(polygon
			(pts
				(xy 41.868852 -109.41558) (xy 41.665652 -109.41558) (xy 41.665652 -109.61878) (xy 41.868852 -109.61878)
			)
		)
		(polygon
			(pts
				(xy 39.384732 -106.44378) (xy 39.181532 -106.44378) (xy 39.181532 -106.64698) (xy 39.384732 -106.64698)
			)
		)
		(polygon
			(pts
				(xy 39.384732 -105.83418) (xy 39.181532 -105.83418) (xy 39.181532 -106.03738) (xy 39.384732 -106.03738)
			)
		)
	)
	(zone
		(layer "B.Cu")
		(hatch none 0.5)
		(connect_pads
			(clearance 0)
		)
		(min_thickness 0.25)
		(keepout
			(tracks not_allowed)
			(vias allowed)
			(pads allowed)
			(copperpour not_allowed)
			(footprints allowed)
		)
		(placement
			(enabled no)
			(sheetname "")
		)
		(fill
			(thermal_gap 0.5)
			(thermal_bridge_width 0.5)
			(island_removal_mode 0)
		)
		(polygon
			(pts
				(arc
					(start 121.358152 -55.000144)
					(mid 121.046246 -54.645001)
					(end 120.65381 -54.90845)
				)
				(arc
					(start 120.65381 -55.244492)
					(mid 120.661467 -55.282984)
					(end 120.683274 -55.315612)
				)
				(arc
					(start 120.683274 -55.315612)
					(mid 120.719065 -55.339464)
					(end 120.761252 -55.34787)
				)
				(arc
					(start 120.911112 -55.34787)
					(mid 120.933563 -55.338571)
					(end 120.942862 -55.31612)
				)
				(arc
					(start 120.942862 -55.234586)
					(mid 121.000012 -54.758837)
					(end 121.057162 -55.234586)
				)
				(xy 121.057162 -55.339742)
				(arc
					(start 121.054876 -55.342028)
					(mid 121.014406 -55.419414)
					(end 120.93702 -55.459884)
				)
				(xy 120.934734 -55.46217) (xy 120.73763 -55.46217)
				(arc
					(start 120.736106 -55.460646)
					(mid 120.687154 -55.449546)
					(end 120.641872 -55.42788)
				)
				(arc
					(start 120.641872 -55.513732)
					(mid 120.700054 -55.532094)
					(end 120.760744 -55.53837)
				)
				(xy 120.934734 -55.53837)
				(arc
					(start 120.93702 -55.540656)
					(mid 121.014406 -55.581126)
					(end 121.054876 -55.658512)
				)
				(xy 121.057162 -55.660798)
				(arc
					(start 121.057162 -55.7657)
					(mid 121.000012 -56.241449)
					(end 120.942862 -55.7657)
				)
				(arc
					(start 120.942862 -55.68442)
					(mid 120.933563 -55.661969)
					(end 120.911112 -55.65267)
				)
				(xy 120.73763 -55.65267)
				(arc
					(start 120.736868 -55.651908)
					(mid 120.68888 -55.646299)
					(end 120.641872 -55.635144)
				)
				(arc
					(start 120.641872 -55.999888)
					(mid 120.999885 -56.358282)
					(end 121.358152 -56.000142)
				)
			)
		)
	)
	(zone
		(layer "B.Cu")
		(hatch none 0.5)
		(connect_pads
			(clearance 0)
		)
		(min_thickness 0.25)
		(keepout
			(tracks allowed)
			(vias allowed)
			(pads allowed)
			(copperpour allowed)
			(footprints allowed)
		)
		(placement
			(enabled no)
			(sheetname "")
		)
		(fill
			(thermal_gap 0.5)
			(thermal_bridge_width 0.5)
			(island_removal_mode 0)
		)
		(polygon
			(pts
				(xy 168.539922 -27.798522) (xy 169.4688 -28.7274) (xy 169.4688 -28.7528) (xy 169.672 -28.956) (xy 170.8912 -28.956)
				(xy 170.940476 -29.005276) (xy 170.940476 -29.014928) (xy 171.00296 -29.077412) (xy 171.506896 -29.077412)
				(xy 171.577508 -29.0068) (xy 171.9072 -29.0068) (xy 172.6184 -29.718) (xy 173.1264 -29.718) (xy 173.3804 -29.464)
				(xy 174.2186 -29.464) (xy 174.625 -29.8704) (xy 174.700692 -29.946092) (xy 175.514508 -29.946092)
				(xy 175.5902 -29.8704) (xy 176.2252 -29.2354) (xy 176.2252 -28.4988) (xy 176.255934 -28.468066)
				(xy 176.816258 -28.468066) (xy 176.8602 -28.512008) (xy 176.8602 -31.0388) (xy 176.3776 -31.5214)
				(xy 167.5892 -31.5214) (xy 167.3606 -31.2928) (xy 167.3606 -29.11729) (xy 167.975026 -28.502864)
				(xy 167.975026 -28.240736) (xy 168.41724 -27.798522)
			)
		)
	)
	(zone
		(layer "B.Cu")
		(hatch none 0.5)
		(connect_pads
			(clearance 0)
		)
		(min_thickness 0.25)
		(keepout
			(tracks allowed)
			(vias allowed)
			(pads allowed)
			(copperpour allowed)
			(footprints not_allowed)
		)
		(placement
			(enabled no)
			(sheetname "")
		)
		(fill
			(thermal_gap 0.5)
			(thermal_bridge_width 0.5)
			(island_removal_mode 0)
		)
		(polygon
			(pts
				(arc
					(start 79.749904 -134.999984)
					(mid 75.000104 -130.250184)
					(end 70.25005 -134.999984)
				)
				(arc
					(start 70.25005 -134.999984)
					(mid 75.000104 -139.750038)
					(end 79.749904 -134.999984)
				)
			)
		)
	)
	(zone
		(layer "B.Cu")
		(hatch none 0.5)
		(connect_pads
			(clearance 0)
		)
		(min_thickness 0.25)
		(keepout
			(tracks not_allowed)
			(vias allowed)
			(pads allowed)
			(copperpour not_allowed)
			(footprints allowed)
		)
		(placement
			(enabled no)
			(sheetname "")
		)
		(fill
			(thermal_gap 0.5)
			(thermal_bridge_width 0.5)
			(island_removal_mode 0)
		)
		(polygon
			(pts
				(arc
					(start 119.358156 -55.000144)
					(mid 119.042613 -54.644546)
					(end 118.652036 -54.915562)
				)
				(arc
					(start 118.652036 -55.240174)
					(mid 118.660157 -55.280999)
					(end 118.683278 -55.315612)
				)
				(arc
					(start 118.683278 -55.315612)
					(mid 118.719069 -55.339464)
					(end 118.761256 -55.34787)
				)
				(arc
					(start 118.911116 -55.34787)
					(mid 118.933567 -55.338571)
					(end 118.942866 -55.31612)
				)
				(arc
					(start 118.942866 -55.234586)
					(mid 119.000016 -54.758837)
					(end 119.057166 -55.234586)
				)
				(xy 119.057166 -55.339742)
				(arc
					(start 119.05488 -55.342028)
					(mid 119.01441 -55.419414)
					(end 118.937024 -55.459884)
				)
				(xy 118.934738 -55.46217) (xy 118.737634 -55.46217)
				(arc
					(start 118.73611 -55.460646)
					(mid 118.687158 -55.449546)
					(end 118.641876 -55.42788)
				)
				(arc
					(start 118.641876 -55.513732)
					(mid 118.700058 -55.532094)
					(end 118.760748 -55.53837)
				)
				(xy 118.934738 -55.53837)
				(arc
					(start 118.937024 -55.540656)
					(mid 119.01441 -55.581126)
					(end 119.05488 -55.658512)
				)
				(xy 119.057166 -55.660798)
				(arc
					(start 119.057166 -55.7657)
					(mid 119.000016 -56.241449)
					(end 118.942866 -55.7657)
				)
				(arc
					(start 118.942866 -55.68442)
					(mid 118.933567 -55.661969)
					(end 118.911116 -55.65267)
				)
				(xy 118.737634 -55.65267)
				(arc
					(start 118.736872 -55.651908)
					(mid 118.688884 -55.646299)
					(end 118.641876 -55.635144)
				)
				(arc
					(start 118.641876 -55.999888)
					(mid 118.999889 -56.358282)
					(end 119.358156 -56.000142)
				)
			)
		)
	)
	(zone
		(layer "B.Cu")
		(hatch none 0.5)
		(connect_pads
			(clearance 0)
		)
		(min_thickness 0.25)
		(keepout
			(tracks not_allowed)
			(vias allowed)
			(pads allowed)
			(copperpour not_allowed)
			(footprints allowed)
		)
		(placement
			(enabled no)
			(sheetname "")
		)
		(fill
			(thermal_gap 0.5)
			(thermal_bridge_width 0.5)
			(island_removal_mode 0)
		)
		(polygon
			(pts
				(arc
					(start 126.000256 -62.641988)
					(mid 125.641862 -63.000001)
					(end 126.000002 -63.358268)
				)
				(arc
					(start 127 -63.358268)
					(mid 127.355971 -63.039481)
					(end 127.078232 -62.650624)
				)
				(arc
					(start 126.751588 -62.650624)
					(mid 126.681362 -62.679712)
					(end 126.652274 -62.749938)
				)
				(arc
					(start 126.652274 -62.900052)
					(mid 126.664847 -62.930405)
					(end 126.6952 -62.942978)
				)
				(arc
					(start 126.765558 -62.942978)
					(mid 127.241307 -63.000128)
					(end 126.765558 -63.057278)
				)
				(xy 126.671578 -63.057278)
				(arc
					(start 126.669292 -63.055246)
					(mid 126.583943 -63.011309)
					(end 126.540006 -62.92596)
				)
				(xy 126.537974 -62.923674) (xy 126.537974 -62.726316)
				(arc
					(start 126.539498 -62.724792)
					(mid 126.549066 -62.681961)
					(end 126.567184 -62.641988)
				)
				(arc
					(start 126.482602 -62.641988)
					(mid 126.467024 -62.694967)
					(end 126.461774 -62.749938)
				)
				(xy 126.461774 -62.923928)
				(arc
					(start 126.459742 -62.926214)
					(mid 126.415882 -63.011386)
					(end 126.33071 -63.055246)
				)
				(xy 126.328424 -63.057278)
				(arc
					(start 126.234444 -63.057278)
					(mid 125.758695 -63.000128)
					(end 126.234444 -62.942978)
				)
				(arc
					(start 126.304802 -62.942978)
					(mid 126.334976 -62.93048)
					(end 126.347474 -62.900306)
				)
				(xy 126.347474 -62.726316)
				(arc
					(start 126.348236 -62.725554)
					(mid 126.353015 -62.683402)
					(end 126.362206 -62.641988)
				)
			)
		)
	)
	(zone
		(layers "B.Cu" "In2.Cu")
		(hatch none 0.5)
		(connect_pads
			(clearance 0)
		)
		(min_thickness 0.25)
		(keepout
			(tracks not_allowed)
			(vias allowed)
			(pads allowed)
			(copperpour not_allowed)
			(footprints allowed)
		)
		(placement
			(enabled no)
			(sheetname "")
		)
		(fill yes
			(thermal_gap 0.5)
			(thermal_bridge_width 0.5)
			(island_removal_mode 0)
		)
		(polygon
			(pts
				(arc
					(start 170.600624 -23.11527)
					(mid 170.217084 -22.73173)
					(end 169.833544 -23.11527)
				)
				(arc
					(start 169.833544 -24.004016)
					(mid 170.215687 -24.387808)
					(end 170.600624 -24.00681)
				)
				(arc
					(start 170.483784 -24.00681)
					(mid 170.217084 -24.270982)
					(end 169.950384 -24.00681)
				)
				(arc
					(start 169.950384 -24.00427)
					(mid 170.217084 -23.73757)
					(end 170.483784 -24.00427)
				)
				(xy 170.600624 -24.00427) (xy 170.600624 -23.11781)
				(arc
					(start 170.483784 -23.11781)
					(mid 170.217084 -23.381982)
					(end 169.950384 -23.11781)
				)
				(arc
					(start 169.950384 -23.11527)
					(mid 170.217084 -22.84857)
					(end 170.483784 -23.11527)
				)
			)
		)
	)
	(zone
		(layers "B.Cu" "In2.Cu")
		(hatch none 0.5)
		(connect_pads
			(clearance 0)
		)
		(min_thickness 0.25)
		(keepout
			(tracks not_allowed)
			(vias allowed)
			(pads allowed)
			(copperpour not_allowed)
			(footprints allowed)
		)
		(placement
			(enabled no)
			(sheetname "")
		)
		(fill yes
			(thermal_gap 0.5)
			(thermal_bridge_width 0.5)
			(island_removal_mode 0)
		)
		(polygon
			(pts
				(arc
					(start 174.698406 -23.112476)
					(mid 174.314866 -22.728936)
					(end 173.931326 -23.112476)
				)
				(arc
					(start 173.931326 -24.001222)
					(mid 174.313469 -24.385014)
					(end 174.698406 -24.004016)
				)
				(arc
					(start 174.581566 -24.004016)
					(mid 174.314866 -24.268188)
					(end 174.048166 -24.004016)
				)
				(arc
					(start 174.048166 -24.001476)
					(mid 174.314866 -23.734776)
					(end 174.581566 -24.001476)
				)
				(xy 174.698406 -24.001476) (xy 174.698406 -23.115016)
				(arc
					(start 174.581566 -23.115016)
					(mid 174.314866 -23.379188)
					(end 174.048166 -23.115016)
				)
				(arc
					(start 174.048166 -23.112476)
					(mid 174.314866 -22.845776)
					(end 174.581566 -23.112476)
				)
			)
		)
	)
	(zone
		(layers "B.Cu" "In2.Cu")
		(hatch none 0.5)
		(connect_pads
			(clearance 0)
		)
		(min_thickness 0.25)
		(keepout
			(tracks not_allowed)
			(vias allowed)
			(pads allowed)
			(copperpour not_allowed)
			(footprints allowed)
		)
		(placement
			(enabled no)
			(sheetname "")
		)
		(fill yes
			(thermal_gap 0.5)
			(thermal_bridge_width 0.5)
			(island_removal_mode 0)
		)
		(polygon
			(pts
				(arc
					(start 130.000248 -61.64199)
					(mid 129.641854 -62.000003)
					(end 129.999994 -62.35827)
				)
				(arc
					(start 130.999992 -62.35827)
					(mid 131.252336 -62.25427)
					(end 131.358132 -62.00267)
				)
				(arc
					(start 131.241292 -62.00267)
					(mid 130.999992 -62.241443)
					(end 130.758692 -62.00267)
				)
				(arc
					(start 130.241294 -62.00267)
					(mid 129.999994 -62.241443)
					(end 129.758694 -62.00267)
				)
				(arc
					(start 129.758694 -62.00013)
					(mid 129.999994 -61.75883)
					(end 130.241294 -62.00013)
				)
				(arc
					(start 130.758692 -62.00013)
					(mid 130.999992 -61.75883)
					(end 131.241292 -62.00013)
				)
				(arc
					(start 131.358132 -62.00013)
					(mid 131.253235 -61.746887)
					(end 130.999992 -61.64199)
				)
			)
		)
	)
	(zone
		(layers "B.Cu" "In2.Cu")
		(hatch none 0.5)
		(connect_pads
			(clearance 0)
		)
		(min_thickness 0.25)
		(keepout
			(tracks not_allowed)
			(vias allowed)
			(pads allowed)
			(copperpour not_allowed)
			(footprints allowed)
		)
		(placement
			(enabled no)
			(sheetname "")
		)
		(fill yes
			(thermal_gap 0.5)
			(thermal_bridge_width 0.5)
			(island_removal_mode 0)
		)
		(polygon
			(pts
				(arc
					(start 118.358158 -52.00015)
					(mid 118.000018 -51.64201)
					(end 117.641878 -52.00015)
				)
				(arc
					(start 117.641878 -52.999894)
					(mid 117.998621 -53.358285)
					(end 118.358158 -53.002688)
				)
				(arc
					(start 118.241318 -53.002688)
					(mid 118.000018 -53.241461)
					(end 117.758718 -53.002688)
				)
				(arc
					(start 117.758718 -53.000148)
					(mid 118.000018 -52.758848)
					(end 118.241318 -53.000148)
				)
				(xy 118.358158 -53.000148) (xy 118.358158 -52.00269)
				(arc
					(start 118.241318 -52.00269)
					(mid 118.000018 -52.241463)
					(end 117.758718 -52.00269)
				)
				(arc
					(start 117.758718 -52.00015)
					(mid 118.000018 -51.75885)
					(end 118.241318 -52.00015)
				)
			)
		)
	)
	(zone
		(layers "B.Cu" "In2.Cu")
		(hatch none 0.5)
		(connect_pads
			(clearance 0)
		)
		(min_thickness 0.25)
		(keepout
			(tracks not_allowed)
			(vias allowed)
			(pads allowed)
			(copperpour not_allowed)
			(footprints allowed)
		)
		(placement
			(enabled no)
			(sheetname "")
		)
		(fill yes
			(thermal_gap 0.5)
			(thermal_bridge_width 0.5)
			(island_removal_mode 0)
		)
		(polygon
			(pts
				(arc
					(start 104.358186 -51.000152)
					(mid 104.000046 -50.642012)
					(end 103.641906 -51.000152)
				)
				(arc
					(start 103.641906 -51.999896)
					(mid 103.998649 -52.358287)
					(end 104.358186 -52.00269)
				)
				(arc
					(start 104.241346 -52.00269)
					(mid 104.000046 -52.241463)
					(end 103.758746 -52.00269)
				)
				(arc
					(start 103.758746 -52.00015)
					(mid 104.000046 -51.75885)
					(end 104.241346 -52.00015)
				)
				(xy 104.358186 -52.00015) (xy 104.358186 -51.002692)
				(arc
					(start 104.241346 -51.002692)
					(mid 104.000046 -51.241465)
					(end 103.758746 -51.002692)
				)
				(arc
					(start 103.758746 -51.000152)
					(mid 104.000046 -50.758852)
					(end 104.241346 -51.000152)
				)
			)
		)
	)
	(zone
		(layers "B.Cu" "In2.Cu")
		(hatch none 0.5)
		(connect_pads
			(clearance 0)
		)
		(min_thickness 0.25)
		(keepout
			(tracks not_allowed)
			(vias allowed)
			(pads allowed)
			(copperpour not_allowed)
			(footprints allowed)
		)
		(placement
			(enabled no)
			(sheetname "")
		)
		(fill yes
			(thermal_gap 0.5)
			(thermal_bridge_width 0.5)
			(island_removal_mode 0)
		)
		(polygon
			(pts
				(arc
					(start 121.358152 -51.000152)
					(mid 121.000012 -50.642012)
					(end 120.641872 -51.000152)
				)
				(arc
					(start 120.641872 -51.999896)
					(mid 120.998615 -52.358287)
					(end 121.358152 -52.00269)
				)
				(arc
					(start 121.241312 -52.00269)
					(mid 121.000012 -52.241463)
					(end 120.758712 -52.00269)
				)
				(arc
					(start 120.758712 -52.00015)
					(mid 121.000012 -51.75885)
					(end 121.241312 -52.00015)
				)
				(xy 121.358152 -52.00015) (xy 121.358152 -51.002692)
				(arc
					(start 121.241312 -51.002692)
					(mid 121.000012 -51.241465)
					(end 120.758712 -51.002692)
				)
				(arc
					(start 120.758712 -51.000152)
					(mid 121.000012 -50.758852)
					(end 121.241312 -51.000152)
				)
			)
		)
	)
	(zone
		(layers "B.Cu" "In2.Cu")
		(hatch none 0.5)
		(connect_pads
			(clearance 0)
		)
		(min_thickness 0.25)
		(keepout
			(tracks not_allowed)
			(vias allowed)
			(pads allowed)
			(copperpour not_allowed)
			(footprints allowed)
		)
		(placement
			(enabled no)
			(sheetname "")
		)
		(fill yes
			(thermal_gap 0.5)
			(thermal_bridge_width 0.5)
			(island_removal_mode 0)
		)
		(polygon
			(pts
				(arc
					(start 103.358188 -52.00015)
					(mid 103.000048 -51.64201)
					(end 102.641908 -52.00015)
				)
				(arc
					(start 102.641908 -52.999894)
					(mid 102.998651 -53.358285)
					(end 103.358188 -53.002688)
				)
				(arc
					(start 103.241348 -53.002688)
					(mid 103.000048 -53.241461)
					(end 102.758748 -53.002688)
				)
				(arc
					(start 102.758748 -53.000148)
					(mid 103.000048 -52.758848)
					(end 103.241348 -53.000148)
				)
				(xy 103.358188 -53.000148) (xy 103.358188 -52.00269)
				(arc
					(start 103.241348 -52.00269)
					(mid 103.000048 -52.241463)
					(end 102.758748 -52.00269)
				)
				(arc
					(start 102.758748 -52.00015)
					(mid 103.000048 -51.75885)
					(end 103.241348 -52.00015)
				)
			)
		)
	)
	(zone
		(layers "B.Cu" "In2.Cu")
		(hatch none 0.5)
		(connect_pads
			(clearance 0)
		)
		(min_thickness 0.25)
		(keepout
			(tracks not_allowed)
			(vias allowed)
			(pads allowed)
			(copperpour not_allowed)
			(footprints allowed)
		)
		(placement
			(enabled no)
			(sheetname "")
		)
		(fill yes
			(thermal_gap 0.5)
			(thermal_bridge_width 0.5)
			(island_removal_mode 0)
		)
		(polygon
			(pts
				(arc
					(start 106.358182 -51.000152)
					(mid 106.000042 -50.642012)
					(end 105.641902 -51.000152)
				)
				(arc
					(start 105.641902 -51.999896)
					(mid 105.998645 -52.358287)
					(end 106.358182 -52.00269)
				)
				(arc
					(start 106.241342 -52.00269)
					(mid 106.000042 -52.241463)
					(end 105.758742 -52.00269)
				)
				(arc
					(start 105.758742 -52.00015)
					(mid 106.000042 -51.75885)
					(end 106.241342 -52.00015)
				)
				(xy 106.358182 -52.00015) (xy 106.358182 -51.002692)
				(arc
					(start 106.241342 -51.002692)
					(mid 106.000042 -51.241465)
					(end 105.758742 -51.002692)
				)
				(arc
					(start 105.758742 -51.000152)
					(mid 106.000042 -50.758852)
					(end 106.241342 -51.000152)
				)
			)
		)
	)
	(zone
		(layers "B.Cu" "In2.Cu")
		(hatch none 0.5)
		(connect_pads
			(clearance 0)
		)
		(min_thickness 0.25)
		(keepout
			(tracks not_allowed)
			(vias allowed)
			(pads allowed)
			(copperpour not_allowed)
			(footprints allowed)
		)
		(placement
			(enabled no)
			(sheetname "")
		)
		(fill yes
			(thermal_gap 0.5)
			(thermal_bridge_width 0.5)
			(island_removal_mode 0)
		)
		(polygon
			(pts
				(arc
					(start 108.358178 -51.000152)
					(mid 108.000038 -50.642012)
					(end 107.641898 -51.000152)
				)
				(arc
					(start 107.641898 -51.999896)
					(mid 107.998641 -52.358287)
					(end 108.358178 -52.00269)
				)
				(arc
					(start 108.241338 -52.00269)
					(mid 108.000038 -52.241463)
					(end 107.758738 -52.00269)
				)
				(arc
					(start 107.758738 -52.00015)
					(mid 108.000038 -51.75885)
					(end 108.241338 -52.00015)
				)
				(xy 108.358178 -52.00015) (xy 108.358178 -51.002692)
				(arc
					(start 108.241338 -51.002692)
					(mid 108.000038 -51.241465)
					(end 107.758738 -51.002692)
				)
				(arc
					(start 107.758738 -51.000152)
					(mid 108.000038 -50.758852)
					(end 108.241338 -51.000152)
				)
			)
		)
	)
	(zone
		(layers "B.Cu" "In2.Cu")
		(hatch none 0.5)
		(connect_pads
			(clearance 0)
		)
		(min_thickness 0.25)
		(keepout
			(tracks not_allowed)
			(vias allowed)
			(pads allowed)
			(copperpour not_allowed)
			(footprints allowed)
		)
		(placement
			(enabled no)
			(sheetname "")
		)
		(fill yes
			(thermal_gap 0.5)
			(thermal_bridge_width 0.5)
			(island_removal_mode 0)
		)
		(polygon
			(pts
				(arc
					(start 105.358184 -52.00015)
					(mid 105.000044 -51.64201)
					(end 104.641904 -52.00015)
				)
				(arc
					(start 104.641904 -52.999894)
					(mid 104.998647 -53.358285)
					(end 105.358184 -53.002688)
				)
				(arc
					(start 105.241344 -53.002688)
					(mid 105.000044 -53.241461)
					(end 104.758744 -53.002688)
				)
				(arc
					(start 104.758744 -53.000148)
					(mid 105.000044 -52.758848)
					(end 105.241344 -53.000148)
				)
				(xy 105.358184 -53.000148) (xy 105.358184 -52.00269)
				(arc
					(start 105.241344 -52.00269)
					(mid 105.000044 -52.241463)
					(end 104.758744 -52.00269)
				)
				(arc
					(start 104.758744 -52.00015)
					(mid 105.000044 -51.75885)
					(end 105.241344 -52.00015)
				)
			)
		)
	)
	(zone
		(layers "B.Cu" "In2.Cu")
		(hatch none 0.5)
		(connect_pads
			(clearance 0)
		)
		(min_thickness 0.25)
		(keepout
			(tracks not_allowed)
			(vias allowed)
			(pads allowed)
			(copperpour not_allowed)
			(footprints allowed)
		)
		(placement
			(enabled no)
			(sheetname "")
		)
		(fill yes
			(thermal_gap 0.5)
			(thermal_bridge_width 0.5)
			(island_removal_mode 0)
		)
		(polygon
			(pts
				(arc
					(start 176.75225 -23.103332)
					(mid 176.36871 -22.719792)
					(end 175.98517 -23.103332)
				)
				(arc
					(start 175.98517 -23.992078)
					(mid 176.367313 -24.37587)
					(end 176.75225 -23.994872)
				)
				(arc
					(start 176.63541 -23.994872)
					(mid 176.36871 -24.259044)
					(end 176.10201 -23.994872)
				)
				(arc
					(start 176.10201 -23.992332)
					(mid 176.36871 -23.725632)
					(end 176.63541 -23.992332)
				)
				(xy 176.75225 -23.992332) (xy 176.75225 -23.105872)
				(arc
					(start 176.63541 -23.105872)
					(mid 176.36871 -23.370044)
					(end 176.10201 -23.105872)
				)
				(arc
					(start 176.10201 -23.103332)
					(mid 176.36871 -22.836632)
					(end 176.63541 -23.103332)
				)
			)
		)
	)
	(zone
		(layers "B.Cu" "In2.Cu")
		(hatch none 0.5)
		(connect_pads
			(clearance 0)
		)
		(min_thickness 0.25)
		(keepout
			(tracks not_allowed)
			(vias allowed)
			(pads allowed)
			(copperpour not_allowed)
			(footprints allowed)
		)
		(placement
			(enabled no)
			(sheetname "")
		)
		(fill yes
			(thermal_gap 0.5)
			(thermal_bridge_width 0.5)
			(island_removal_mode 0)
		)
		(polygon
			(pts
				(arc
					(start 178.790854 -23.11654)
					(mid 178.407314 -22.733)
					(end 178.023774 -23.11654)
				)
				(arc
					(start 178.023774 -24.005286)
					(mid 178.405917 -24.389078)
					(end 178.790854 -24.00808)
				)
				(arc
					(start 178.674014 -24.00808)
					(mid 178.407314 -24.272252)
					(end 178.140614 -24.00808)
				)
				(arc
					(start 178.140614 -24.00554)
					(mid 178.407314 -23.73884)
					(end 178.674014 -24.00554)
				)
				(xy 178.790854 -24.00554) (xy 178.790854 -23.11908)
				(arc
					(start 178.674014 -23.11908)
					(mid 178.407314 -23.383252)
					(end 178.140614 -23.11908)
				)
				(arc
					(start 178.140614 -23.11654)
					(mid 178.407314 -22.84984)
					(end 178.674014 -23.11654)
				)
			)
		)
	)
	(zone
		(layers "B.Cu" "In2.Cu")
		(hatch none 0.5)
		(connect_pads
			(clearance 0)
		)
		(min_thickness 0.25)
		(keepout
			(tracks not_allowed)
			(vias allowed)
			(pads allowed)
			(copperpour not_allowed)
			(footprints allowed)
		)
		(placement
			(enabled no)
			(sheetname "")
		)
		(fill yes
			(thermal_gap 0.5)
			(thermal_bridge_width 0.5)
			(island_removal_mode 0)
		)
		(polygon
			(pts
				(arc
					(start 129.00025 -71.64197)
					(mid 128.641856 -71.999983)
					(end 128.999996 -72.35825)
				)
				(arc
					(start 129.999994 -72.35825)
					(mid 130.252338 -72.25425)
					(end 130.358134 -72.00265)
				)
				(arc
					(start 130.241294 -72.00265)
					(mid 129.999994 -72.241423)
					(end 129.758694 -72.00265)
				)
				(arc
					(start 129.241296 -72.00265)
					(mid 128.999996 -72.241423)
					(end 128.758696 -72.00265)
				)
				(arc
					(start 128.758696 -72.00011)
					(mid 128.999996 -71.75881)
					(end 129.241296 -72.00011)
				)
				(arc
					(start 129.758694 -72.00011)
					(mid 129.999994 -71.75881)
					(end 130.241294 -72.00011)
				)
				(arc
					(start 130.358134 -72.00011)
					(mid 130.253237 -71.746867)
					(end 129.999994 -71.64197)
				)
			)
		)
	)
	(zone
		(layers "B.Cu" "In2.Cu")
		(hatch none 0.5)
		(connect_pads
			(clearance 0)
		)
		(min_thickness 0.25)
		(keepout
			(tracks not_allowed)
			(vias allowed)
			(pads allowed)
			(copperpour not_allowed)
			(footprints allowed)
		)
		(placement
			(enabled no)
			(sheetname "")
		)
		(fill yes
			(thermal_gap 0.5)
			(thermal_bridge_width 0.5)
			(island_removal_mode 0)
		)
		(polygon
			(pts
				(arc
					(start 122.35815 -52.00015)
					(mid 122.00001 -51.64201)
					(end 121.64187 -52.00015)
				)
				(arc
					(start 121.64187 -52.999894)
					(mid 121.998613 -53.358285)
					(end 122.35815 -53.002688)
				)
				(arc
					(start 122.24131 -53.002688)
					(mid 122.00001 -53.241461)
					(end 121.75871 -53.002688)
				)
				(arc
					(start 121.75871 -53.000148)
					(mid 122.00001 -52.758848)
					(end 122.24131 -53.000148)
				)
				(xy 122.35815 -53.000148) (xy 122.35815 -52.00269)
				(arc
					(start 122.24131 -52.00269)
					(mid 122.00001 -52.241463)
					(end 121.75871 -52.00269)
				)
				(arc
					(start 121.75871 -52.00015)
					(mid 122.00001 -51.75885)
					(end 122.24131 -52.00015)
				)
			)
		)
	)
	(zone
		(layers "B.Cu" "In2.Cu")
		(hatch none 0.5)
		(connect_pads
			(clearance 0)
		)
		(min_thickness 0.25)
		(keepout
			(tracks not_allowed)
			(vias allowed)
			(pads allowed)
			(copperpour not_allowed)
			(footprints allowed)
		)
		(placement
			(enabled no)
			(sheetname "")
		)
		(fill yes
			(thermal_gap 0.5)
			(thermal_bridge_width 0.5)
			(island_removal_mode 0)
		)
		(polygon
			(pts
				(arc
					(start 130.000248 -65.641982)
					(mid 129.641854 -65.999995)
					(end 129.999994 -66.358262)
				)
				(arc
					(start 130.999992 -66.358262)
					(mid 131.252336 -66.254262)
					(end 131.358132 -66.002662)
				)
				(arc
					(start 131.241292 -66.002662)
					(mid 130.999992 -66.241435)
					(end 130.758692 -66.002662)
				)
				(arc
					(start 130.241294 -66.002662)
					(mid 129.999994 -66.241435)
					(end 129.758694 -66.002662)
				)
				(arc
					(start 129.758694 -66.000122)
					(mid 129.999994 -65.758822)
					(end 130.241294 -66.000122)
				)
				(arc
					(start 130.758692 -66.000122)
					(mid 130.999992 -65.758822)
					(end 131.241292 -66.000122)
				)
				(arc
					(start 131.358132 -66.000122)
					(mid 131.253235 -65.746879)
					(end 130.999992 -65.641982)
				)
			)
		)
	)
	(zone
		(layers "B.Cu" "In2.Cu")
		(hatch none 0.5)
		(connect_pads
			(clearance 0)
		)
		(min_thickness 0.25)
		(keepout
			(tracks not_allowed)
			(vias allowed)
			(pads allowed)
			(copperpour not_allowed)
			(footprints allowed)
		)
		(placement
			(enabled no)
			(sheetname "")
		)
		(fill yes
			(thermal_gap 0.5)
			(thermal_bridge_width 0.5)
			(island_removal_mode 0)
		)
		(polygon
			(pts
				(arc
					(start 102.35819 -51.000152)
					(mid 102.00005 -50.642012)
					(end 101.64191 -51.000152)
				)
				(arc
					(start 101.64191 -51.999896)
					(mid 101.998653 -52.358287)
					(end 102.35819 -52.00269)
				)
				(arc
					(start 102.24135 -52.00269)
					(mid 102.00005 -52.241463)
					(end 101.75875 -52.00269)
				)
				(arc
					(start 101.75875 -52.00015)
					(mid 102.00005 -51.75885)
					(end 102.24135 -52.00015)
				)
				(xy 102.35819 -52.00015) (xy 102.35819 -51.002692)
				(arc
					(start 102.24135 -51.002692)
					(mid 102.00005 -51.241465)
					(end 101.75875 -51.002692)
				)
				(arc
					(start 101.75875 -51.000152)
					(mid 102.00005 -50.758852)
					(end 102.24135 -51.000152)
				)
			)
		)
	)
	(zone
		(layers "B.Cu" "In2.Cu")
		(hatch none 0.5)
		(connect_pads
			(clearance 0)
		)
		(min_thickness 0.25)
		(keepout
			(tracks not_allowed)
			(vias allowed)
			(pads allowed)
			(copperpour not_allowed)
			(footprints allowed)
		)
		(placement
			(enabled no)
			(sheetname "")
		)
		(fill yes
			(thermal_gap 0.5)
			(thermal_bridge_width 0.5)
			(island_removal_mode 0)
		)
		(polygon
			(pts
				(arc
					(start 129.00025 -60.641992)
					(mid 128.641856 -61.000005)
					(end 128.999996 -61.358272)
				)
				(arc
					(start 129.999994 -61.358272)
					(mid 130.252338 -61.254272)
					(end 130.358134 -61.002672)
				)
				(arc
					(start 130.241294 -61.002672)
					(mid 129.999994 -61.241445)
					(end 129.758694 -61.002672)
				)
				(arc
					(start 129.241296 -61.002672)
					(mid 128.999996 -61.241445)
					(end 128.758696 -61.002672)
				)
				(arc
					(start 128.758696 -61.000132)
					(mid 128.999996 -60.758832)
					(end 129.241296 -61.000132)
				)
				(arc
					(start 129.758694 -61.000132)
					(mid 129.999994 -60.758832)
					(end 130.241294 -61.000132)
				)
				(arc
					(start 130.358134 -61.000132)
					(mid 130.253237 -60.746889)
					(end 129.999994 -60.641992)
				)
			)
		)
	)
	(zone
		(layers "B.Cu" "In2.Cu")
		(hatch none 0.5)
		(connect_pads
			(clearance 0)
		)
		(min_thickness 0.25)
		(keepout
			(tracks not_allowed)
			(vias allowed)
			(pads allowed)
			(copperpour not_allowed)
			(footprints allowed)
		)
		(placement
			(enabled no)
			(sheetname "")
		)
		(fill yes
			(thermal_gap 0.5)
			(thermal_bridge_width 0.5)
			(island_removal_mode 0)
		)
		(polygon
			(pts
				(arc
					(start 109.358176 -52.00015)
					(mid 109.000036 -51.64201)
					(end 108.641896 -52.00015)
				)
				(arc
					(start 108.641896 -52.999894)
					(mid 108.998639 -53.358285)
					(end 109.358176 -53.002688)
				)
				(arc
					(start 109.241336 -53.002688)
					(mid 109.000036 -53.241461)
					(end 108.758736 -53.002688)
				)
				(arc
					(start 108.758736 -53.000148)
					(mid 109.000036 -52.758848)
					(end 109.241336 -53.000148)
				)
				(xy 109.358176 -53.000148) (xy 109.358176 -52.00269)
				(arc
					(start 109.241336 -52.00269)
					(mid 109.000036 -52.241463)
					(end 108.758736 -52.00269)
				)
				(arc
					(start 108.758736 -52.00015)
					(mid 109.000036 -51.75885)
					(end 109.241336 -52.00015)
				)
			)
		)
	)
	(zone
		(layers "B.Cu" "In2.Cu")
		(hatch none 0.5)
		(connect_pads
			(clearance 0)
		)
		(min_thickness 0.25)
		(keepout
			(tracks not_allowed)
			(vias allowed)
			(pads allowed)
			(copperpour not_allowed)
			(footprints allowed)
		)
		(placement
			(enabled no)
			(sheetname "")
		)
		(fill yes
			(thermal_gap 0.5)
			(thermal_bridge_width 0.5)
			(island_removal_mode 0)
		)
		(polygon
			(pts
				(arc
					(start 113.358168 -52.00015)
					(mid 113.000028 -51.64201)
					(end 112.641888 -52.00015)
				)
				(arc
					(start 112.641888 -52.999894)
					(mid 112.998631 -53.358285)
					(end 113.358168 -53.002688)
				)
				(arc
					(start 113.241328 -53.002688)
					(mid 113.000028 -53.241461)
					(end 112.758728 -53.002688)
				)
				(arc
					(start 112.758728 -53.000148)
					(mid 113.000028 -52.758848)
					(end 113.241328 -53.000148)
				)
				(xy 113.358168 -53.000148) (xy 113.358168 -52.00269)
				(arc
					(start 113.241328 -52.00269)
					(mid 113.000028 -52.241463)
					(end 112.758728 -52.00269)
				)
				(arc
					(start 112.758728 -52.00015)
					(mid 113.000028 -51.75885)
					(end 113.241328 -52.00015)
				)
			)
		)
	)
	(zone
		(layers "B.Cu" "In2.Cu")
		(hatch none 0.5)
		(connect_pads
			(clearance 0)
		)
		(min_thickness 0.25)
		(keepout
			(tracks not_allowed)
			(vias allowed)
			(pads allowed)
			(copperpour not_allowed)
			(footprints allowed)
		)
		(placement
			(enabled no)
			(sheetname "")
		)
		(fill yes
			(thermal_gap 0.5)
			(thermal_bridge_width 0.5)
			(island_removal_mode 0)
		)
		(polygon
			(pts
				(arc
					(start 172.65269 -23.112984)
					(mid 172.26915 -22.729444)
					(end 171.88561 -23.112984)
				)
				(arc
					(start 171.88561 -24.00173)
					(mid 172.267753 -24.385522)
					(end 172.65269 -24.004524)
				)
				(arc
					(start 172.53585 -24.004524)
					(mid 172.26915 -24.268696)
					(end 172.00245 -24.004524)
				)
				(arc
					(start 172.00245 -24.001984)
					(mid 172.26915 -23.735284)
					(end 172.53585 -24.001984)
				)
				(xy 172.65269 -24.001984) (xy 172.65269 -23.115524)
				(arc
					(start 172.53585 -23.115524)
					(mid 172.26915 -23.379696)
					(end 172.00245 -23.115524)
				)
				(arc
					(start 172.00245 -23.112984)
					(mid 172.26915 -22.846284)
					(end 172.53585 -23.112984)
				)
			)
		)
	)
	(zone
		(layers "B.Cu" "In2.Cu")
		(hatch none 0.5)
		(connect_pads
			(clearance 0)
		)
		(min_thickness 0.25)
		(keepout
			(tracks not_allowed)
			(vias allowed)
			(pads allowed)
			(copperpour not_allowed)
			(footprints allowed)
		)
		(placement
			(enabled no)
			(sheetname "")
		)
		(fill yes
			(thermal_gap 0.5)
			(thermal_bridge_width 0.5)
			(island_removal_mode 0)
		)
		(polygon
			(pts
				(arc
					(start 129.00025 -64.641984)
					(mid 128.641856 -64.999997)
					(end 128.999996 -65.358264)
				)
				(arc
					(start 129.999994 -65.358264)
					(mid 130.252338 -65.254264)
					(end 130.358134 -65.002664)
				)
				(arc
					(start 130.241294 -65.002664)
					(mid 129.999994 -65.241437)
					(end 129.758694 -65.002664)
				)
				(arc
					(start 129.241296 -65.002664)
					(mid 128.999996 -65.241437)
					(end 128.758696 -65.002664)
				)
				(arc
					(start 128.758696 -65.000124)
					(mid 128.999996 -64.758824)
					(end 129.241296 -65.000124)
				)
				(arc
					(start 129.758694 -65.000124)
					(mid 129.999994 -64.758824)
					(end 130.241294 -65.000124)
				)
				(arc
					(start 130.358134 -65.000124)
					(mid 130.253237 -64.746881)
					(end 129.999994 -64.641984)
				)
			)
		)
	)
	(zone
		(layers "B.Cu" "In2.Cu")
		(hatch none 0.5)
		(connect_pads
			(clearance 0)
		)
		(min_thickness 0.25)
		(keepout
			(tracks not_allowed)
			(vias allowed)
			(pads allowed)
			(copperpour not_allowed)
			(footprints allowed)
		)
		(placement
			(enabled no)
			(sheetname "")
		)
		(fill yes
			(thermal_gap 0.5)
			(thermal_bridge_width 0.5)
			(island_removal_mode 0)
		)
		(polygon
			(pts
				(arc
					(start 114.358166 -51.000152)
					(mid 114.000026 -50.642012)
					(end 113.641886 -51.000152)
				)
				(arc
					(start 113.641886 -51.999896)
					(mid 113.998629 -52.358287)
					(end 114.358166 -52.00269)
				)
				(arc
					(start 114.241326 -52.00269)
					(mid 114.000026 -52.241463)
					(end 113.758726 -52.00269)
				)
				(arc
					(start 113.758726 -52.00015)
					(mid 114.000026 -51.75885)
					(end 114.241326 -52.00015)
				)
				(xy 114.358166 -52.00015) (xy 114.358166 -51.002692)
				(arc
					(start 114.241326 -51.002692)
					(mid 114.000026 -51.241465)
					(end 113.758726 -51.002692)
				)
				(arc
					(start 113.758726 -51.000152)
					(mid 114.000026 -50.758852)
					(end 114.241326 -51.000152)
				)
			)
		)
	)
	(zone
		(layers "B.Cu" "In2.Cu")
		(hatch none 0.5)
		(connect_pads
			(clearance 0)
		)
		(min_thickness 0.25)
		(keepout
			(tracks not_allowed)
			(vias allowed)
			(pads allowed)
			(copperpour not_allowed)
			(footprints allowed)
		)
		(placement
			(enabled no)
			(sheetname "")
		)
		(fill yes
			(thermal_gap 0.5)
			(thermal_bridge_width 0.5)
			(island_removal_mode 0)
		)
		(polygon
			(pts
				(arc
					(start 130.000248 -63.641986)
					(mid 129.641854 -63.999999)
					(end 129.999994 -64.358266)
				)
				(arc
					(start 130.999992 -64.358266)
					(mid 131.252336 -64.254266)
					(end 131.358132 -64.002666)
				)
				(arc
					(start 131.241292 -64.002666)
					(mid 130.999992 -64.241439)
					(end 130.758692 -64.002666)
				)
				(arc
					(start 130.241294 -64.002666)
					(mid 129.999994 -64.241439)
					(end 129.758694 -64.002666)
				)
				(arc
					(start 129.758694 -64.000126)
					(mid 129.999994 -63.758826)
					(end 130.241294 -64.000126)
				)
				(arc
					(start 130.758692 -64.000126)
					(mid 130.999992 -63.758826)
					(end 131.241292 -64.000126)
				)
				(arc
					(start 131.358132 -64.000126)
					(mid 131.253235 -63.746883)
					(end 130.999992 -63.641986)
				)
			)
		)
	)
	(zone
		(layers "B.Cu" "In2.Cu")
		(hatch none 0.5)
		(connect_pads
			(clearance 0)
		)
		(min_thickness 0.25)
		(keepout
			(tracks not_allowed)
			(vias allowed)
			(pads allowed)
			(copperpour not_allowed)
			(footprints allowed)
		)
		(placement
			(enabled no)
			(sheetname "")
		)
		(fill yes
			(thermal_gap 0.5)
			(thermal_bridge_width 0.5)
			(island_removal_mode 0)
		)
		(polygon
			(pts
				(arc
					(start 112.35817 -51.000152)
					(mid 112.00003 -50.642012)
					(end 111.64189 -51.000152)
				)
				(arc
					(start 111.64189 -51.999896)
					(mid 111.998633 -52.358287)
					(end 112.35817 -52.00269)
				)
				(arc
					(start 112.24133 -52.00269)
					(mid 112.00003 -52.241463)
					(end 111.75873 -52.00269)
				)
				(arc
					(start 111.75873 -52.00015)
					(mid 112.00003 -51.75885)
					(end 112.24133 -52.00015)
				)
				(xy 112.35817 -52.00015) (xy 112.35817 -51.002692)
				(arc
					(start 112.24133 -51.002692)
					(mid 112.00003 -51.241465)
					(end 111.75873 -51.002692)
				)
				(arc
					(start 111.75873 -51.000152)
					(mid 112.00003 -50.758852)
					(end 112.24133 -51.000152)
				)
			)
		)
	)
	(zone
		(layers "B.Cu" "In2.Cu")
		(hatch none 0.5)
		(connect_pads
			(clearance 0)
		)
		(min_thickness 0.25)
		(keepout
			(tracks not_allowed)
			(vias allowed)
			(pads allowed)
			(copperpour not_allowed)
			(footprints allowed)
		)
		(placement
			(enabled no)
			(sheetname "")
		)
		(fill yes
			(thermal_gap 0.5)
			(thermal_bridge_width 0.5)
			(island_removal_mode 0)
		)
		(polygon
			(pts
				(arc
					(start 129.00025 -69.641974)
					(mid 128.641856 -69.999987)
					(end 128.999996 -70.358254)
				)
				(arc
					(start 129.999994 -70.358254)
					(mid 130.252338 -70.254254)
					(end 130.358134 -70.002654)
				)
				(arc
					(start 130.241294 -70.002654)
					(mid 129.999994 -70.241427)
					(end 129.758694 -70.002654)
				)
				(arc
					(start 129.241296 -70.002654)
					(mid 128.999996 -70.241427)
					(end 128.758696 -70.002654)
				)
				(arc
					(start 128.758696 -70.000114)
					(mid 128.999996 -69.758814)
					(end 129.241296 -70.000114)
				)
				(arc
					(start 129.758694 -70.000114)
					(mid 129.999994 -69.758814)
					(end 130.241294 -70.000114)
				)
				(arc
					(start 130.358134 -70.000114)
					(mid 130.253237 -69.746871)
					(end 129.999994 -69.641974)
				)
			)
		)
	)
	(zone
		(layers "B.Cu" "In2.Cu")
		(hatch none 0.5)
		(connect_pads
			(clearance 0)
		)
		(min_thickness 0.25)
		(keepout
			(tracks not_allowed)
			(vias allowed)
			(pads allowed)
			(copperpour not_allowed)
			(footprints allowed)
		)
		(placement
			(enabled no)
			(sheetname "")
		)
		(fill yes
			(thermal_gap 0.5)
			(thermal_bridge_width 0.5)
			(island_removal_mode 0)
		)
		(polygon
			(pts
				(arc
					(start 100.358194 -51.000152)
					(mid 100.000054 -50.642012)
					(end 99.641914 -51.000152)
				)
				(arc
					(start 99.641914 -51.999896)
					(mid 99.998657 -52.358287)
					(end 100.358194 -52.00269)
				)
				(arc
					(start 100.241354 -52.00269)
					(mid 100.000054 -52.241463)
					(end 99.758754 -52.00269)
				)
				(arc
					(start 99.758754 -52.00015)
					(mid 100.000054 -51.75885)
					(end 100.241354 -52.00015)
				)
				(xy 100.358194 -52.00015) (xy 100.358194 -51.002692)
				(arc
					(start 100.241354 -51.002692)
					(mid 100.000054 -51.241465)
					(end 99.758754 -51.002692)
				)
				(arc
					(start 99.758754 -51.000152)
					(mid 100.000054 -50.758852)
					(end 100.241354 -51.000152)
				)
			)
		)
	)
	(zone
		(layers "B.Cu" "In2.Cu")
		(hatch none 0.5)
		(connect_pads
			(clearance 0)
		)
		(min_thickness 0.25)
		(keepout
			(tracks not_allowed)
			(vias allowed)
			(pads allowed)
			(copperpour not_allowed)
			(footprints allowed)
		)
		(placement
			(enabled no)
			(sheetname "")
		)
		(fill yes
			(thermal_gap 0.5)
			(thermal_bridge_width 0.5)
			(island_removal_mode 0)
		)
		(polygon
			(pts
				(arc
					(start 129.00025 -62.641988)
					(mid 128.641856 -63.000001)
					(end 128.999996 -63.358268)
				)
				(arc
					(start 129.999994 -63.358268)
					(mid 130.252338 -63.254268)
					(end 130.358134 -63.002668)
				)
				(arc
					(start 130.241294 -63.002668)
					(mid 129.999994 -63.241441)
					(end 129.758694 -63.002668)
				)
				(arc
					(start 129.241296 -63.002668)
					(mid 128.999996 -63.241441)
					(end 128.758696 -63.002668)
				)
				(arc
					(start 128.758696 -63.000128)
					(mid 128.999996 -62.758828)
					(end 129.241296 -63.000128)
				)
				(arc
					(start 129.758694 -63.000128)
					(mid 129.999994 -62.758828)
					(end 130.241294 -63.000128)
				)
				(arc
					(start 130.358134 -63.000128)
					(mid 130.253237 -62.746885)
					(end 129.999994 -62.641988)
				)
			)
		)
	)
	(zone
		(layers "B.Cu" "In2.Cu")
		(hatch none 0.5)
		(connect_pads
			(clearance 0)
		)
		(min_thickness 0.25)
		(keepout
			(tracks not_allowed)
			(vias allowed)
			(pads allowed)
			(copperpour not_allowed)
			(footprints allowed)
		)
		(placement
			(enabled no)
			(sheetname "")
		)
		(fill yes
			(thermal_gap 0.5)
			(thermal_bridge_width 0.5)
			(island_removal_mode 0)
		)
		(polygon
			(pts
				(xy 138.500866 -79.813912) (xy 138.500612 -79.814166)
				(arc
					(start 138.500612 -79.814674)
					(mid 138.117834 -80.197452)
					(end 138.500612 -80.58023)
				)
				(xy 138.500612 -80.580992) (xy 139.643612 -80.580992)
				(arc
					(start 139.643612 -80.58023)
					(mid 139.913377 -80.469013)
					(end 140.02639 -80.199992)
				)
				(arc
					(start 139.910312 -80.199992)
					(mid 139.643612 -80.464164)
					(end 139.376912 -80.199992)
				)
				(arc
					(start 138.767312 -80.199992)
					(mid 138.500612 -80.464164)
					(end 138.233912 -80.199992)
				)
				(arc
					(start 138.233912 -80.197452)
					(mid 138.500612 -79.930752)
					(end 138.767312 -80.197452)
				)
				(arc
					(start 139.376912 -80.197452)
					(mid 139.643612 -79.930752)
					(end 139.910312 -80.197452)
				)
				(arc
					(start 140.02639 -80.197452)
					(mid 139.914277 -79.926787)
					(end 139.643612 -79.814674)
				)
				(xy 139.643612 -79.813912)
			)
		)
	)
	(zone
		(layers "B.Cu" "In2.Cu")
		(hatch none 0.5)
		(connect_pads
			(clearance 0)
		)
		(min_thickness 0.25)
		(keepout
			(tracks not_allowed)
			(vias allowed)
			(pads allowed)
			(copperpour not_allowed)
			(footprints allowed)
		)
		(placement
			(enabled no)
			(sheetname "")
		)
		(fill yes
			(thermal_gap 0.5)
			(thermal_bridge_width 0.5)
			(island_removal_mode 0)
		)
		(polygon
			(pts
				(arc
					(start 130.000248 -70.641972)
					(mid 129.641854 -70.999985)
					(end 129.999994 -71.358252)
				)
				(arc
					(start 130.999992 -71.358252)
					(mid 131.252336 -71.254252)
					(end 131.358132 -71.002652)
				)
				(arc
					(start 131.241292 -71.002652)
					(mid 130.999992 -71.241425)
					(end 130.758692 -71.002652)
				)
				(arc
					(start 130.241294 -71.002652)
					(mid 129.999994 -71.241425)
					(end 129.758694 -71.002652)
				)
				(arc
					(start 129.758694 -71.000112)
					(mid 129.999994 -70.758812)
					(end 130.241294 -71.000112)
				)
				(arc
					(start 130.758692 -71.000112)
					(mid 130.999992 -70.758812)
					(end 131.241292 -71.000112)
				)
				(arc
					(start 131.358132 -71.000112)
					(mid 131.253235 -70.746869)
					(end 130.999992 -70.641972)
				)
			)
		)
	)
	(zone
		(layers "B.Cu" "In2.Cu")
		(hatch none 0.5)
		(connect_pads
			(clearance 0)
		)
		(min_thickness 0.25)
		(keepout
			(tracks not_allowed)
			(vias allowed)
			(pads allowed)
			(copperpour not_allowed)
			(footprints allowed)
		)
		(placement
			(enabled no)
			(sheetname "")
		)
		(fill yes
			(thermal_gap 0.5)
			(thermal_bridge_width 0.5)
			(island_removal_mode 0)
		)
		(polygon
			(pts
				(arc
					(start 129.00025 -67.641978)
					(mid 128.641856 -67.999991)
					(end 128.999996 -68.358258)
				)
				(arc
					(start 129.999994 -68.358258)
					(mid 130.252338 -68.254258)
					(end 130.358134 -68.002658)
				)
				(arc
					(start 130.241294 -68.002658)
					(mid 129.999994 -68.241431)
					(end 129.758694 -68.002658)
				)
				(arc
					(start 129.241296 -68.002658)
					(mid 128.999996 -68.241431)
					(end 128.758696 -68.002658)
				)
				(arc
					(start 128.758696 -68.000118)
					(mid 128.999996 -67.758818)
					(end 129.241296 -68.000118)
				)
				(arc
					(start 129.758694 -68.000118)
					(mid 129.999994 -67.758818)
					(end 130.241294 -68.000118)
				)
				(arc
					(start 130.358134 -68.000118)
					(mid 130.253237 -67.746875)
					(end 129.999994 -67.641978)
				)
			)
		)
	)
	(zone
		(layers "B.Cu" "In2.Cu")
		(hatch none 0.5)
		(connect_pads
			(clearance 0)
		)
		(min_thickness 0.25)
		(keepout
			(tracks not_allowed)
			(vias allowed)
			(pads allowed)
			(copperpour not_allowed)
			(footprints allowed)
		)
		(placement
			(enabled no)
			(sheetname "")
		)
		(fill yes
			(thermal_gap 0.5)
			(thermal_bridge_width 0.5)
			(island_removal_mode 0)
		)
		(polygon
			(pts
				(arc
					(start 180.819552 -23.596346)
					(mid 180.436012 -23.212806)
					(end 180.052472 -23.596346)
				)
				(arc
					(start 180.052472 -24.485092)
					(mid 180.434615 -24.868884)
					(end 180.819552 -24.487886)
				)
				(arc
					(start 180.702712 -24.487886)
					(mid 180.436012 -24.752058)
					(end 180.169312 -24.487886)
				)
				(arc
					(start 180.169312 -24.485346)
					(mid 180.436012 -24.218646)
					(end 180.702712 -24.485346)
				)
				(xy 180.819552 -24.485346) (xy 180.819552 -23.598886)
				(arc
					(start 180.702712 -23.598886)
					(mid 180.436012 -23.863058)
					(end 180.169312 -23.598886)
				)
				(arc
					(start 180.169312 -23.596346)
					(mid 180.436012 -23.329646)
					(end 180.702712 -23.596346)
				)
			)
		)
	)
	(zone
		(layers "B.Cu" "In2.Cu")
		(hatch none 0.5)
		(connect_pads
			(clearance 0)
		)
		(min_thickness 0.25)
		(keepout
			(tracks not_allowed)
			(vias allowed)
			(pads allowed)
			(copperpour not_allowed)
			(footprints allowed)
		)
		(placement
			(enabled no)
			(sheetname "")
		)
		(fill yes
			(thermal_gap 0.5)
			(thermal_bridge_width 0.5)
			(island_removal_mode 0)
		)
		(polygon
			(pts
				(arc
					(start 110.358174 -51.000152)
					(mid 110.000034 -50.642012)
					(end 109.641894 -51.000152)
				)
				(arc
					(start 109.641894 -51.999896)
					(mid 109.998637 -52.358287)
					(end 110.358174 -52.00269)
				)
				(arc
					(start 110.241334 -52.00269)
					(mid 110.000034 -52.241463)
					(end 109.758734 -52.00269)
				)
				(arc
					(start 109.758734 -52.00015)
					(mid 110.000034 -51.75885)
					(end 110.241334 -52.00015)
				)
				(xy 110.358174 -52.00015) (xy 110.358174 -51.002692)
				(arc
					(start 110.241334 -51.002692)
					(mid 110.000034 -51.241465)
					(end 109.758734 -51.002692)
				)
				(arc
					(start 109.758734 -51.000152)
					(mid 110.000034 -50.758852)
					(end 110.241334 -51.000152)
				)
			)
		)
	)
	(zone
		(layers "B.Cu" "In2.Cu")
		(hatch none 0.5)
		(connect_pads
			(clearance 0)
		)
		(min_thickness 0.25)
		(keepout
			(tracks not_allowed)
			(vias allowed)
			(pads allowed)
			(copperpour not_allowed)
			(footprints allowed)
		)
		(placement
			(enabled no)
			(sheetname "")
		)
		(fill yes
			(thermal_gap 0.5)
			(thermal_bridge_width 0.5)
			(island_removal_mode 0)
		)
		(polygon
			(pts
				(arc
					(start 111.358172 -52.00015)
					(mid 111.000032 -51.64201)
					(end 110.641892 -52.00015)
				)
				(arc
					(start 110.641892 -52.999894)
					(mid 110.998635 -53.358285)
					(end 111.358172 -53.002688)
				)
				(arc
					(start 111.241332 -53.002688)
					(mid 111.000032 -53.241461)
					(end 110.758732 -53.002688)
				)
				(arc
					(start 110.758732 -53.000148)
					(mid 111.000032 -52.758848)
					(end 111.241332 -53.000148)
				)
				(xy 111.358172 -53.000148) (xy 111.358172 -52.00269)
				(arc
					(start 111.241332 -52.00269)
					(mid 111.000032 -52.241463)
					(end 110.758732 -52.00269)
				)
				(arc
					(start 110.758732 -52.00015)
					(mid 111.000032 -51.75885)
					(end 111.241332 -52.00015)
				)
			)
		)
	)
	(zone
		(layers "B.Cu" "In2.Cu")
		(hatch none 0.5)
		(connect_pads
			(clearance 0)
		)
		(min_thickness 0.25)
		(keepout
			(tracks not_allowed)
			(vias allowed)
			(pads allowed)
			(copperpour not_allowed)
			(footprints allowed)
		)
		(placement
			(enabled no)
			(sheetname "")
		)
		(fill yes
			(thermal_gap 0.5)
			(thermal_bridge_width 0.5)
			(island_removal_mode 0)
		)
		(polygon
			(pts
				(arc
					(start 120.358154 -52.00015)
					(mid 120.000014 -51.64201)
					(end 119.641874 -52.00015)
				)
				(arc
					(start 119.641874 -52.999894)
					(mid 119.998617 -53.358285)
					(end 120.358154 -53.002688)
				)
				(arc
					(start 120.241314 -53.002688)
					(mid 120.000014 -53.241461)
					(end 119.758714 -53.002688)
				)
				(arc
					(start 119.758714 -53.000148)
					(mid 120.000014 -52.758848)
					(end 120.241314 -53.000148)
				)
				(xy 120.358154 -53.000148) (xy 120.358154 -52.00269)
				(arc
					(start 120.241314 -52.00269)
					(mid 120.000014 -52.241463)
					(end 119.758714 -52.00269)
				)
				(arc
					(start 119.758714 -52.00015)
					(mid 120.000014 -51.75885)
					(end 120.241314 -52.00015)
				)
			)
		)
	)
	(zone
		(layers "B.Cu" "In2.Cu")
		(hatch none 0.5)
		(connect_pads
			(clearance 0)
		)
		(min_thickness 0.25)
		(keepout
			(tracks not_allowed)
			(vias allowed)
			(pads allowed)
			(copperpour not_allowed)
			(footprints allowed)
		)
		(placement
			(enabled no)
			(sheetname "")
		)
		(fill yes
			(thermal_gap 0.5)
			(thermal_bridge_width 0.5)
			(island_removal_mode 0)
		)
		(polygon
			(pts
				(xy 138.843512 -81.924906) (xy 138.843258 -81.92516)
				(arc
					(start 138.843258 -81.925668)
					(mid 138.46048 -82.308446)
					(end 138.843258 -82.691224)
				)
				(xy 138.843258 -82.691986) (xy 139.986258 -82.691986)
				(arc
					(start 139.986258 -82.691224)
					(mid 140.256023 -82.580007)
					(end 140.369036 -82.310986)
				)
				(arc
					(start 140.252958 -82.310986)
					(mid 139.986258 -82.575158)
					(end 139.719558 -82.310986)
				)
				(arc
					(start 139.109958 -82.310986)
					(mid 138.843258 -82.575158)
					(end 138.576558 -82.310986)
				)
				(arc
					(start 138.576558 -82.308446)
					(mid 138.843258 -82.041746)
					(end 139.109958 -82.308446)
				)
				(arc
					(start 139.719558 -82.308446)
					(mid 139.986258 -82.041746)
					(end 140.252958 -82.308446)
				)
				(arc
					(start 140.369036 -82.308446)
					(mid 140.256923 -82.037781)
					(end 139.986258 -81.925668)
				)
				(xy 139.986258 -81.924906)
			)
		)
	)
	(zone
		(layers "B.Cu" "In2.Cu")
		(hatch none 0.5)
		(connect_pads
			(clearance 0)
		)
		(min_thickness 0.25)
		(keepout
			(tracks not_allowed)
			(vias allowed)
			(pads allowed)
			(copperpour not_allowed)
			(footprints allowed)
		)
		(placement
			(enabled no)
			(sheetname "")
		)
		(fill yes
			(thermal_gap 0.5)
			(thermal_bridge_width 0.5)
			(island_removal_mode 0)
		)
		(polygon
			(pts
				(xy 138.486134 -78.044294)
				(arc
					(start 138.486134 -78.045056)
					(mid 138.103356 -78.427834)
					(end 138.486134 -78.810612)
				)
				(xy 138.486134 -78.811374) (xy 139.62888 -78.811374) (xy 139.629134 -78.81112)
				(arc
					(start 139.629134 -78.810612)
					(mid 139.898899 -78.699395)
					(end 140.011912 -78.430374)
				)
				(arc
					(start 139.895834 -78.430374)
					(mid 139.629134 -78.694546)
					(end 139.362434 -78.430374)
				)
				(arc
					(start 138.752834 -78.430374)
					(mid 138.486134 -78.694546)
					(end 138.219434 -78.430374)
				)
				(arc
					(start 138.219434 -78.427834)
					(mid 138.486134 -78.161134)
					(end 138.752834 -78.427834)
				)
				(arc
					(start 139.362434 -78.427834)
					(mid 139.629134 -78.161134)
					(end 139.895834 -78.427834)
				)
				(arc
					(start 140.011912 -78.427834)
					(mid 139.899799 -78.157169)
					(end 139.629134 -78.045056)
				)
				(xy 139.629134 -78.044294)
			)
		)
	)
	(zone
		(layers "B.Cu" "In2.Cu")
		(hatch none 0.5)
		(connect_pads
			(clearance 0)
		)
		(min_thickness 0.25)
		(keepout
			(tracks not_allowed)
			(vias allowed)
			(pads allowed)
			(copperpour not_allowed)
			(footprints allowed)
		)
		(placement
			(enabled no)
			(sheetname "")
		)
		(fill yes
			(thermal_gap 0.5)
			(thermal_bridge_width 0.5)
			(island_removal_mode 0)
		)
		(polygon
			(pts
				(arc
					(start 130.000248 -68.641976)
					(mid 129.641854 -68.999989)
					(end 129.999994 -69.358256)
				)
				(arc
					(start 130.999992 -69.358256)
					(mid 131.252336 -69.254256)
					(end 131.358132 -69.002656)
				)
				(arc
					(start 131.241292 -69.002656)
					(mid 130.999992 -69.241429)
					(end 130.758692 -69.002656)
				)
				(arc
					(start 130.241294 -69.002656)
					(mid 129.999994 -69.241429)
					(end 129.758694 -69.002656)
				)
				(arc
					(start 129.758694 -69.000116)
					(mid 129.999994 -68.758816)
					(end 130.241294 -69.000116)
				)
				(arc
					(start 130.758692 -69.000116)
					(mid 130.999992 -68.758816)
					(end 131.241292 -69.000116)
				)
				(arc
					(start 131.358132 -69.000116)
					(mid 131.253235 -68.746873)
					(end 130.999992 -68.641976)
				)
			)
		)
	)
	(zone
		(layers "B.Cu" "In2.Cu")
		(hatch none 0.5)
		(connect_pads
			(clearance 0)
		)
		(min_thickness 0.25)
		(keepout
			(tracks not_allowed)
			(vias allowed)
			(pads allowed)
			(copperpour not_allowed)
			(footprints allowed)
		)
		(placement
			(enabled no)
			(sheetname "")
		)
		(fill yes
			(thermal_gap 0.5)
			(thermal_bridge_width 0.5)
			(island_removal_mode 0)
		)
		(polygon
			(pts
				(arc
					(start 117.35816 -51.000152)
					(mid 117.00002 -50.642012)
					(end 116.64188 -51.000152)
				)
				(arc
					(start 116.64188 -51.999896)
					(mid 116.998623 -52.358287)
					(end 117.35816 -52.00269)
				)
				(arc
					(start 117.24132 -52.00269)
					(mid 117.00002 -52.241463)
					(end 116.75872 -52.00269)
				)
				(arc
					(start 116.75872 -52.00015)
					(mid 117.00002 -51.75885)
					(end 117.24132 -52.00015)
				)
				(xy 117.35816 -52.00015) (xy 117.35816 -51.002692)
				(arc
					(start 117.24132 -51.002692)
					(mid 117.00002 -51.241465)
					(end 116.75872 -51.002692)
				)
				(arc
					(start 116.75872 -51.000152)
					(mid 117.00002 -50.758852)
					(end 117.24132 -51.000152)
				)
			)
		)
	)
	(zone
		(layers "B.Cu" "In2.Cu")
		(hatch none 0.5)
		(connect_pads
			(clearance 0)
		)
		(min_thickness 0.25)
		(keepout
			(tracks not_allowed)
			(vias allowed)
			(pads allowed)
			(copperpour not_allowed)
			(footprints allowed)
		)
		(placement
			(enabled no)
			(sheetname "")
		)
		(fill yes
			(thermal_gap 0.5)
			(thermal_bridge_width 0.5)
			(island_removal_mode 0)
		)
		(polygon
			(pts
				(xy 138.479276 -76.14158) (xy 138.479022 -76.141834)
				(arc
					(start 138.479022 -76.142342)
					(mid 138.096244 -76.52512)
					(end 138.479022 -76.907898)
				)
				(xy 138.479022 -76.90866) (xy 139.622022 -76.90866)
				(arc
					(start 139.622022 -76.907898)
					(mid 139.891787 -76.796681)
					(end 140.0048 -76.52766)
				)
				(arc
					(start 139.888722 -76.52766)
					(mid 139.622022 -76.791832)
					(end 139.355322 -76.52766)
				)
				(arc
					(start 138.745722 -76.52766)
					(mid 138.479022 -76.791832)
					(end 138.212322 -76.52766)
				)
				(arc
					(start 138.212322 -76.52512)
					(mid 138.479022 -76.25842)
					(end 138.745722 -76.52512)
				)
				(arc
					(start 139.355322 -76.52512)
					(mid 139.622022 -76.25842)
					(end 139.888722 -76.52512)
				)
				(arc
					(start 140.0048 -76.52512)
					(mid 139.892687 -76.254455)
					(end 139.622022 -76.142342)
				)
				(xy 139.622022 -76.14158)
			)
		)
	)
	(zone
		(layers "B.Cu" "In2.Cu")
		(hatch none 0.5)
		(connect_pads
			(clearance 0)
		)
		(min_thickness 0.25)
		(keepout
			(tracks not_allowed)
			(vias allowed)
			(pads allowed)
			(copperpour not_allowed)
			(footprints allowed)
		)
		(placement
			(enabled no)
			(sheetname "")
		)
		(fill yes
			(thermal_gap 0.5)
			(thermal_bridge_width 0.5)
			(island_removal_mode 0)
		)
		(polygon
			(pts
				(arc
					(start 130.000248 -72.641968)
					(mid 129.641854 -72.999981)
					(end 129.999994 -73.358248)
				)
				(arc
					(start 130.999992 -73.358248)
					(mid 131.252336 -73.254248)
					(end 131.358132 -73.002648)
				)
				(arc
					(start 131.241292 -73.002648)
					(mid 130.999992 -73.241421)
					(end 130.758692 -73.002648)
				)
				(arc
					(start 130.241294 -73.002648)
					(mid 129.999994 -73.241421)
					(end 129.758694 -73.002648)
				)
				(arc
					(start 129.758694 -73.000108)
					(mid 129.999994 -72.758808)
					(end 130.241294 -73.000108)
				)
				(arc
					(start 130.758692 -73.000108)
					(mid 130.999992 -72.758808)
					(end 131.241292 -73.000108)
				)
				(arc
					(start 131.358132 -73.000108)
					(mid 131.253235 -72.746865)
					(end 130.999992 -72.641968)
				)
			)
		)
	)
	(zone
		(layers "B.Cu" "In2.Cu")
		(hatch none 0.5)
		(connect_pads
			(clearance 0)
		)
		(min_thickness 0.25)
		(keepout
			(tracks not_allowed)
			(vias allowed)
			(pads allowed)
			(copperpour not_allowed)
			(footprints allowed)
		)
		(placement
			(enabled no)
			(sheetname "")
		)
		(fill yes
			(thermal_gap 0.5)
			(thermal_bridge_width 0.5)
			(island_removal_mode 0)
		)
		(polygon
			(pts
				(arc
					(start 101.358192 -52.00015)
					(mid 101.000052 -51.64201)
					(end 100.641912 -52.00015)
				)
				(arc
					(start 100.641912 -52.999894)
					(mid 100.998655 -53.358285)
					(end 101.358192 -53.002688)
				)
				(arc
					(start 101.241352 -53.002688)
					(mid 101.000052 -53.241461)
					(end 100.758752 -53.002688)
				)
				(arc
					(start 100.758752 -53.000148)
					(mid 101.000052 -52.758848)
					(end 101.241352 -53.000148)
				)
				(xy 101.358192 -53.000148) (xy 101.358192 -52.00269)
				(arc
					(start 101.241352 -52.00269)
					(mid 101.000052 -52.241463)
					(end 100.758752 -52.00269)
				)
				(arc
					(start 100.758752 -52.00015)
					(mid 101.000052 -51.75885)
					(end 101.241352 -52.00015)
				)
			)
		)
	)
	(zone
		(layers "B.Cu" "In2.Cu")
		(hatch none 0.5)
		(connect_pads
			(clearance 0)
		)
		(min_thickness 0.25)
		(keepout
			(tracks not_allowed)
			(vias allowed)
			(pads allowed)
			(copperpour not_allowed)
			(footprints allowed)
		)
		(placement
			(enabled no)
			(sheetname "")
		)
		(fill yes
			(thermal_gap 0.5)
			(thermal_bridge_width 0.5)
			(island_removal_mode 0)
		)
		(polygon
			(pts
				(arc
					(start 123.358148 -51.000152)
					(mid 123.000008 -50.642012)
					(end 122.641868 -51.000152)
				)
				(arc
					(start 122.641868 -51.999896)
					(mid 122.998611 -52.358287)
					(end 123.358148 -52.00269)
				)
				(arc
					(start 123.241308 -52.00269)
					(mid 123.000008 -52.241463)
					(end 122.758708 -52.00269)
				)
				(arc
					(start 122.758708 -52.00015)
					(mid 123.000008 -51.75885)
					(end 123.241308 -52.00015)
				)
				(xy 123.358148 -52.00015) (xy 123.358148 -51.002692)
				(arc
					(start 123.241308 -51.002692)
					(mid 123.000008 -51.241465)
					(end 122.758708 -51.002692)
				)
				(arc
					(start 122.758708 -51.000152)
					(mid 123.000008 -50.758852)
					(end 123.241308 -51.000152)
				)
			)
		)
	)
	(zone
		(layers "B.Cu" "In2.Cu")
		(hatch none 0.5)
		(connect_pads
			(clearance 0)
		)
		(min_thickness 0.25)
		(keepout
			(tracks not_allowed)
			(vias allowed)
			(pads allowed)
			(copperpour not_allowed)
			(footprints allowed)
		)
		(placement
			(enabled no)
			(sheetname "")
		)
		(fill yes
			(thermal_gap 0.5)
			(thermal_bridge_width 0.5)
			(island_removal_mode 0)
		)
		(polygon
			(pts
				(arc
					(start 168.543478 -23.123906)
					(mid 168.159938 -22.740366)
					(end 167.776398 -23.123906)
				)
				(arc
					(start 167.776398 -24.012652)
					(mid 168.158541 -24.396444)
					(end 168.543478 -24.015446)
				)
				(arc
					(start 168.426638 -24.015446)
					(mid 168.159938 -24.279618)
					(end 167.893238 -24.015446)
				)
				(arc
					(start 167.893238 -24.012906)
					(mid 168.159938 -23.746206)
					(end 168.426638 -24.012906)
				)
				(xy 168.543478 -24.012906) (xy 168.543478 -23.126446)
				(arc
					(start 168.426638 -23.126446)
					(mid 168.159938 -23.390618)
					(end 167.893238 -23.126446)
				)
				(arc
					(start 167.893238 -23.123906)
					(mid 168.159938 -22.857206)
					(end 168.426638 -23.123906)
				)
			)
		)
	)
	(zone
		(layers "B.Cu" "In2.Cu")
		(hatch none 0.5)
		(connect_pads
			(clearance 0)
		)
		(min_thickness 0.25)
		(keepout
			(tracks not_allowed)
			(vias allowed)
			(pads allowed)
			(copperpour not_allowed)
			(footprints allowed)
		)
		(placement
			(enabled no)
			(sheetname "")
		)
		(fill yes
			(thermal_gap 0.5)
			(thermal_bridge_width 0.5)
			(island_removal_mode 0)
		)
		(polygon
			(pts
				(arc
					(start 116.358162 -52.00015)
					(mid 116.000022 -51.64201)
					(end 115.641882 -52.00015)
				)
				(arc
					(start 115.641882 -52.999894)
					(mid 115.998625 -53.358285)
					(end 116.358162 -53.002688)
				)
				(arc
					(start 116.241322 -53.002688)
					(mid 116.000022 -53.241461)
					(end 115.758722 -53.002688)
				)
				(arc
					(start 115.758722 -53.000148)
					(mid 116.000022 -52.758848)
					(end 116.241322 -53.000148)
				)
				(xy 116.358162 -53.000148) (xy 116.358162 -52.00269)
				(arc
					(start 116.241322 -52.00269)
					(mid 116.000022 -52.241463)
					(end 115.758722 -52.00269)
				)
				(arc
					(start 115.758722 -52.00015)
					(mid 116.000022 -51.75885)
					(end 116.241322 -52.00015)
				)
			)
		)
	)
	(zone
		(layers "B.Cu" "In2.Cu")
		(hatch none 0.5)
		(connect_pads
			(clearance 0)
		)
		(min_thickness 0.25)
		(keepout
			(tracks not_allowed)
			(vias allowed)
			(pads allowed)
			(copperpour not_allowed)
			(footprints allowed)
		)
		(placement
			(enabled no)
			(sheetname "")
		)
		(fill yes
			(thermal_gap 0.5)
			(thermal_bridge_width 0.5)
			(island_removal_mode 0)
		)
		(polygon
			(pts
				(arc
					(start 107.35818 -52.00015)
					(mid 107.00004 -51.64201)
					(end 106.6419 -52.00015)
				)
				(arc
					(start 106.6419 -52.999894)
					(mid 106.998643 -53.358285)
					(end 107.35818 -53.002688)
				)
				(arc
					(start 107.24134 -53.002688)
					(mid 107.00004 -53.241461)
					(end 106.75874 -53.002688)
				)
				(arc
					(start 106.75874 -53.000148)
					(mid 107.00004 -52.758848)
					(end 107.24134 -53.000148)
				)
				(xy 107.35818 -53.000148) (xy 107.35818 -52.00269)
				(arc
					(start 107.24134 -52.00269)
					(mid 107.00004 -52.241463)
					(end 106.75874 -52.00269)
				)
				(arc
					(start 106.75874 -52.00015)
					(mid 107.00004 -51.75885)
					(end 107.24134 -52.00015)
				)
			)
		)
	)
	(zone
		(layers "B.Cu" "In2.Cu")
		(hatch none 0.5)
		(connect_pads
			(clearance 0)
		)
		(min_thickness 0.25)
		(keepout
			(tracks not_allowed)
			(vias allowed)
			(pads allowed)
			(copperpour not_allowed)
			(footprints allowed)
		)
		(placement
			(enabled no)
			(sheetname "")
		)
		(fill yes
			(thermal_gap 0.5)
			(thermal_bridge_width 0.5)
			(island_removal_mode 0)
		)
		(polygon
			(pts
				(arc
					(start 124.358146 -52.00015)
					(mid 124.000006 -51.64201)
					(end 123.641866 -52.00015)
				)
				(arc
					(start 123.641866 -52.999894)
					(mid 123.998609 -53.358285)
					(end 124.358146 -53.002688)
				)
				(arc
					(start 124.241306 -53.002688)
					(mid 124.000006 -53.241461)
					(end 123.758706 -53.002688)
				)
				(arc
					(start 123.758706 -53.000148)
					(mid 124.000006 -52.758848)
					(end 124.241306 -53.000148)
				)
				(xy 124.358146 -53.000148) (xy 124.358146 -52.00269)
				(arc
					(start 124.241306 -52.00269)
					(mid 124.000006 -52.241463)
					(end 123.758706 -52.00269)
				)
				(arc
					(start 123.758706 -52.00015)
					(mid 124.000006 -51.75885)
					(end 124.241306 -52.00015)
				)
			)
		)
	)
	(zone
		(layers "B.Cu" "In2.Cu")
		(hatch none 0.5)
		(connect_pads
			(clearance 0)
		)
		(min_thickness 0.25)
		(keepout
			(tracks not_allowed)
			(vias allowed)
			(pads allowed)
			(copperpour not_allowed)
			(footprints allowed)
		)
		(placement
			(enabled no)
			(sheetname "")
		)
		(fill yes
			(thermal_gap 0.5)
			(thermal_bridge_width 0.5)
			(island_removal_mode 0)
		)
		(polygon
			(pts
				(arc
					(start 166.508938 -23.166832)
					(mid 166.125398 -22.783292)
					(end 165.741858 -23.166832)
				)
				(arc
					(start 165.741858 -24.055578)
					(mid 166.124001 -24.43937)
					(end 166.508938 -24.058372)
				)
				(arc
					(start 166.392098 -24.058372)
					(mid 166.125398 -24.322544)
					(end 165.858698 -24.058372)
				)
				(arc
					(start 165.858698 -24.055832)
					(mid 166.125398 -23.789132)
					(end 166.392098 -24.055832)
				)
				(xy 166.508938 -24.055832) (xy 166.508938 -23.169372)
				(arc
					(start 166.392098 -23.169372)
					(mid 166.125398 -23.433544)
					(end 165.858698 -23.169372)
				)
				(arc
					(start 165.858698 -23.166832)
					(mid 166.125398 -22.900132)
					(end 166.392098 -23.166832)
				)
			)
		)
	)
	(zone
		(layers "B.Cu" "In2.Cu")
		(hatch none 0.5)
		(connect_pads
			(clearance 0)
		)
		(min_thickness 0.25)
		(keepout
			(tracks not_allowed)
			(vias allowed)
			(pads allowed)
			(copperpour not_allowed)
			(footprints allowed)
		)
		(placement
			(enabled no)
			(sheetname "")
		)
		(fill yes
			(thermal_gap 0.5)
			(thermal_bridge_width 0.5)
			(island_removal_mode 0)
		)
		(polygon
			(pts
				(arc
					(start 119.358156 -51.000152)
					(mid 119.000016 -50.642012)
					(end 118.641876 -51.000152)
				)
				(arc
					(start 118.641876 -51.999896)
					(mid 118.998619 -52.358287)
					(end 119.358156 -52.00269)
				)
				(arc
					(start 119.241316 -52.00269)
					(mid 119.000016 -52.241463)
					(end 118.758716 -52.00269)
				)
				(arc
					(start 118.758716 -52.00015)
					(mid 119.000016 -51.75885)
					(end 119.241316 -52.00015)
				)
				(xy 119.358156 -52.00015) (xy 119.358156 -51.002692)
				(arc
					(start 119.241316 -51.002692)
					(mid 119.000016 -51.241465)
					(end 118.758716 -51.002692)
				)
				(arc
					(start 118.758716 -51.000152)
					(mid 119.000016 -50.758852)
					(end 119.241316 -51.000152)
				)
			)
		)
	)
	(zone
		(layers "B.Cu" "In2.Cu" "In3.Cu" "In4.Cu" "In5.Cu")
		(hatch none 0.5)
		(connect_pads
			(clearance 0)
		)
		(min_thickness 0.25)
		(keepout
			(tracks not_allowed)
			(vias allowed)
			(pads allowed)
			(copperpour not_allowed)
			(footprints allowed)
		)
		(placement
			(enabled no)
			(sheetname "")
		)
		(fill yes
			(thermal_gap 0.5)
			(thermal_bridge_width 0.5)
			(island_removal_mode 0)
		)
		(polygon
			(pts
				(arc
					(start 205.000098 -123.63577)
					(mid 191.499908 -131.430014)
					(end 205.000098 -139.224258)
				)
			)
		)
	)
	(zone
		(layers "B.Cu" "In2.Cu" "In5.Cu")
		(hatch none 0.5)
		(connect_pads
			(clearance 0)
		)
		(min_thickness 0.25)
		(keepout
			(tracks not_allowed)
			(vias allowed)
			(pads allowed)
			(copperpour not_allowed)
			(footprints allowed)
		)
		(placement
			(enabled no)
			(sheetname "")
		)
		(fill yes
			(thermal_gap 0.5)
			(thermal_bridge_width 0.5)
			(island_removal_mode 0)
		)
		(polygon
			(pts
				(arc
					(start 180.561234 -7.400036)
					(mid 179.999894 -6.838696)
					(end 179.438554 -7.400036)
				)
				(arc
					(start 179.438554 -8.79983)
					(mid 179.998497 -9.361422)
					(end 180.561234 -8.802624)
				)
				(arc
					(start 180.393594 -8.802624)
					(mid 179.999894 -9.193792)
					(end 179.606194 -8.802624)
				)
				(arc
					(start 179.606194 -8.800084)
					(mid 179.999894 -8.406384)
					(end 180.393594 -8.800084)
				)
				(xy 180.561234 -8.800084) (xy 180.561234 -7.402576)
				(arc
					(start 180.393594 -7.402576)
					(mid 179.999894 -7.793744)
					(end 179.606194 -7.402576)
				)
				(arc
					(start 179.606194 -7.400036)
					(mid 179.999894 -7.006336)
					(end 180.393594 -7.400036)
				)
			)
		)
	)
	(zone
		(layers "B.Cu" "In5.Cu")
		(hatch none 0.5)
		(connect_pads
			(clearance 0)
		)
		(min_thickness 0.25)
		(keepout
			(tracks not_allowed)
			(vias allowed)
			(pads allowed)
			(copperpour not_allowed)
			(footprints allowed)
		)
		(placement
			(enabled no)
			(sheetname "")
		)
		(fill yes
			(thermal_gap 0.5)
			(thermal_bridge_width 0.5)
			(island_removal_mode 0)
		)
		(polygon
			(pts
				(arc
					(start 127.533908 -45.844206)
					(mid 127.076708 -45.387006)
					(end 126.619508 -45.844206)
				)
				(arc
					(start 126.619508 -46.986952)
					(mid 127.075311 -47.444404)
					(end 127.533908 -46.989746)
				)
				(arc
					(start 127.343408 -46.989746)
					(mid 127.076708 -47.253918)
					(end 126.810008 -46.989746)
				)
				(arc
					(start 126.810008 -46.987206)
					(mid 127.076708 -46.720506)
					(end 127.343408 -46.987206)
				)
				(xy 127.533908 -46.987206) (xy 127.533908 -45.846746)
				(arc
					(start 127.343408 -45.846746)
					(mid 127.076708 -46.110918)
					(end 126.810008 -45.846746)
				)
				(arc
					(start 126.810008 -45.844206)
					(mid 127.076708 -45.577506)
					(end 127.343408 -45.844206)
				)
			)
		)
	)
	(zone
		(layers "B.Cu" "In5.Cu")
		(hatch none 0.5)
		(connect_pads
			(clearance 0)
		)
		(min_thickness 0.25)
		(keepout
			(tracks not_allowed)
			(vias allowed)
			(pads allowed)
			(copperpour not_allowed)
			(footprints allowed)
		)
		(placement
			(enabled no)
			(sheetname "")
		)
		(fill yes
			(thermal_gap 0.5)
			(thermal_bridge_width 0.5)
			(island_removal_mode 0)
		)
		(polygon
			(pts
				(arc
					(start 126.000256 -56.642)
					(mid 125.641862 -57.000013)
					(end 126.000002 -57.35828)
				)
				(arc
					(start 127 -57.35828)
					(mid 127.252344 -57.25428)
					(end 127.35814 -57.00268)
				)
				(arc
					(start 127.2413 -57.00268)
					(mid 127 -57.241453)
					(end 126.7587 -57.00268)
				)
				(arc
					(start 126.241302 -57.00268)
					(mid 126.000002 -57.241453)
					(end 125.758702 -57.00268)
				)
				(arc
					(start 125.758702 -57.00014)
					(mid 126.000002 -56.75884)
					(end 126.241302 -57.00014)
				)
				(arc
					(start 126.7587 -57.00014)
					(mid 127 -56.75884)
					(end 127.2413 -57.00014)
				)
				(arc
					(start 127.35814 -57.00014)
					(mid 127.253243 -56.746897)
					(end 127 -56.642)
				)
			)
		)
	)
	(zone
		(layers "B.Cu" "In5.Cu")
		(hatch none 0.5)
		(connect_pads
			(clearance 0)
		)
		(min_thickness 0.25)
		(keepout
			(tracks not_allowed)
			(vias allowed)
			(pads allowed)
			(copperpour not_allowed)
			(footprints allowed)
		)
		(placement
			(enabled no)
			(sheetname "")
		)
		(fill yes
			(thermal_gap 0.5)
			(thermal_bridge_width 0.5)
			(island_removal_mode 0)
		)
		(polygon
			(pts
				(arc
					(start 125.139958 -45.858938)
					(mid 124.682758 -45.401738)
					(end 124.225558 -45.858938)
				)
				(arc
					(start 124.225558 -47.001684)
					(mid 124.681361 -47.459136)
					(end 125.139958 -47.004478)
				)
				(arc
					(start 124.949458 -47.004478)
					(mid 124.682758 -47.26865)
					(end 124.416058 -47.004478)
				)
				(arc
					(start 124.416058 -47.001938)
					(mid 124.682758 -46.735238)
					(end 124.949458 -47.001938)
				)
				(xy 125.139958 -47.001938) (xy 125.139958 -45.861478)
				(arc
					(start 124.949458 -45.861478)
					(mid 124.682758 -46.12565)
					(end 124.416058 -45.861478)
				)
				(arc
					(start 124.416058 -45.858938)
					(mid 124.682758 -45.592238)
					(end 124.949458 -45.858938)
				)
			)
		)
	)
	(zone
		(layers "B.Cu" "In5.Cu")
		(hatch none 0.5)
		(connect_pads
			(clearance 0)
		)
		(min_thickness 0.25)
		(keepout
			(tracks not_allowed)
			(vias allowed)
			(pads allowed)
			(copperpour not_allowed)
			(footprints allowed)
		)
		(placement
			(enabled no)
			(sheetname "")
		)
		(fill yes
			(thermal_gap 0.5)
			(thermal_bridge_width 0.5)
			(island_removal_mode 0)
		)
		(polygon
			(pts
				(arc
					(start 166.58336 -35.199828)
					(mid 166.19982 -34.816288)
					(end 165.81628 -35.199828)
				)
				(arc
					(start 165.81628 -35.999928)
					(mid 166.19855 -36.383466)
					(end 166.58336 -36.002468)
				)
				(arc
					(start 166.46652 -36.002468)
					(mid 166.19982 -36.26664)
					(end 165.93312 -36.002468)
				)
				(arc
					(start 165.93312 -35.999928)
					(mid 166.19982 -35.733228)
					(end 166.46652 -35.999928)
				)
				(xy 166.58336 -35.999928) (xy 166.58336 -35.202368)
				(arc
					(start 166.46652 -35.202368)
					(mid 166.19982 -35.46654)
					(end 165.93312 -35.202368)
				)
				(arc
					(start 165.93312 -35.199828)
					(mid 166.19982 -34.933128)
					(end 166.46652 -35.199828)
				)
			)
		)
	)
	(zone
		(layers "B.Cu" "In5.Cu")
		(hatch none 0.5)
		(connect_pads
			(clearance 0)
		)
		(min_thickness 0.25)
		(keepout
			(tracks not_allowed)
			(vias allowed)
			(pads allowed)
			(copperpour not_allowed)
			(footprints allowed)
		)
		(placement
			(enabled no)
			(sheetname "")
		)
		(fill yes
			(thermal_gap 0.5)
			(thermal_bridge_width 0.5)
			(island_removal_mode 0)
		)
		(polygon
			(pts
				(arc
					(start 149.321774 -40.235378)
					(mid 148.912326 -39.780679)
					(end 148.41728 -40.140382)
				)
				(arc
					(start 148.179536 -41.25849)
					(mid 148.531834 -41.80078)
					(end 149.074124 -41.448482)
				)
				(xy 149.093682 -41.356026)
				(arc
					(start 148.89353 -41.356026)
					(mid 148.62683 -41.620198)
					(end 148.36013 -41.356026)
				)
				(arc
					(start 148.36013 -41.353486)
					(mid 148.62683 -41.086786)
					(end 148.89353 -41.353486)
				)
				(xy 149.09419 -41.353486)
				(arc
					(start 149.309328 -40.340788)
					(mid 149.318466 -40.289706)
					(end 149.321774 -40.237918)
				)
				(arc
					(start 149.131274 -40.237918)
					(mid 148.864574 -40.50209)
					(end 148.597874 -40.237918)
				)
				(arc
					(start 148.597874 -40.235378)
					(mid 148.864574 -39.968678)
					(end 149.131274 -40.235378)
				)
			)
		)
	)
	(zone
		(layers "B.Cu" "In5.Cu")
		(hatch none 0.5)
		(connect_pads
			(clearance 0)
		)
		(min_thickness 0.25)
		(keepout
			(tracks not_allowed)
			(vias allowed)
			(pads allowed)
			(copperpour not_allowed)
			(footprints allowed)
		)
		(placement
			(enabled no)
			(sheetname "")
		)
		(fill yes
			(thermal_gap 0.5)
			(thermal_bridge_width 0.5)
			(island_removal_mode 0)
		)
		(polygon
			(pts
				(arc
					(start 126.000256 -57.641998)
					(mid 125.641862 -58.000011)
					(end 126.000002 -58.358278)
				)
				(arc
					(start 127 -58.358278)
					(mid 127.252344 -58.254278)
					(end 127.35814 -58.002678)
				)
				(arc
					(start 127.2413 -58.002678)
					(mid 127 -58.241451)
					(end 126.7587 -58.002678)
				)
				(arc
					(start 126.241302 -58.002678)
					(mid 126.000002 -58.241451)
					(end 125.758702 -58.002678)
				)
				(arc
					(start 125.758702 -58.000138)
					(mid 126.000002 -57.758838)
					(end 126.241302 -58.000138)
				)
				(arc
					(start 126.7587 -58.000138)
					(mid 127 -57.758838)
					(end 127.2413 -58.000138)
				)
				(arc
					(start 127.35814 -58.000138)
					(mid 127.253243 -57.746895)
					(end 127 -57.641998)
				)
			)
		)
	)
	(zone
		(layers "B.Cu" "In5.Cu")
		(hatch none 0.5)
		(connect_pads
			(clearance 0)
		)
		(min_thickness 0.25)
		(keepout
			(tracks not_allowed)
			(vias allowed)
			(pads allowed)
			(copperpour not_allowed)
			(footprints allowed)
		)
		(placement
			(enabled no)
			(sheetname "")
		)
		(fill yes
			(thermal_gap 0.5)
			(thermal_bridge_width 0.5)
			(island_removal_mode 0)
		)
		(polygon
			(pts
				(arc
					(start 126.000256 -54.642004)
					(mid 125.641862 -55.000017)
					(end 126.000002 -55.358284)
				)
				(arc
					(start 127 -55.358284)
					(mid 127.252344 -55.254284)
					(end 127.35814 -55.002684)
				)
				(arc
					(start 127.2413 -55.002684)
					(mid 127 -55.241457)
					(end 126.7587 -55.002684)
				)
				(arc
					(start 126.241302 -55.002684)
					(mid 126.000002 -55.241457)
					(end 125.758702 -55.002684)
				)
				(arc
					(start 125.758702 -55.000144)
					(mid 126.000002 -54.758844)
					(end 126.241302 -55.000144)
				)
				(arc
					(start 126.7587 -55.000144)
					(mid 127 -54.758844)
					(end 127.2413 -55.000144)
				)
				(arc
					(start 127.35814 -55.000144)
					(mid 127.253243 -54.746901)
					(end 127 -54.642004)
				)
			)
		)
	)
	(zone
		(layers "B.Cu" "In5.Cu")
		(hatch none 0.5)
		(connect_pads
			(clearance 0)
		)
		(min_thickness 0.25)
		(keepout
			(tracks not_allowed)
			(vias allowed)
			(pads allowed)
			(copperpour not_allowed)
			(footprints allowed)
		)
		(placement
			(enabled no)
			(sheetname "")
		)
		(fill yes
			(thermal_gap 0.5)
			(thermal_bridge_width 0.5)
			(island_removal_mode 0)
		)
		(polygon
			(pts
				(arc
					(start 126.000256 -53.642006)
					(mid 125.641862 -54.000019)
					(end 126.000002 -54.358286)
				)
				(arc
					(start 127 -54.358286)
					(mid 127.252344 -54.254286)
					(end 127.35814 -54.002686)
				)
				(arc
					(start 127.2413 -54.002686)
					(mid 127 -54.241459)
					(end 126.7587 -54.002686)
				)
				(arc
					(start 126.241302 -54.002686)
					(mid 126.000002 -54.241459)
					(end 125.758702 -54.002686)
				)
				(arc
					(start 125.758702 -54.000146)
					(mid 126.000002 -53.758846)
					(end 126.241302 -54.000146)
				)
				(arc
					(start 126.7587 -54.000146)
					(mid 127 -53.758846)
					(end 127.2413 -54.000146)
				)
				(arc
					(start 127.35814 -54.000146)
					(mid 127.253243 -53.746903)
					(end 127 -53.642006)
				)
			)
		)
	)
	(zone
		(layers "B.Cu" "In5.Cu")
		(hatch none 0.5)
		(connect_pads
			(clearance 0)
		)
		(min_thickness 0.25)
		(keepout
			(tracks not_allowed)
			(vias allowed)
			(pads allowed)
			(copperpour not_allowed)
			(footprints allowed)
		)
		(placement
			(enabled no)
			(sheetname "")
		)
		(fill yes
			(thermal_gap 0.5)
			(thermal_bridge_width 0.5)
			(island_removal_mode 0)
		)
		(polygon
			(pts
				(arc
					(start 149.04974 -50.414682)
					(mid 148.640292 -49.959983)
					(end 148.145246 -50.319686)
				)
				(arc
					(start 147.907502 -51.437794)
					(mid 148.2598 -51.980084)
					(end 148.80209 -51.627786)
				)
				(xy 148.821648 -51.53533)
				(arc
					(start 148.621496 -51.53533)
					(mid 148.354796 -51.799502)
					(end 148.088096 -51.53533)
				)
				(arc
					(start 148.088096 -51.53279)
					(mid 148.354796 -51.26609)
					(end 148.621496 -51.53279)
				)
				(xy 148.822156 -51.53279)
				(arc
					(start 149.037294 -50.520092)
					(mid 149.046432 -50.46901)
					(end 149.04974 -50.417222)
				)
				(arc
					(start 148.85924 -50.417222)
					(mid 148.59254 -50.681394)
					(end 148.32584 -50.417222)
				)
				(arc
					(start 148.32584 -50.414682)
					(mid 148.59254 -50.147982)
					(end 148.85924 -50.414682)
				)
			)
		)
	)
	(zone
		(layers "B.Cu" "In5.Cu")
		(hatch none 0.5)
		(connect_pads
			(clearance 0)
		)
		(min_thickness 0.25)
		(keepout
			(tracks not_allowed)
			(vias allowed)
			(pads allowed)
			(copperpour not_allowed)
			(footprints allowed)
		)
		(placement
			(enabled no)
			(sheetname "")
		)
		(fill yes
			(thermal_gap 0.5)
			(thermal_bridge_width 0.5)
			(island_removal_mode 0)
		)
		(polygon
			(pts
				(arc
					(start 126.000256 -55.642002)
					(mid 125.641862 -56.000015)
					(end 126.000002 -56.358282)
				)
				(arc
					(start 127 -56.358282)
					(mid 127.252344 -56.254282)
					(end 127.35814 -56.002682)
				)
				(arc
					(start 127.2413 -56.002682)
					(mid 127 -56.241455)
					(end 126.7587 -56.002682)
				)
				(arc
					(start 126.241302 -56.002682)
					(mid 126.000002 -56.241455)
					(end 125.758702 -56.002682)
				)
				(arc
					(start 125.758702 -56.000142)
					(mid 126.000002 -55.758842)
					(end 126.241302 -56.000142)
				)
				(arc
					(start 126.7587 -56.000142)
					(mid 127 -55.758842)
					(end 127.2413 -56.000142)
				)
				(arc
					(start 127.35814 -56.000142)
					(mid 127.253243 -55.746899)
					(end 127 -55.642002)
				)
			)
		)
	)
	(zone
		(layers "B.Cu" "In5.Cu")
		(hatch none 0.5)
		(connect_pads
			(clearance 0)
		)
		(min_thickness 0.25)
		(keepout
			(tracks not_allowed)
			(vias allowed)
			(pads allowed)
			(copperpour not_allowed)
			(footprints allowed)
		)
		(placement
			(enabled no)
			(sheetname "")
		)
		(fill yes
			(thermal_gap 0.5)
			(thermal_bridge_width 0.5)
			(island_removal_mode 0)
		)
		(polygon
			(pts
				(arc
					(start 166.200074 -29.21635)
					(mid 165.81628 -29.599763)
					(end 166.19982 -29.98343)
				)
				(arc
					(start 166.999412 -29.983684)
					(mid 167.26997 -29.872244)
					(end 167.383206 -29.60243)
				)
				(arc
					(start 167.266366 -29.60243)
					(mid 166.999666 -29.866854)
					(end 166.732966 -29.60243)
				)
				(arc
					(start 166.46652 -29.60243)
					(mid 166.19982 -29.866602)
					(end 165.93312 -29.60243)
				)
				(arc
					(start 165.93312 -29.59989)
					(mid 166.19982 -29.33319)
					(end 166.46652 -29.59989)
				)
				(arc
					(start 166.732966 -29.59989)
					(mid 166.999666 -29.333444)
					(end 167.266366 -29.59989)
				)
				(arc
					(start 167.383206 -29.59989)
					(mid 167.27078 -29.32885)
					(end 166.999666 -29.216604)
				)
			)
		)
	)
	(zone
		(layers "B.Cu" "In5.Cu")
		(hatch none 0.5)
		(connect_pads
			(clearance 0)
		)
		(min_thickness 0.25)
		(keepout
			(tracks not_allowed)
			(vias allowed)
			(pads allowed)
			(copperpour not_allowed)
			(footprints allowed)
		)
		(placement
			(enabled no)
			(sheetname "")
		)
		(fill yes
			(thermal_gap 0.5)
			(thermal_bridge_width 0.5)
			(island_removal_mode 0)
		)
		(polygon
			(pts
				(arc
					(start 165.400228 -36.416488)
					(mid 165.016434 -36.799901)
					(end 165.399974 -37.183568)
				)
				(arc
					(start 166.19982 -37.183568)
					(mid 166.470124 -37.072128)
					(end 166.58336 -36.802568)
				)
				(arc
					(start 166.46652 -36.802568)
					(mid 166.19982 -37.06674)
					(end 165.93312 -36.802568)
				)
				(arc
					(start 165.666674 -36.802568)
					(mid 165.399974 -37.06674)
					(end 165.133274 -36.802568)
				)
				(arc
					(start 165.133274 -36.800028)
					(mid 165.399974 -36.533328)
					(end 165.666674 -36.800028)
				)
				(arc
					(start 165.93312 -36.800028)
					(mid 166.19982 -36.533328)
					(end 166.46652 -36.800028)
				)
				(arc
					(start 166.58336 -36.800028)
					(mid 166.471024 -36.528824)
					(end 166.19982 -36.416488)
				)
			)
		)
	)
	(zone
		(layers "B.Cu" "In5.Cu")
		(hatch none 0.5)
		(connect_pads
			(clearance 0)
		)
		(min_thickness 0.25)
		(keepout
			(tracks not_allowed)
			(vias allowed)
			(pads allowed)
			(copperpour not_allowed)
			(footprints allowed)
		)
		(placement
			(enabled no)
			(sheetname "")
		)
		(fill yes
			(thermal_gap 0.5)
			(thermal_bridge_width 0.5)
			(island_removal_mode 0)
		)
		(polygon
			(pts
				(arc
					(start 150.09749 -54.383178)
					(mid 149.688042 -53.928479)
					(end 149.192996 -54.288182)
				)
				(arc
					(start 148.957792 -55.395876)
					(mid 149.302356 -55.947245)
					(end 149.84984 -55.596282)
				)
				(xy 149.869398 -55.503826)
				(arc
					(start 149.669246 -55.503826)
					(mid 149.402546 -55.767998)
					(end 149.135846 -55.503826)
				)
				(arc
					(start 149.135846 -55.501286)
					(mid 149.402546 -55.234586)
					(end 149.669246 -55.501286)
				)
				(xy 149.87016 -55.501286)
				(arc
					(start 150.087584 -54.478174)
					(mid 150.094899 -54.432199)
					(end 150.09749 -54.385718)
				)
				(arc
					(start 149.90699 -54.385718)
					(mid 149.64029 -54.64989)
					(end 149.37359 -54.385718)
				)
				(arc
					(start 149.37359 -54.383178)
					(mid 149.64029 -54.116478)
					(end 149.90699 -54.383178)
				)
			)
		)
	)
	(zone
		(layers "B.Cu" "In5.Cu")
		(hatch none 0.5)
		(connect_pads
			(clearance 0)
		)
		(min_thickness 0.25)
		(keepout
			(tracks not_allowed)
			(vias allowed)
			(pads allowed)
			(copperpour not_allowed)
			(footprints allowed)
		)
		(placement
			(enabled no)
			(sheetname "")
		)
		(fill yes
			(thermal_gap 0.5)
			(thermal_bridge_width 0.5)
			(island_removal_mode 0)
		)
		(polygon
			(pts
				(arc
					(start 130.105658 -45.829474)
					(mid 129.648458 -45.372274)
					(end 129.191258 -45.829474)
				)
				(arc
					(start 129.191258 -46.97222)
					(mid 129.647061 -47.429672)
					(end 130.105658 -46.975014)
				)
				(arc
					(start 129.915158 -46.975014)
					(mid 129.648458 -47.239186)
					(end 129.381758 -46.975014)
				)
				(arc
					(start 129.381758 -46.972474)
					(mid 129.648458 -46.705774)
					(end 129.915158 -46.972474)
				)
				(xy 130.105658 -46.972474) (xy 130.105658 -45.832014)
				(arc
					(start 129.915158 -45.832014)
					(mid 129.648458 -46.096186)
					(end 129.381758 -45.832014)
				)
				(arc
					(start 129.381758 -45.829474)
					(mid 129.648458 -45.562774)
					(end 129.915158 -45.829474)
				)
			)
		)
	)
	(zone
		(layers "B.Cu" "In5.Cu")
		(hatch none 0.5)
		(connect_pads
			(clearance 0)
		)
		(min_thickness 0.25)
		(keepout
			(tracks not_allowed)
			(vias allowed)
			(pads allowed)
			(copperpour not_allowed)
			(footprints allowed)
		)
		(placement
			(enabled no)
			(sheetname "")
		)
		(fill yes
			(thermal_gap 0.5)
			(thermal_bridge_width 0.5)
			(island_removal_mode 0)
		)
		(polygon
			(pts
				(arc
					(start 150.242524 -44.203874)
					(mid 149.833076 -43.749175)
					(end 149.33803 -44.108878)
				)
				(arc
					(start 149.100286 -45.226986)
					(mid 149.452584 -45.769276)
					(end 149.994874 -45.416978)
				)
				(xy 150.014432 -45.324522)
				(arc
					(start 149.81428 -45.324522)
					(mid 149.54758 -45.588694)
					(end 149.28088 -45.324522)
				)
				(arc
					(start 149.28088 -45.321982)
					(mid 149.54758 -45.055282)
					(end 149.81428 -45.321982)
				)
				(xy 150.01494 -45.321982)
				(arc
					(start 150.230078 -44.309284)
					(mid 150.239216 -44.258202)
					(end 150.242524 -44.206414)
				)
				(arc
					(start 150.052024 -44.206414)
					(mid 149.785324 -44.470586)
					(end 149.518624 -44.206414)
				)
				(arc
					(start 149.518624 -44.203874)
					(mid 149.785324 -43.937174)
					(end 150.052024 -44.203874)
				)
			)
		)
	)
	(zone
		(layers "B.Cu" "In5.Cu")
		(hatch none 0.5)
		(connect_pads
			(clearance 0)
		)
		(min_thickness 0.25)
		(keepout
			(tracks not_allowed)
			(vias allowed)
			(pads allowed)
			(copperpour not_allowed)
			(footprints allowed)
		)
		(placement
			(enabled no)
			(sheetname "")
		)
		(fill yes
			(thermal_gap 0.5)
			(thermal_bridge_width 0.5)
			(island_removal_mode 0)
		)
		(polygon
			(pts
				(arc
					(start 166.58336 -32.800036)
					(mid 166.19982 -32.416496)
					(end 165.81628 -32.800036)
				)
				(arc
					(start 165.81628 -33.599882)
					(mid 166.19855 -33.98342)
					(end 166.58336 -33.602422)
				)
				(arc
					(start 166.46652 -33.602422)
					(mid 166.19982 -33.866594)
					(end 165.93312 -33.602422)
				)
				(arc
					(start 165.93312 -33.599882)
					(mid 166.19982 -33.333182)
					(end 166.46652 -33.599882)
				)
				(xy 166.58336 -33.599882) (xy 166.58336 -32.802576)
				(arc
					(start 166.46652 -32.802576)
					(mid 166.19982 -33.066748)
					(end 165.93312 -32.802576)
				)
				(arc
					(start 165.93312 -32.800036)
					(mid 166.19982 -32.533336)
					(end 166.46652 -32.800036)
				)
			)
		)
	)
	(zone
		(layers "B.Cu" "In5.Cu")
		(hatch none 0.5)
		(connect_pads
			(clearance 0)
		)
		(min_thickness 0.25)
		(keepout
			(tracks not_allowed)
			(vias allowed)
			(pads allowed)
			(copperpour not_allowed)
			(footprints allowed)
		)
		(placement
			(enabled no)
			(sheetname "")
		)
		(fill yes
			(thermal_gap 0.5)
			(thermal_bridge_width 0.5)
			(island_removal_mode 0)
		)
		(polygon
			(pts
				(arc
					(start 149.82698 -35.10788)
					(mid 149.417532 -34.653181)
					(end 148.922486 -35.012884)
				)
				(arc
					(start 148.684742 -36.130992)
					(mid 149.03704 -36.673282)
					(end 149.57933 -36.320984)
				)
				(xy 149.598888 -36.228528)
				(arc
					(start 149.398736 -36.228528)
					(mid 149.132036 -36.4927)
					(end 148.865336 -36.228528)
				)
				(arc
					(start 148.865336 -36.225988)
					(mid 149.132036 -35.959288)
					(end 149.398736 -36.225988)
				)
				(xy 149.599396 -36.225988)
				(arc
					(start 149.814534 -35.21329)
					(mid 149.823672 -35.162208)
					(end 149.82698 -35.11042)
				)
				(arc
					(start 149.63648 -35.11042)
					(mid 149.36978 -35.374592)
					(end 149.10308 -35.11042)
				)
				(arc
					(start 149.10308 -35.10788)
					(mid 149.36978 -34.84118)
					(end 149.63648 -35.10788)
				)
			)
		)
	)
	(zone
		(layers "B.Cu" "In5.Cu")
		(hatch none 0.5)
		(connect_pads
			(clearance 0)
		)
		(min_thickness 0.25)
		(keepout
			(tracks not_allowed)
			(vias allowed)
			(pads allowed)
			(copperpour not_allowed)
			(footprints allowed)
		)
		(placement
			(enabled no)
			(sheetname "")
		)
		(fill yes
			(thermal_gap 0.5)
			(thermal_bridge_width 0.5)
			(island_removal_mode 0)
		)
		(polygon
			(pts
				(arc
					(start 165.399974 -34.016442)
					(mid 165.016434 -34.399982)
					(end 165.399974 -34.783522)
				)
				(arc
					(start 166.199566 -34.783522)
					(mid 166.470034 -34.672172)
					(end 166.58336 -34.402522)
				)
				(arc
					(start 166.46652 -34.402522)
					(mid 166.19982 -34.666694)
					(end 165.93312 -34.402522)
				)
				(arc
					(start 165.666674 -34.402522)
					(mid 165.399974 -34.666694)
					(end 165.133274 -34.402522)
				)
				(arc
					(start 165.133274 -34.399982)
					(mid 165.399974 -34.133282)
					(end 165.666674 -34.399982)
				)
				(arc
					(start 165.93312 -34.399982)
					(mid 166.19982 -34.133282)
					(end 166.46652 -34.399982)
				)
				(arc
					(start 166.58336 -34.399982)
					(mid 166.471024 -34.128778)
					(end 166.19982 -34.016442)
				)
			)
		)
	)
	(zone
		(layers "B.Cu" "In5.Cu")
		(hatch none 0.5)
		(connect_pads
			(clearance 0)
		)
		(min_thickness 0.25)
		(keepout
			(tracks not_allowed)
			(vias allowed)
			(pads allowed)
			(copperpour not_allowed)
			(footprints allowed)
		)
		(placement
			(enabled no)
			(sheetname "")
		)
		(fill yes
			(thermal_gap 0.5)
			(thermal_bridge_width 0.5)
			(island_removal_mode 0)
		)
		(polygon
			(pts
				(arc
					(start 165.399974 -36.416488)
					(mid 165.016434 -36.800028)
					(end 165.399974 -37.183568)
				)
				(arc
					(start 166.199566 -37.183568)
					(mid 166.470034 -37.072218)
					(end 166.58336 -36.802568)
				)
				(arc
					(start 166.46652 -36.802568)
					(mid 166.19982 -37.06674)
					(end 165.93312 -36.802568)
				)
				(arc
					(start 165.666674 -36.802568)
					(mid 165.399974 -37.06674)
					(end 165.133274 -36.802568)
				)
				(arc
					(start 165.133274 -36.800028)
					(mid 165.399974 -36.533328)
					(end 165.666674 -36.800028)
				)
				(arc
					(start 165.93312 -36.800028)
					(mid 166.19982 -36.533328)
					(end 166.46652 -36.800028)
				)
				(arc
					(start 166.58336 -36.800028)
					(mid 166.471024 -36.528824)
					(end 166.19982 -36.416488)
				)
			)
		)
	)
	(zone
		(layers "B.Cu" "In5.Cu")
		(hatch none 0.5)
		(connect_pads
			(clearance 0)
		)
		(min_thickness 0.25)
		(keepout
			(tracks not_allowed)
			(vias allowed)
			(pads allowed)
			(copperpour not_allowed)
			(footprints allowed)
		)
		(placement
			(enabled no)
			(sheetname "")
		)
		(fill yes
			(thermal_gap 0.5)
			(thermal_bridge_width 0.5)
			(island_removal_mode 0)
		)
		(polygon
			(pts
				(arc
					(start 165.400228 -34.016442)
					(mid 165.016434 -34.399855)
					(end 165.399974 -34.783522)
				)
				(arc
					(start 166.19982 -34.783522)
					(mid 166.470124 -34.672082)
					(end 166.58336 -34.402522)
				)
				(arc
					(start 166.46652 -34.402522)
					(mid 166.19982 -34.666694)
					(end 165.93312 -34.402522)
				)
				(arc
					(start 165.666674 -34.402522)
					(mid 165.399974 -34.666694)
					(end 165.133274 -34.402522)
				)
				(arc
					(start 165.133274 -34.399982)
					(mid 165.399974 -34.133282)
					(end 165.666674 -34.399982)
				)
				(arc
					(start 165.93312 -34.399982)
					(mid 166.19982 -34.133282)
					(end 166.46652 -34.399982)
				)
				(arc
					(start 166.58336 -34.399982)
					(mid 166.471024 -34.128778)
					(end 166.19982 -34.016442)
				)
			)
		)
	)
	(zone
		(layers "B.Cu" "In5.Cu")
		(hatch none 0.5)
		(connect_pads
			(clearance 0)
		)
		(min_thickness 0.25)
		(keepout
			(tracks not_allowed)
			(vias allowed)
			(pads allowed)
			(copperpour not_allowed)
			(footprints allowed)
		)
		(placement
			(enabled no)
			(sheetname "")
		)
		(fill yes
			(thermal_gap 0.5)
			(thermal_bridge_width 0.5)
			(island_removal_mode 0)
		)
		(polygon
			(pts
				(arc
					(start 151.689308 -37.993066)
					(mid 151.27986 -37.538367)
					(end 150.784814 -37.89807)
				)
				(arc
					(start 150.54707 -39.016178)
					(mid 150.899368 -39.558468)
					(end 151.441658 -39.20617)
				)
				(xy 151.461216 -39.113714)
				(arc
					(start 151.261064 -39.113714)
					(mid 150.994364 -39.377886)
					(end 150.727664 -39.113714)
				)
				(arc
					(start 150.727664 -39.111174)
					(mid 150.994364 -38.844474)
					(end 151.261064 -39.111174)
				)
				(xy 151.461724 -39.111174)
				(arc
					(start 151.676862 -38.098476)
					(mid 151.686 -38.047394)
					(end 151.689308 -37.995606)
				)
				(arc
					(start 151.498808 -37.995606)
					(mid 151.232108 -38.259778)
					(end 150.965408 -37.995606)
				)
				(arc
					(start 150.965408 -37.993066)
					(mid 151.232108 -37.726366)
					(end 151.498808 -37.993066)
				)
			)
		)
	)
	(zone
		(layers "B.Cu" "In5.Cu")
		(hatch none 0.5)
		(connect_pads
			(clearance 0)
		)
		(min_thickness 0.25)
		(keepout
			(tracks not_allowed)
			(vias allowed)
			(pads allowed)
			(copperpour not_allowed)
			(footprints allowed)
		)
		(placement
			(enabled no)
			(sheetname "")
		)
		(fill yes
			(thermal_gap 0.5)
			(thermal_bridge_width 0.5)
			(island_removal_mode 0)
		)
		(polygon
			(pts
				(arc
					(start 166.58336 -30.39999)
					(mid 166.19982 -30.01645)
					(end 165.81628 -30.39999)
				)
				(arc
					(start 165.81628 -31.199836)
					(mid 166.19855 -31.583374)
					(end 166.58336 -31.202376)
				)
				(arc
					(start 166.46652 -31.202376)
					(mid 166.19982 -31.466548)
					(end 165.93312 -31.202376)
				)
				(arc
					(start 165.93312 -31.199836)
					(mid 166.19982 -30.933136)
					(end 166.46652 -31.199836)
				)
				(xy 166.58336 -31.199836) (xy 166.58336 -30.40253)
				(arc
					(start 166.46652 -30.40253)
					(mid 166.19982 -30.666702)
					(end 165.93312 -30.40253)
				)
				(arc
					(start 165.93312 -30.39999)
					(mid 166.19982 -30.13329)
					(end 166.46652 -30.39999)
				)
			)
		)
	)
	(zone
		(layers "B.Cu" "In5.Cu")
		(hatch none 0.5)
		(connect_pads
			(clearance 0)
		)
		(min_thickness 0.25)
		(keepout
			(tracks not_allowed)
			(vias allowed)
			(pads allowed)
			(copperpour not_allowed)
			(footprints allowed)
		)
		(placement
			(enabled no)
			(sheetname "")
		)
		(fill yes
			(thermal_gap 0.5)
			(thermal_bridge_width 0.5)
			(island_removal_mode 0)
		)
		(polygon
			(pts
				(arc
					(start 166.200074 -31.616396)
					(mid 165.816534 -31.999936)
					(end 166.200074 -32.383476)
				)
				(arc
					(start 166.999666 -32.383476)
					(mid 167.270134 -32.272126)
					(end 167.38346 -32.002476)
				)
				(arc
					(start 167.26662 -32.002476)
					(mid 166.99992 -32.266648)
					(end 166.73322 -32.002476)
				)
				(arc
					(start 166.466774 -32.002476)
					(mid 166.200074 -32.266648)
					(end 165.933374 -32.002476)
				)
				(arc
					(start 165.933374 -31.999936)
					(mid 166.200074 -31.733236)
					(end 166.466774 -31.999936)
				)
				(arc
					(start 166.73322 -31.999936)
					(mid 166.99992 -31.733236)
					(end 167.26662 -31.999936)
				)
				(arc
					(start 167.38346 -31.999936)
					(mid 167.271124 -31.728732)
					(end 166.99992 -31.616396)
				)
			)
		)
	)
	(zone
		(layers "B.Cu" "In5.Cu")
		(hatch none 0.5)
		(connect_pads
			(clearance 0)
		)
		(min_thickness 0.25)
		(keepout
			(tracks not_allowed)
			(vias allowed)
			(pads allowed)
			(copperpour not_allowed)
			(footprints allowed)
		)
		(placement
			(enabled no)
			(sheetname "")
		)
		(fill yes
			(thermal_gap 0.5)
			(thermal_bridge_width 0.5)
			(island_removal_mode 0)
		)
		(polygon
			(pts
				(arc
					(start 166.58336 -37.599874)
					(mid 166.19982 -37.216334)
					(end 165.81628 -37.599874)
				)
				(arc
					(start 165.81628 -38.399974)
					(mid 166.19855 -38.783512)
					(end 166.58336 -38.402514)
				)
				(arc
					(start 166.46652 -38.402514)
					(mid 166.19982 -38.666686)
					(end 165.93312 -38.402514)
				)
				(arc
					(start 165.93312 -38.399974)
					(mid 166.19982 -38.133274)
					(end 166.46652 -38.399974)
				)
				(xy 166.58336 -38.399974) (xy 166.58336 -37.602414)
				(arc
					(start 166.46652 -37.602414)
					(mid 166.19982 -37.866586)
					(end 165.93312 -37.602414)
				)
				(arc
					(start 165.93312 -37.599874)
					(mid 166.19982 -37.333174)
					(end 166.46652 -37.599874)
				)
			)
		)
	)
	(zone
		(layers "B.Cu" "In5.Cu")
		(hatch none 0.5)
		(connect_pads
			(clearance 0)
		)
		(min_thickness 0.25)
		(keepout
			(tracks not_allowed)
			(vias allowed)
			(pads allowed)
			(copperpour not_allowed)
			(footprints allowed)
		)
		(placement
			(enabled no)
			(sheetname "")
		)
		(fill yes
			(thermal_gap 0.5)
			(thermal_bridge_width 0.5)
			(island_removal_mode 0)
		)
		(polygon
			(pts
				(arc
					(start 126.000256 -58.641996)
					(mid 125.641862 -59.000009)
					(end 126.000002 -59.358276)
				)
				(arc
					(start 127 -59.358276)
					(mid 127.252344 -59.254276)
					(end 127.35814 -59.002676)
				)
				(arc
					(start 127.2413 -59.002676)
					(mid 127 -59.241449)
					(end 126.7587 -59.002676)
				)
				(arc
					(start 126.241302 -59.002676)
					(mid 126.000002 -59.241449)
					(end 125.758702 -59.002676)
				)
				(arc
					(start 125.758702 -59.000136)
					(mid 126.000002 -58.758836)
					(end 126.241302 -59.000136)
				)
				(arc
					(start 126.7587 -59.000136)
					(mid 127 -58.758836)
					(end 127.2413 -59.000136)
				)
				(arc
					(start 127.35814 -59.000136)
					(mid 127.253243 -58.746893)
					(end 127 -58.641996)
				)
			)
		)
	)
	(zone
		(layers "B.Cu" "In5.Cu")
		(hatch none 0.5)
		(connect_pads
			(clearance 0)
		)
		(min_thickness 0.25)
		(keepout
			(tracks not_allowed)
			(vias allowed)
			(pads allowed)
			(copperpour not_allowed)
			(footprints allowed)
		)
		(placement
			(enabled no)
			(sheetname "")
		)
		(fill yes
			(thermal_gap 0.5)
			(thermal_bridge_width 0.5)
			(island_removal_mode 0)
		)
		(polygon
			(pts
				(arc
					(start 146.981672 -32.354774)
					(mid 146.572224 -31.900075)
					(end 146.077178 -32.259778)
				)
				(arc
					(start 145.839434 -33.377886)
					(mid 146.191732 -33.920176)
					(end 146.734022 -33.567878)
				)
				(xy 146.75358 -33.475422)
				(arc
					(start 146.553428 -33.475422)
					(mid 146.286728 -33.739594)
					(end 146.020028 -33.475422)
				)
				(arc
					(start 146.020028 -33.472882)
					(mid 146.286728 -33.206182)
					(end 146.553428 -33.472882)
				)
				(xy 146.754088 -33.472882)
				(arc
					(start 146.969226 -32.460184)
					(mid 146.978364 -32.409102)
					(end 146.981672 -32.357314)
				)
				(arc
					(start 146.791172 -32.357314)
					(mid 146.524472 -32.621486)
					(end 146.257772 -32.357314)
				)
				(arc
					(start 146.257772 -32.354774)
					(mid 146.524472 -32.088074)
					(end 146.791172 -32.354774)
				)
			)
		)
	)
	(zone
		(layers "B.Cu" "In5.Cu")
		(hatch none 0.5)
		(connect_pads
			(clearance 0)
		)
		(min_thickness 0.25)
		(keepout
			(tracks not_allowed)
			(vias allowed)
			(pads allowed)
			(copperpour not_allowed)
			(footprints allowed)
		)
		(placement
			(enabled no)
			(sheetname "")
		)
		(fill yes
			(thermal_gap 0.5)
			(thermal_bridge_width 0.5)
			(island_removal_mode 0)
		)
		(polygon
			(pts
				(arc
					(start 139.03071 -60.667392)
					(mid 138.57605 -61.122052)
					(end 139.03071 -61.576712)
				)
				(arc
					(start 140.173456 -61.576712)
					(mid 140.494214 -61.444532)
					(end 140.62837 -61.124592)
				)
				(arc
					(start 140.44041 -61.124592)
					(mid 140.17371 -61.388764)
					(end 139.90701 -61.124592)
				)
				(arc
					(start 139.29741 -61.124592)
					(mid 139.03071 -61.388764)
					(end 138.76401 -61.124592)
				)
				(arc
					(start 138.76401 -61.122052)
					(mid 139.03071 -60.855352)
					(end 139.29741 -61.122052)
				)
				(arc
					(start 139.90701 -61.122052)
					(mid 140.17371 -60.855352)
					(end 140.44041 -61.122052)
				)
				(arc
					(start 140.62837 -61.122052)
					(mid 140.495203 -60.800559)
					(end 140.17371 -60.667392)
				)
			)
		)
	)
	(zone
		(layers "B.Cu" "In5.Cu")
		(hatch none 0.5)
		(connect_pads
			(clearance 0)
		)
		(min_thickness 0.25)
		(keepout
			(tracks not_allowed)
			(vias allowed)
			(pads allowed)
			(copperpour not_allowed)
			(footprints allowed)
		)
		(placement
			(enabled no)
			(sheetname "")
		)
		(fill yes
			(thermal_gap 0.5)
			(thermal_bridge_width 0.5)
			(island_removal_mode 0)
		)
		(polygon
			(pts
				(arc
					(start 138.80465 -62.590426)
					(mid 138.34999 -63.045086)
					(end 138.80465 -63.499746)
				)
				(arc
					(start 139.947396 -63.499746)
					(mid 140.268154 -63.367566)
					(end 140.40231 -63.047626)
				)
				(arc
					(start 140.21435 -63.047626)
					(mid 139.94765 -63.311798)
					(end 139.68095 -63.047626)
				)
				(arc
					(start 139.07135 -63.047626)
					(mid 138.80465 -63.311798)
					(end 138.53795 -63.047626)
				)
				(arc
					(start 138.53795 -63.045086)
					(mid 138.80465 -62.778386)
					(end 139.07135 -63.045086)
				)
				(arc
					(start 139.68095 -63.045086)
					(mid 139.94765 -62.778386)
					(end 140.21435 -63.045086)
				)
				(arc
					(start 140.40231 -63.045086)
					(mid 140.269143 -62.723593)
					(end 139.94765 -62.590426)
				)
			)
		)
	)
	(zone
		(layers "B.Cu" "In5.Cu")
		(hatch none 0.5)
		(connect_pads
			(clearance 0)
		)
		(min_thickness 0.25)
		(keepout
			(tracks not_allowed)
			(vias allowed)
			(pads allowed)
			(copperpour not_allowed)
			(footprints allowed)
		)
		(placement
			(enabled no)
			(sheetname "")
		)
		(fill yes
			(thermal_gap 0.5)
			(thermal_bridge_width 0.5)
			(island_removal_mode 0)
		)
		(polygon
			(pts
				(arc
					(start 127.000254 -52.642008)
					(mid 126.64186 -53.000021)
					(end 127 -53.358288)
				)
				(arc
					(start 127.999998 -53.358288)
					(mid 128.252342 -53.254288)
					(end 128.358138 -53.002688)
				)
				(arc
					(start 128.241298 -53.002688)
					(mid 127.999998 -53.241461)
					(end 127.758698 -53.002688)
				)
				(arc
					(start 127.2413 -53.002688)
					(mid 127 -53.241461)
					(end 126.7587 -53.002688)
				)
				(arc
					(start 126.7587 -53.000148)
					(mid 127 -52.758848)
					(end 127.2413 -53.000148)
				)
				(arc
					(start 127.758698 -53.000148)
					(mid 127.999998 -52.758848)
					(end 128.241298 -53.000148)
				)
				(arc
					(start 128.358138 -53.000148)
					(mid 128.253241 -52.746905)
					(end 127.999998 -52.642008)
				)
			)
		)
	)
	(zone
		(layers "B.Cu" "In5.Cu")
		(hatch none 0.5)
		(connect_pads
			(clearance 0)
		)
		(min_thickness 0.25)
		(keepout
			(tracks not_allowed)
			(vias allowed)
			(pads allowed)
			(copperpour not_allowed)
			(footprints allowed)
		)
		(placement
			(enabled no)
			(sheetname "")
		)
		(fill yes
			(thermal_gap 0.5)
			(thermal_bridge_width 0.5)
			(island_removal_mode 0)
		)
		(polygon
			(pts
				(arc
					(start 132.677408 -45.814742)
					(mid 132.220208 -45.357542)
					(end 131.763008 -45.814742)
				)
				(arc
					(start 131.763008 -46.957488)
					(mid 132.218811 -47.41494)
					(end 132.677408 -46.960282)
				)
				(arc
					(start 132.486908 -46.960282)
					(mid 132.220208 -47.224454)
					(end 131.953508 -46.960282)
				)
				(arc
					(start 131.953508 -46.957742)
					(mid 132.220208 -46.691042)
					(end 132.486908 -46.957742)
				)
				(xy 132.677408 -46.957742) (xy 132.677408 -45.817282)
				(arc
					(start 132.486908 -45.817282)
					(mid 132.220208 -46.081454)
					(end 131.953508 -45.817282)
				)
				(arc
					(start 131.953508 -45.814742)
					(mid 132.220208 -45.548042)
					(end 132.486908 -45.814742)
				)
			)
		)
	)
	(zone
		(layers "B.Cu" "In5.Cu")
		(hatch none 0.5)
		(connect_pads
			(clearance 0)
		)
		(min_thickness 0.25)
		(keepout
			(tracks not_allowed)
			(vias allowed)
			(pads allowed)
			(copperpour not_allowed)
			(footprints allowed)
		)
		(placement
			(enabled no)
			(sheetname "")
		)
		(fill yes
			(thermal_gap 0.5)
			(thermal_bridge_width 0.5)
			(island_removal_mode 0)
		)
		(polygon
			(pts
				(arc
					(start 139.446 -58.44794)
					(mid 138.99134 -58.9026)
					(end 139.446 -59.35726)
				)
				(arc
					(start 140.588746 -59.35726)
					(mid 140.909504 -59.22508)
					(end 141.04366 -58.90514)
				)
				(arc
					(start 140.8557 -58.90514)
					(mid 140.589 -59.169312)
					(end 140.3223 -58.90514)
				)
				(arc
					(start 139.7127 -58.90514)
					(mid 139.446 -59.169312)
					(end 139.1793 -58.90514)
				)
				(arc
					(start 139.1793 -58.9026)
					(mid 139.446 -58.6359)
					(end 139.7127 -58.9026)
				)
				(arc
					(start 140.3223 -58.9026)
					(mid 140.589 -58.6359)
					(end 140.8557 -58.9026)
				)
				(arc
					(start 141.04366 -58.9026)
					(mid 140.910493 -58.581107)
					(end 140.589 -58.44794)
				)
			)
		)
	)
	(zone
		(layers "B.Cu" "In5.Cu")
		(hatch none 0.5)
		(connect_pads
			(clearance 0)
		)
		(min_thickness 0.25)
		(keepout
			(tracks not_allowed)
			(vias allowed)
			(pads allowed)
			(copperpour not_allowed)
			(footprints allowed)
		)
		(placement
			(enabled no)
			(sheetname "")
		)
		(fill yes
			(thermal_gap 0.5)
			(thermal_bridge_width 0.5)
			(island_removal_mode 0)
		)
		(polygon
			(pts
				(arc
					(start 138.739118 -64.517524)
					(mid 138.284458 -64.972184)
					(end 138.739118 -65.426844)
				)
				(arc
					(start 139.881864 -65.426844)
					(mid 140.202622 -65.294664)
					(end 140.336778 -64.974724)
				)
				(arc
					(start 140.148818 -64.974724)
					(mid 139.882118 -65.238896)
					(end 139.615418 -64.974724)
				)
				(arc
					(start 139.005818 -64.974724)
					(mid 138.739118 -65.238896)
					(end 138.472418 -64.974724)
				)
				(arc
					(start 138.472418 -64.972184)
					(mid 138.739118 -64.705484)
					(end 139.005818 -64.972184)
				)
				(arc
					(start 139.615418 -64.972184)
					(mid 139.882118 -64.705484)
					(end 140.148818 -64.972184)
				)
				(arc
					(start 140.336778 -64.972184)
					(mid 140.203611 -64.650691)
					(end 139.882118 -64.517524)
				)
			)
		)
	)
	(zone
		(layers "B.Cu" "In5.Cu")
		(hatch none 0.5)
		(connect_pads
			(clearance 0)
		)
		(min_thickness 0.25)
		(keepout
			(tracks not_allowed)
			(vias allowed)
			(pads allowed)
			(copperpour not_allowed)
			(footprints allowed)
		)
		(placement
			(enabled no)
			(sheetname "")
		)
		(fill yes
			(thermal_gap 0.5)
			(thermal_bridge_width 0.5)
			(island_removal_mode 0)
		)
		(polygon
			(pts
				(arc
					(start 126.000256 -59.641994)
					(mid 125.641862 -60.000007)
					(end 126.000002 -60.358274)
				)
				(arc
					(start 127 -60.358274)
					(mid 127.252344 -60.254274)
					(end 127.35814 -60.002674)
				)
				(arc
					(start 127.2413 -60.002674)
					(mid 127 -60.241447)
					(end 126.7587 -60.002674)
				)
				(arc
					(start 126.241302 -60.002674)
					(mid 126.000002 -60.241447)
					(end 125.758702 -60.002674)
				)
				(arc
					(start 125.758702 -60.000134)
					(mid 126.000002 -59.758834)
					(end 126.241302 -60.000134)
				)
				(arc
					(start 126.7587 -60.000134)
					(mid 127 -59.758834)
					(end 127.2413 -60.000134)
				)
				(arc
					(start 127.35814 -60.000134)
					(mid 127.253243 -59.746891)
					(end 127 -59.641994)
				)
			)
		)
	)
	(zone
		(layers "B.Cu" "In5.Cu")
		(hatch none 0.5)
		(connect_pads
			(clearance 0)
		)
		(min_thickness 0.25)
		(keepout
			(tracks not_allowed)
			(vias allowed)
			(pads allowed)
			(copperpour not_allowed)
			(footprints allowed)
		)
		(placement
			(enabled no)
			(sheetname "")
		)
		(fill yes
			(thermal_gap 0.5)
			(thermal_bridge_width 0.5)
			(island_removal_mode 0)
		)
		(polygon
			(pts
				(arc
					(start 148.00199 -46.446186)
					(mid 147.592542 -45.991487)
					(end 147.097496 -46.35119)
				)
				(arc
					(start 146.859752 -47.469298)
					(mid 147.21205 -48.011588)
					(end 147.75434 -47.65929)
				)
				(xy 147.773898 -47.566834)
				(arc
					(start 147.573746 -47.566834)
					(mid 147.307046 -47.831006)
					(end 147.040346 -47.566834)
				)
				(arc
					(start 147.040346 -47.564294)
					(mid 147.307046 -47.297594)
					(end 147.573746 -47.564294)
				)
				(xy 147.774406 -47.564294)
				(arc
					(start 147.989544 -46.551596)
					(mid 147.998682 -46.500514)
					(end 148.00199 -46.448726)
				)
				(arc
					(start 147.81149 -46.448726)
					(mid 147.54479 -46.712898)
					(end 147.27809 -46.448726)
				)
				(arc
					(start 147.27809 -46.446186)
					(mid 147.54479 -46.179486)
					(end 147.81149 -46.446186)
				)
			)
		)
	)
	(zone
		(net "AGND_CURRENT_MON")
		(layer "In1.Cu")
		(hatch none 0.5)
		(connect_pads
			(clearance 0.5)
		)
		(min_thickness 0.25)
		(fill yes
			(thermal_gap 0.5)
			(thermal_bridge_width 0.5)
			(island_removal_mode 0)
		)
		(polygon
			(pts
				(xy 5.410454 -35.3695) (xy 4.93268 -35.847274) (xy 4.93268 -63.715646) (xy 5.357114 -64.14008) (xy 23.763986 -64.14008)
				(xy 24.64562 -63.258446) (xy 24.64562 -39.103554) (xy 23.728426 -38.18636) (xy 20.929346 -38.18636)
				(xy 18.112486 -35.3695)
			)
		)
	)
	(zone
		(net "GND")
		(layer "In1.Cu")
		(hatch none 0.5)
		(connect_pads
			(clearance 0.5)
		)
		(min_thickness 0.25)
		(fill yes
			(thermal_gap 0.5)
			(thermal_bridge_width 0.5)
			(island_removal_mode 0)
		)
		(polygon
			(pts
				(arc
					(start 1.999996 -0.763016)
					(mid 1.125319 -1.125319)
					(end 0.763016 -1.999996)
				)
				(arc
					(start 0.763016 -142.999968)
					(mid 1.125319 -143.874645)
					(end 1.999996 -144.236948)
				)
				(arc
					(start 83.002882 -144.236948)
					(mid 83.877395 -143.874555)
					(end 84.239608 -142.999968)
				)
				(arc
					(start 84.239608 -132.262626)
					(mid 85.617496 -128.523498)
					(end 89.092024 -126.572264)
				)
				(xy 97.43948 -125.236986) (xy 112.560354 -125.236986)
				(arc
					(start 120.91289 -126.573026)
					(mid 124.387646 -128.524285)
					(end 125.76556 -132.263642)
				)
				(arc
					(start 125.76556 -142.999968)
					(mid 126.127863 -143.874645)
					(end 127.00254 -144.236948)
				)
				(arc
					(start 208.000092 -144.236948)
					(mid 208.874769 -143.874645)
					(end 209.237072 -142.999968)
				)
				(arc
					(start 209.237072 -1.999996)
					(mid 208.874769 -1.125319)
					(end 208.000092 -0.763016)
				)
			)
		)
		(polygon
			(pts
				(arc
					(start 106.233722 -115.10899)
					(mid 106.009186 -114.366294)
					(end 105.26649 -114.59083)
				)
				(arc
					(start 104.516428 -115.990624)
					(mid 104.740809 -116.733627)
					(end 105.48366 -116.509038)
				)
			)
		)
		(polygon
			(pts
				(arc
					(start 103.983536 -115.10899)
					(mid 103.759 -114.366294)
					(end 103.016304 -114.59083)
				)
				(xy 102.266496 -115.990624)
				(arc
					(start 102.266496 -115.990878)
					(mid 102.491032 -116.733574)
					(end 103.233728 -116.509038)
				)
			)
		)
		(polygon
			(pts
				(arc
					(start 106.233722 -111.30915)
					(mid 106.009186 -110.566454)
					(end 105.26649 -110.79099)
				)
				(arc
					(start 104.516428 -112.190784)
					(mid 104.740809 -112.933787)
					(end 105.48366 -112.709198)
				)
			)
		)
		(polygon
			(pts
				(arc
					(start 103.983536 -111.30915)
					(mid 103.759 -110.566454)
					(end 103.016304 -110.79099)
				)
				(xy 102.266496 -112.190784)
				(arc
					(start 102.266496 -112.191038)
					(mid 102.491032 -112.933734)
					(end 103.233728 -112.709198)
				)
			)
		)
		(polygon
			(pts
				(arc
					(start 106.188256 -107.484672)
					(mid 105.984802 -106.811826)
					(end 105.311956 -107.01528)
				)
				(xy 105.311194 -107.014772) (xy 104.561386 -108.41482) (xy 104.561386 -108.415074)
				(arc
					(start 104.561894 -108.415328)
					(mid 104.765348 -109.088174)
					(end 105.438194 -108.88472)
				)
				(xy 105.438956 -108.885228) (xy 106.189018 -107.48518)
			)
		)
		(polygon
			(pts
				(arc
					(start 103.93807 -107.484672)
					(mid 103.734616 -106.811826)
					(end 103.06177 -107.01528)
				)
				(xy 103.061008 -107.015026) (xy 102.311454 -108.41482) (xy 102.311454 -108.415074)
				(arc
					(start 102.311962 -108.415328)
					(mid 102.515416 -109.088174)
					(end 103.188262 -108.88472)
				)
				(xy 103.189024 -108.884974) (xy 103.938832 -107.484926)
			)
		)
		(polygon
			(pts
				(arc
					(start 106.188256 -103.684832)
					(mid 105.984802 -103.011986)
					(end 105.311956 -103.21544)
				)
				(xy 105.311194 -103.214932) (xy 104.561386 -104.614472) (xy 104.561386 -104.61498)
				(arc
					(start 104.561894 -104.615234)
					(mid 104.765348 -105.28808)
					(end 105.438194 -105.084626)
				)
				(xy 105.438956 -105.085134) (xy 106.189018 -103.68534)
			)
		)
		(polygon
			(pts
				(arc
					(start 103.93807 -103.684832)
					(mid 103.734616 -103.011986)
					(end 103.06177 -103.21544)
				)
				(xy 103.061008 -103.215186) (xy 102.311454 -104.614726) (xy 102.311454 -104.61498)
				(arc
					(start 102.311962 -104.615234)
					(mid 102.515416 -105.28808)
					(end 103.188262 -105.084626)
				)
				(xy 103.189024 -105.08488) (xy 103.938832 -103.685086)
			)
		)
		(polygon
			(pts
				(xy 139.986258 -81.924906) (xy 138.843512 -81.924906) (xy 138.843258 -81.92516)
				(arc
					(start 138.843258 -81.925668)
					(mid 138.46048 -82.308446)
					(end 138.843258 -82.691224)
				)
				(xy 138.843258 -82.691986) (xy 139.986258 -82.691986)
				(arc
					(start 139.986258 -82.691224)
					(mid 140.369036 -82.308446)
					(end 139.986258 -81.925668)
				)
			)
		)
		(polygon
			(pts
				(arc
					(start 136.7028 -81.026)
					(mid 136.687921 -80.990079)
					(end 136.652 -80.9752)
				)
				(arc
					(start 135.8392 -80.9752)
					(mid 135.803279 -80.990079)
					(end 135.7884 -81.026)
				)
				(arc
					(start 135.7884 -81.2292)
					(mid 135.803279 -81.265121)
					(end 135.8392 -81.28)
				)
				(arc
					(start 136.652 -81.28)
					(mid 136.687921 -81.265121)
					(end 136.7028 -81.2292)
				)
			)
		)
		(polygon
			(pts
				(arc
					(start 136.7028 -80.4672)
					(mid 136.687921 -80.431279)
					(end 136.652 -80.4164)
				)
				(arc
					(start 135.8392 -80.4164)
					(mid 135.803279 -80.431279)
					(end 135.7884 -80.4672)
				)
				(arc
					(start 135.7884 -80.6704)
					(mid 135.803279 -80.706321)
					(end 135.8392 -80.7212)
				)
				(arc
					(start 136.652 -80.7212)
					(mid 136.687921 -80.706321)
					(end 136.7028 -80.6704)
				)
			)
		)
		(polygon
			(pts
				(xy 139.643612 -79.813912) (xy 138.500866 -79.813912) (xy 138.500612 -79.814166)
				(arc
					(start 138.500612 -79.814674)
					(mid 138.117834 -80.197452)
					(end 138.500612 -80.58023)
				)
				(xy 138.500612 -80.580992) (xy 139.643612 -80.580992)
				(arc
					(start 139.643612 -80.58023)
					(mid 140.02639 -80.197452)
					(end 139.643612 -79.814674)
				)
			)
		)
		(polygon
			(pts
				(arc
					(start 136.684512 -79.628492)
					(mid 136.669633 -79.592571)
					(end 136.633712 -79.577692)
				)
				(arc
					(start 135.820912 -79.577692)
					(mid 135.784991 -79.592571)
					(end 135.770112 -79.628492)
				)
				(arc
					(start 135.770112 -79.831692)
					(mid 135.784991 -79.867613)
					(end 135.820912 -79.882492)
				)
				(arc
					(start 136.633712 -79.882492)
					(mid 136.669633 -79.867613)
					(end 136.684512 -79.831692)
				)
			)
		)
		(polygon
			(pts
				(arc
					(start 136.684512 -79.069692)
					(mid 136.669633 -79.033771)
					(end 136.633712 -79.018892)
				)
				(arc
					(start 135.820912 -79.018892)
					(mid 135.784991 -79.033771)
					(end 135.770112 -79.069692)
				)
				(arc
					(start 135.770112 -79.272892)
					(mid 135.784991 -79.308813)
					(end 135.820912 -79.323692)
				)
				(arc
					(start 136.633712 -79.323692)
					(mid 136.669633 -79.308813)
					(end 136.684512 -79.272892)
				)
			)
		)
		(polygon
			(pts
				(xy 139.629134 -78.044294) (xy 138.486134 -78.044294)
				(arc
					(start 138.486134 -78.045056)
					(mid 138.103356 -78.427834)
					(end 138.486134 -78.810612)
				)
				(xy 138.486134 -78.811374) (xy 139.62888 -78.811374) (xy 139.629134 -78.81112)
				(arc
					(start 139.629134 -78.810612)
					(mid 140.011912 -78.427834)
					(end 139.629134 -78.045056)
				)
			)
		)
		(polygon
			(pts
				(arc
					(start 136.638792 -77.729334)
					(mid 136.623913 -77.693413)
					(end 136.587992 -77.678534)
				)
				(arc
					(start 135.775192 -77.678534)
					(mid 135.739271 -77.693413)
					(end 135.724392 -77.729334)
				)
				(arc
					(start 135.724392 -77.932534)
					(mid 135.739271 -77.968455)
					(end 135.775192 -77.983334)
				)
				(arc
					(start 136.587992 -77.983334)
					(mid 136.623913 -77.968455)
					(end 136.638792 -77.932534)
				)
			)
		)
		(polygon
			(pts
				(arc
					(start 136.638792 -77.170534)
					(mid 136.623913 -77.134613)
					(end 136.587992 -77.119734)
				)
				(arc
					(start 135.775192 -77.119734)
					(mid 135.739271 -77.134613)
					(end 135.724392 -77.170534)
				)
				(arc
					(start 135.724392 -77.373734)
					(mid 135.739271 -77.409655)
					(end 135.775192 -77.424534)
				)
				(arc
					(start 136.587992 -77.424534)
					(mid 136.623913 -77.409655)
					(end 136.638792 -77.373734)
				)
			)
		)
		(polygon
			(pts
				(arc
					(start 127 -77.35824)
					(mid 127.35814 -77.0001)
					(end 127 -76.64196)
				)
				(arc
					(start 125.999748 -76.64196)
					(mid 125.641862 -77.000227)
					(end 126.000002 -77.35824)
				)
			)
		)
		(polygon
			(pts
				(xy 139.622022 -76.14158) (xy 138.479276 -76.14158) (xy 138.479022 -76.141834)
				(arc
					(start 138.479022 -76.142342)
					(mid 138.096244 -76.52512)
					(end 138.479022 -76.907898)
				)
				(xy 138.479022 -76.90866) (xy 139.622022 -76.90866)
				(arc
					(start 139.622022 -76.907898)
					(mid 140.0048 -76.52512)
					(end 139.622022 -76.142342)
				)
			)
		)
		(polygon
			(pts
				(arc
					(start 136.706102 -75.81392)
					(mid 136.691223 -75.777999)
					(end 136.655302 -75.76312)
				)
				(arc
					(start 135.842502 -75.76312)
					(mid 135.806581 -75.777999)
					(end 135.791702 -75.81392)
				)
				(arc
					(start 135.791702 -76.01712)
					(mid 135.806581 -76.053041)
					(end 135.842502 -76.06792)
				)
				(arc
					(start 136.655302 -76.06792)
					(mid 136.691223 -76.053041)
					(end 136.706102 -76.01712)
				)
			)
		)
		(polygon
			(pts
				(arc
					(start 127 -76.358242)
					(mid 127.35814 -76.000102)
					(end 127 -75.641962)
				)
				(arc
					(start 125.999748 -75.641962)
					(mid 125.641862 -76.000229)
					(end 126.000002 -76.358242)
				)
			)
		)
		(polygon
			(pts
				(arc
					(start 136.706102 -75.25512)
					(mid 136.691223 -75.219199)
					(end 136.655302 -75.20432)
				)
				(arc
					(start 135.842502 -75.20432)
					(mid 135.806581 -75.219199)
					(end 135.791702 -75.25512)
				)
				(arc
					(start 135.791702 -75.45832)
					(mid 135.806581 -75.494241)
					(end 135.842502 -75.50912)
				)
				(arc
					(start 136.655302 -75.50912)
					(mid 136.691223 -75.494241)
					(end 136.706102 -75.45832)
				)
			)
		)
		(polygon
			(pts
				(arc
					(start 127 -75.358244)
					(mid 127.35814 -75.000104)
					(end 127 -74.641964)
				)
				(arc
					(start 125.999748 -74.641964)
					(mid 125.641862 -75.000231)
					(end 126.000002 -75.358244)
				)
			)
		)
		(polygon
			(pts
				(arc
					(start 127 -74.358246)
					(mid 127.35814 -74.000106)
					(end 127 -73.641966)
				)
				(arc
					(start 125.999748 -73.641966)
					(mid 125.641862 -74.000233)
					(end 126.000002 -74.358246)
				)
			)
		)
		(polygon
			(pts
				(arc
					(start 130.999992 -73.358248)
					(mid 131.358132 -73.000108)
					(end 130.999992 -72.641968)
				)
				(arc
					(start 129.99974 -72.641968)
					(mid 129.641854 -73.000235)
					(end 129.999994 -73.358248)
				)
			)
		)
		(polygon
			(pts
				(arc
					(start 127 -73.358248)
					(mid 127.35814 -73.000108)
					(end 127 -72.641968)
				)
				(arc
					(start 125.999748 -72.641968)
					(mid 125.641862 -73.000235)
					(end 126.000002 -73.358248)
				)
			)
		)
		(polygon
			(pts
				(arc
					(start 129.999994 -72.35825)
					(mid 130.358134 -72.00011)
					(end 129.999994 -71.64197)
				)
				(arc
					(start 128.999742 -71.64197)
					(mid 128.641856 -72.000237)
					(end 128.999996 -72.35825)
				)
			)
		)
		(polygon
			(pts
				(arc
					(start 127 -72.35825)
					(mid 127.35814 -72.00011)
					(end 127 -71.64197)
				)
				(arc
					(start 125.999748 -71.64197)
					(mid 125.641862 -72.000237)
					(end 126.000002 -72.35825)
				)
			)
		)
		(polygon
			(pts
				(arc
					(start 130.999992 -71.358252)
					(mid 131.358132 -71.000112)
					(end 130.999992 -70.641972)
				)
				(arc
					(start 129.99974 -70.641972)
					(mid 129.641854 -71.000239)
					(end 129.999994 -71.358252)
				)
			)
		)
		(polygon
			(pts
				(arc
					(start 127 -71.358252)
					(mid 127.35814 -71.000112)
					(end 127 -70.641972)
				)
				(arc
					(start 125.999748 -70.641972)
					(mid 125.641862 -71.000239)
					(end 126.000002 -71.358252)
				)
			)
		)
		(polygon
			(pts
				(arc
					(start 129.999994 -70.358254)
					(mid 130.358134 -70.000114)
					(end 129.999994 -69.641974)
				)
				(arc
					(start 128.999742 -69.641974)
					(mid 128.641856 -70.000241)
					(end 128.999996 -70.358254)
				)
			)
		)
		(polygon
			(pts
				(arc
					(start 127 -70.358254)
					(mid 127.35814 -70.000114)
					(end 127 -69.641974)
				)
				(arc
					(start 125.999748 -69.641974)
					(mid 125.641862 -70.000241)
					(end 126.000002 -70.358254)
				)
			)
		)
		(polygon
			(pts
				(arc
					(start 130.999992 -69.358256)
					(mid 131.358132 -69.000116)
					(end 130.999992 -68.641976)
				)
				(arc
					(start 129.99974 -68.641976)
					(mid 129.641854 -69.000243)
					(end 129.999994 -69.358256)
				)
			)
		)
		(polygon
			(pts
				(arc
					(start 127 -69.358256)
					(mid 127.35814 -69.000116)
					(end 127 -68.641976)
				)
				(arc
					(start 125.999748 -68.641976)
					(mid 125.641862 -69.000243)
					(end 126.000002 -69.358256)
				)
			)
		)
		(polygon
			(pts
				(arc
					(start 129.999994 -68.358258)
					(mid 130.358134 -68.000118)
					(end 129.999994 -67.641978)
				)
				(arc
					(start 128.999742 -67.641978)
					(mid 128.641856 -68.000245)
					(end 128.999996 -68.358258)
				)
			)
		)
		(polygon
			(pts
				(arc
					(start 127 -68.358258)
					(mid 127.35814 -68.000118)
					(end 127 -67.641978)
				)
				(arc
					(start 125.999748 -67.641978)
					(mid 125.641862 -68.000245)
					(end 126.000002 -68.358258)
				)
			)
		)
		(polygon
			(pts
				(arc
					(start 130.999992 -66.358262)
					(mid 131.358132 -66.000122)
					(end 130.999992 -65.641982)
				)
				(arc
					(start 129.99974 -65.641982)
					(mid 129.641854 -66.000249)
					(end 129.999994 -66.358262)
				)
			)
		)
		(polygon
			(pts
				(arc
					(start 127 -66.358262)
					(mid 127.35814 -66.000122)
					(end 127 -65.641982)
				)
				(arc
					(start 125.999748 -65.641982)
					(mid 125.641862 -66.000249)
					(end 126.000002 -66.358262)
				)
			)
		)
		(polygon
			(pts
				(arc
					(start 129.999994 -65.358264)
					(mid 130.358134 -65.000124)
					(end 129.999994 -64.641984)
				)
				(arc
					(start 128.999742 -64.641984)
					(mid 128.641856 -65.000251)
					(end 128.999996 -65.358264)
				)
			)
		)
		(polygon
			(pts
				(arc
					(start 127 -65.358264)
					(mid 127.35814 -65.000124)
					(end 127 -64.641984)
				)
				(arc
					(start 125.999748 -64.641984)
					(mid 125.641862 -65.000251)
					(end 126.000002 -65.358264)
				)
			)
		)
		(polygon
			(pts
				(arc
					(start 139.882372 -65.426844)
					(mid 140.336778 -64.972057)
					(end 139.882118 -64.517524)
				)
				(arc
					(start 138.739118 -64.517524)
					(mid 138.284458 -64.972184)
					(end 138.739118 -65.426844)
				)
			)
		)
		(polygon
			(pts
				(arc
					(start 143.235426 -64.273684)
					(mid 143.220547 -64.237763)
					(end 143.184626 -64.222884)
				)
				(arc
					(start 142.371826 -64.222884)
					(mid 142.335905 -64.237763)
					(end 142.321026 -64.273684)
				)
				(arc
					(start 142.321026 -64.476884)
					(mid 142.335905 -64.512805)
					(end 142.371826 -64.527684)
				)
				(arc
					(start 143.184626 -64.527684)
					(mid 143.220547 -64.512805)
					(end 143.235426 -64.476884)
				)
			)
		)
		(polygon
			(pts
				(arc
					(start 130.999992 -64.358266)
					(mid 131.358132 -64.000126)
					(end 130.999992 -63.641986)
				)
				(arc
					(start 129.99974 -63.641986)
					(mid 129.641854 -64.000253)
					(end 129.999994 -64.358266)
				)
			)
		)
		(polygon
			(pts
				(arc
					(start 127 -64.358266)
					(mid 127.35814 -64.000126)
					(end 127 -63.641986)
				)
				(arc
					(start 125.999748 -63.641986)
					(mid 125.641862 -64.000253)
					(end 126.000002 -64.358266)
				)
			)
		)
		(polygon
			(pts
				(arc
					(start 143.235426 -63.689484)
					(mid 143.220547 -63.653563)
					(end 143.184626 -63.638684)
				)
				(arc
					(start 142.371826 -63.638684)
					(mid 142.335905 -63.653563)
					(end 142.321026 -63.689484)
				)
				(arc
					(start 142.321026 -63.892684)
					(mid 142.335905 -63.928605)
					(end 142.371826 -63.943484)
				)
				(arc
					(start 143.184626 -63.943484)
					(mid 143.220547 -63.928605)
					(end 143.235426 -63.892684)
				)
			)
		)
		(polygon
			(pts
				(arc
					(start 129.999994 -63.358268)
					(mid 130.358134 -63.000128)
					(end 129.999994 -62.641988)
				)
				(arc
					(start 128.999742 -62.641988)
					(mid 128.641856 -63.000255)
					(end 128.999996 -63.358268)
				)
			)
		)
		(polygon
			(pts
				(arc
					(start 127 -63.358268)
					(mid 127.35814 -63.000128)
					(end 127 -62.641988)
				)
				(arc
					(start 125.999748 -62.641988)
					(mid 125.641862 -63.000255)
					(end 126.000002 -63.358268)
				)
			)
		)
		(polygon
			(pts
				(arc
					(start 139.947904 -63.499746)
					(mid 140.40231 -63.044959)
					(end 139.94765 -62.590426)
				)
				(arc
					(start 138.80465 -62.590426)
					(mid 138.34999 -63.045086)
					(end 138.80465 -63.499746)
				)
			)
		)
		(polygon
			(pts
				(arc
					(start 142.80896 -62.346586)
					(mid 142.794081 -62.310665)
					(end 142.75816 -62.295786)
				)
				(arc
					(start 141.94536 -62.295786)
					(mid 141.909439 -62.310665)
					(end 141.89456 -62.346586)
				)
				(arc
					(start 141.89456 -62.549786)
					(mid 141.909439 -62.585707)
					(end 141.94536 -62.600586)
				)
				(arc
					(start 142.75816 -62.600586)
					(mid 142.794081 -62.585707)
					(end 142.80896 -62.549786)
				)
			)
		)
		(polygon
			(pts
				(arc
					(start 142.80896 -61.762386)
					(mid 142.794081 -61.726465)
					(end 142.75816 -61.711586)
				)
				(arc
					(start 141.94536 -61.711586)
					(mid 141.909439 -61.726465)
					(end 141.89456 -61.762386)
				)
				(arc
					(start 141.89456 -61.965586)
					(mid 141.909439 -62.001507)
					(end 141.94536 -62.016386)
				)
				(arc
					(start 142.75816 -62.016386)
					(mid 142.794081 -62.001507)
					(end 142.80896 -61.965586)
				)
			)
		)
		(polygon
			(pts
				(arc
					(start 130.999992 -62.35827)
					(mid 131.358132 -62.00013)
					(end 130.999992 -61.64199)
				)
				(arc
					(start 129.99974 -61.64199)
					(mid 129.641854 -62.000257)
					(end 129.999994 -62.35827)
				)
			)
		)
		(polygon
			(pts
				(arc
					(start 127 -62.35827)
					(mid 127.35814 -62.00013)
					(end 127 -61.64199)
				)
				(arc
					(start 125.999748 -61.64199)
					(mid 125.641862 -62.000257)
					(end 126.000002 -62.35827)
				)
			)
		)
		(polygon
			(pts
				(arc
					(start 140.173964 -61.576712)
					(mid 140.62837 -61.121925)
					(end 140.17371 -60.667392)
				)
				(arc
					(start 139.03071 -60.667392)
					(mid 138.57605 -61.122052)
					(end 139.03071 -61.576712)
				)
			)
		)
		(polygon
			(pts
				(arc
					(start 129.999994 -61.358272)
					(mid 130.358134 -61.000132)
					(end 129.999994 -60.641992)
				)
				(arc
					(start 128.999742 -60.641992)
					(mid 128.641856 -61.000259)
					(end 128.999996 -61.358272)
				)
			)
		)
		(polygon
			(pts
				(arc
					(start 127 -61.358272)
					(mid 127.35814 -61.000132)
					(end 127 -60.641992)
				)
				(arc
					(start 125.999748 -60.641992)
					(mid 125.641862 -61.000259)
					(end 126.000002 -61.358272)
				)
			)
		)
		(polygon
			(pts
				(arc
					(start 143.03502 -60.423552)
					(mid 143.020141 -60.387631)
					(end 142.98422 -60.372752)
				)
				(arc
					(start 142.17142 -60.372752)
					(mid 142.135499 -60.387631)
					(end 142.12062 -60.423552)
				)
				(arc
					(start 142.12062 -60.626752)
					(mid 142.135499 -60.662673)
					(end 142.17142 -60.677552)
				)
				(arc
					(start 142.98422 -60.677552)
					(mid 143.020141 -60.662673)
					(end 143.03502 -60.626752)
				)
			)
		)
		(polygon
			(pts
				(arc
					(start 143.03502 -59.839352)
					(mid 143.020141 -59.803431)
					(end 142.98422 -59.788552)
				)
				(arc
					(start 142.17142 -59.788552)
					(mid 142.135499 -59.803431)
					(end 142.12062 -59.839352)
				)
				(arc
					(start 142.12062 -60.042552)
					(mid 142.135499 -60.078473)
					(end 142.17142 -60.093352)
				)
				(arc
					(start 142.98422 -60.093352)
					(mid 143.020141 -60.078473)
					(end 143.03502 -60.042552)
				)
			)
		)
		(polygon
			(pts
				(arc
					(start 127 -60.358274)
					(mid 127.35814 -60.000134)
					(end 127 -59.641994)
				)
				(arc
					(start 125.999748 -59.641994)
					(mid 125.641862 -60.000261)
					(end 126.000002 -60.358274)
				)
			)
		)
		(polygon
			(pts
				(arc
					(start 127 -59.358276)
					(mid 127.35814 -59.000136)
					(end 127 -58.641996)
				)
				(arc
					(start 125.999748 -58.641996)
					(mid 125.641862 -59.000263)
					(end 126.000002 -59.358276)
				)
			)
		)
		(polygon
			(pts
				(arc
					(start 140.589254 -59.35726)
					(mid 141.04366 -58.902473)
					(end 140.589 -58.44794)
				)
				(arc
					(start 139.446 -58.44794)
					(mid 138.99134 -58.9026)
					(end 139.446 -59.35726)
				)
			)
		)
		(polygon
			(pts
				(arc
					(start 143.45031 -58.2041)
					(mid 143.435431 -58.168179)
					(end 143.39951 -58.1533)
				)
				(arc
					(start 142.58671 -58.1533)
					(mid 142.550789 -58.168179)
					(end 142.53591 -58.2041)
				)
				(arc
					(start 142.53591 -58.4073)
					(mid 142.550789 -58.443221)
					(end 142.58671 -58.4581)
				)
				(arc
					(start 143.39951 -58.4581)
					(mid 143.435431 -58.443221)
					(end 143.45031 -58.4073)
				)
			)
		)
		(polygon
			(pts
				(arc
					(start 127 -58.358278)
					(mid 127.35814 -58.000138)
					(end 127 -57.641998)
				)
				(arc
					(start 125.999748 -57.641998)
					(mid 125.641862 -58.000265)
					(end 126.000002 -58.358278)
				)
			)
		)
		(polygon
			(pts
				(arc
					(start 143.45031 -57.6199)
					(mid 143.435431 -57.583979)
					(end 143.39951 -57.5691)
				)
				(arc
					(start 142.58671 -57.5691)
					(mid 142.550789 -57.583979)
					(end 142.53591 -57.6199)
				)
				(arc
					(start 142.53591 -57.8231)
					(mid 142.550789 -57.859021)
					(end 142.58671 -57.8739)
				)
				(arc
					(start 143.39951 -57.8739)
					(mid 143.435431 -57.859021)
					(end 143.45031 -57.8231)
				)
			)
		)
		(polygon
			(pts
				(arc
					(start 127 -57.35828)
					(mid 127.35814 -57.00014)
					(end 127 -56.642)
				)
				(arc
					(start 125.999748 -56.642)
					(mid 125.641862 -57.000267)
					(end 126.000002 -57.35828)
				)
			)
		)
		(polygon
			(pts
				(arc
					(start 127 -56.358282)
					(mid 127.35814 -56.000142)
					(end 127 -55.642002)
				)
				(arc
					(start 125.999748 -55.642002)
					(mid 125.641862 -56.000269)
					(end 126.000002 -56.358282)
				)
			)
		)
		(polygon
			(pts
				(xy 147.949412 -54.76367)
				(arc
					(start 147.938744 -54.762654)
					(mid 147.906807 -54.773949)
					(end 147.88896 -54.802786)
				)
				(arc
					(start 147.846796 -55.001668)
					(mid 147.853946 -55.039817)
					(end 147.885912 -55.061866)
				)
				(xy 148.010118 -55.088282) (xy 148.556726 -55.204614) (xy 148.680932 -55.23103) (xy 148.6916 -55.232046)
				(arc
					(start 148.702268 -55.23103)
					(mid 148.727602 -55.217248)
					(end 148.741384 -55.191914)
				)
				(arc
					(start 148.783548 -54.993032)
					(mid 148.776398 -54.954883)
					(end 148.744432 -54.932834)
				)
				(xy 148.620226 -54.906418) (xy 148.073618 -54.790086)
			)
		)
		(polygon
			(pts
				(arc
					(start 127 -55.358284)
					(mid 127.35814 -55.000144)
					(end 127 -54.642004)
				)
				(arc
					(start 125.999748 -54.642004)
					(mid 125.641862 -55.000271)
					(end 126.000002 -55.358284)
				)
			)
		)
		(polygon
			(pts
				(arc
					(start 124.358146 -55.000144)
					(mid 124.000006 -54.642004)
					(end 123.641866 -55.000144)
				)
				(arc
					(start 123.641866 -56.000396)
					(mid 124.000133 -56.358282)
					(end 124.358146 -56.000142)
				)
			)
		)
		(polygon
			(pts
				(arc
					(start 123.358148 -55.000144)
					(mid 123.000008 -54.642004)
					(end 122.641868 -55.000144)
				)
				(arc
					(start 122.641868 -56.000396)
					(mid 123.000135 -56.358282)
					(end 123.358148 -56.000142)
				)
			)
		)
		(polygon
			(pts
				(arc
					(start 122.35815 -55.000144)
					(mid 122.00001 -54.642004)
					(end 121.64187 -55.000144)
				)
				(arc
					(start 121.64187 -56.000396)
					(mid 122.000137 -56.358282)
					(end 122.35815 -56.000142)
				)
			)
		)
		(polygon
			(pts
				(arc
					(start 121.358152 -55.000144)
					(mid 121.000012 -54.642004)
					(end 120.641872 -55.000144)
				)
				(arc
					(start 120.641872 -56.000396)
					(mid 121.000139 -56.358282)
					(end 121.358152 -56.000142)
				)
			)
		)
		(polygon
			(pts
				(arc
					(start 120.358154 -55.000144)
					(mid 120.000014 -54.642004)
					(end 119.641874 -55.000144)
				)
				(arc
					(start 119.641874 -56.000396)
					(mid 120.000141 -56.358282)
					(end 120.358154 -56.000142)
				)
			)
		)
		(polygon
			(pts
				(arc
					(start 119.358156 -55.000144)
					(mid 119.000016 -54.642004)
					(end 118.641876 -55.000144)
				)
				(arc
					(start 118.641876 -56.000396)
					(mid 119.000143 -56.358282)
					(end 119.358156 -56.000142)
				)
			)
		)
		(polygon
			(pts
				(arc
					(start 118.358158 -55.000144)
					(mid 118.000018 -54.642004)
					(end 117.641878 -55.000144)
				)
				(arc
					(start 117.641878 -56.000396)
					(mid 118.000145 -56.358282)
					(end 118.358158 -56.000142)
				)
			)
		)
		(polygon
			(pts
				(arc
					(start 117.35816 -55.000144)
					(mid 117.00002 -54.642004)
					(end 116.64188 -55.000144)
				)
				(arc
					(start 116.64188 -56.000396)
					(mid 117.000147 -56.358282)
					(end 117.35816 -56.000142)
				)
			)
		)
		(polygon
			(pts
				(arc
					(start 116.358162 -55.000144)
					(mid 116.000022 -54.642004)
					(end 115.641882 -55.000144)
				)
				(arc
					(start 115.641882 -56.000396)
					(mid 116.000149 -56.358282)
					(end 116.358162 -56.000142)
				)
			)
		)
		(polygon
			(pts
				(arc
					(start 114.358166 -55.000144)
					(mid 114.000026 -54.642004)
					(end 113.641886 -55.000144)
				)
				(arc
					(start 113.641886 -56.000396)
					(mid 114.000153 -56.358282)
					(end 114.358166 -56.000142)
				)
			)
		)
		(polygon
			(pts
				(arc
					(start 113.358168 -55.000144)
					(mid 113.000028 -54.642004)
					(end 112.641888 -55.000144)
				)
				(arc
					(start 112.641888 -56.000396)
					(mid 113.000155 -56.358282)
					(end 113.358168 -56.000142)
				)
			)
		)
		(polygon
			(pts
				(arc
					(start 112.35817 -55.000144)
					(mid 112.00003 -54.642004)
					(end 111.64189 -55.000144)
				)
				(arc
					(start 111.64189 -56.000396)
					(mid 112.000157 -56.358282)
					(end 112.35817 -56.000142)
				)
			)
		)
		(polygon
			(pts
				(arc
					(start 111.358172 -55.000144)
					(mid 111.000032 -54.642004)
					(end 110.641892 -55.000144)
				)
				(arc
					(start 110.641892 -56.000396)
					(mid 111.000159 -56.358282)
					(end 111.358172 -56.000142)
				)
			)
		)
		(polygon
			(pts
				(arc
					(start 110.358174 -55.000144)
					(mid 110.000034 -54.642004)
					(end 109.641894 -55.000144)
				)
				(arc
					(start 109.641894 -56.000396)
					(mid 110.000161 -56.358282)
					(end 110.358174 -56.000142)
				)
			)
		)
		(polygon
			(pts
				(arc
					(start 109.358176 -55.000144)
					(mid 109.000036 -54.642004)
					(end 108.641896 -55.000144)
				)
				(arc
					(start 108.641896 -56.000396)
					(mid 109.000163 -56.358282)
					(end 109.358176 -56.000142)
				)
			)
		)
		(polygon
			(pts
				(arc
					(start 108.358178 -55.000144)
					(mid 108.000038 -54.642004)
					(end 107.641898 -55.000144)
				)
				(arc
					(start 107.641898 -56.000396)
					(mid 108.000165 -56.358282)
					(end 108.358178 -56.000142)
				)
			)
		)
		(polygon
			(pts
				(arc
					(start 107.35818 -55.000144)
					(mid 107.00004 -54.642004)
					(end 106.6419 -55.000144)
				)
				(arc
					(start 106.6419 -56.000396)
					(mid 107.000167 -56.358282)
					(end 107.35818 -56.000142)
				)
			)
		)
		(polygon
			(pts
				(arc
					(start 106.358182 -55.000144)
					(mid 106.000042 -54.642004)
					(end 105.641902 -55.000144)
				)
				(arc
					(start 105.641902 -56.000396)
					(mid 106.000169 -56.358282)
					(end 106.358182 -56.000142)
				)
			)
		)
		(polygon
			(pts
				(arc
					(start 105.358184 -55.000144)
					(mid 105.000044 -54.642004)
					(end 104.641904 -55.000144)
				)
				(arc
					(start 104.641904 -56.000396)
					(mid 105.000171 -56.358282)
					(end 105.358184 -56.000142)
				)
			)
		)
		(polygon
			(pts
				(arc
					(start 104.358186 -55.000144)
					(mid 104.000046 -54.642004)
					(end 103.641906 -55.000144)
				)
				(arc
					(start 103.641906 -56.000396)
					(mid 104.000173 -56.358282)
					(end 104.358186 -56.000142)
				)
			)
		)
		(polygon
			(pts
				(arc
					(start 103.358188 -55.000144)
					(mid 103.000048 -54.642004)
					(end 102.641908 -55.000144)
				)
				(arc
					(start 102.641908 -56.000396)
					(mid 103.000175 -56.358282)
					(end 103.358188 -56.000142)
				)
			)
		)
		(polygon
			(pts
				(arc
					(start 102.35819 -55.000144)
					(mid 102.00005 -54.642004)
					(end 101.64191 -55.000144)
				)
				(arc
					(start 101.64191 -56.000396)
					(mid 102.000177 -56.358282)
					(end 102.35819 -56.000142)
				)
			)
		)
		(polygon
			(pts
				(arc
					(start 101.358192 -55.000144)
					(mid 101.000052 -54.642004)
					(end 100.641912 -55.000144)
				)
				(arc
					(start 100.641912 -56.000396)
					(mid 101.000179 -56.358282)
					(end 101.358192 -56.000142)
				)
			)
		)
		(polygon
			(pts
				(arc
					(start 148.071078 -54.192424)
					(mid 148.032751 -54.199462)
					(end 148.010626 -54.23154)
				)
				(arc
					(start 147.968462 -54.430422)
					(mid 147.975612 -54.468571)
					(end 148.007578 -54.49062)
				)
				(xy 148.131784 -54.517036) (xy 148.678392 -54.633368)
				(arc
					(start 148.802598 -54.659784)
					(mid 148.840925 -54.652746)
					(end 148.86305 -54.620668)
				)
				(arc
					(start 148.905214 -54.421786)
					(mid 148.898064 -54.383637)
					(end 148.866098 -54.361588)
				)
				(xy 148.741892 -54.335172) (xy 148.195284 -54.21884)
			)
		)
		(polygon
			(pts
				(arc
					(start 150.087584 -54.478174)
					(mid 149.735286 -53.935884)
					(end 149.192996 -54.288182)
				)
				(arc
					(start 148.957792 -55.395876)
					(mid 149.302356 -55.947245)
					(end 149.84984 -55.596282)
				)
			)
		)
		(polygon
			(pts
				(arc
					(start 127 -54.358286)
					(mid 127.35814 -54.000146)
					(end 127 -53.642006)
				)
				(arc
					(start 125.999748 -53.642006)
					(mid 125.641862 -54.000273)
					(end 126.000002 -54.358286)
				)
			)
		)
		(polygon
			(pts
				(arc
					(start 99.358196 -54.000146)
					(mid 99.000056 -53.642006)
					(end 98.641916 -54.000146)
				)
				(arc
					(start 98.641916 -55.000398)
					(mid 99.000183 -55.358284)
					(end 99.358196 -55.000144)
				)
			)
		)
		(polygon
			(pts
				(arc
					(start 127.999998 -53.358288)
					(mid 128.358138 -53.000148)
					(end 127.999998 -52.642008)
				)
				(arc
					(start 126.999746 -52.642008)
					(mid 126.64186 -53.000275)
					(end 127 -53.358288)
				)
			)
		)
		(polygon
			(pts
				(arc
					(start 124.358146 -52.00015)
					(mid 124.000006 -51.64201)
					(end 123.641866 -52.00015)
				)
				(arc
					(start 123.641866 -53.000402)
					(mid 124.000133 -53.358288)
					(end 124.358146 -53.000148)
				)
			)
		)
		(polygon
			(pts
				(arc
					(start 122.35815 -52.00015)
					(mid 122.00001 -51.64201)
					(end 121.64187 -52.00015)
				)
				(arc
					(start 121.64187 -53.000402)
					(mid 122.000137 -53.358288)
					(end 122.35815 -53.000148)
				)
			)
		)
		(polygon
			(pts
				(arc
					(start 120.358154 -52.00015)
					(mid 120.000014 -51.64201)
					(end 119.641874 -52.00015)
				)
				(arc
					(start 119.641874 -53.000402)
					(mid 120.000141 -53.358288)
					(end 120.358154 -53.000148)
				)
			)
		)
		(polygon
			(pts
				(arc
					(start 118.358158 -52.00015)
					(mid 118.000018 -51.64201)
					(end 117.641878 -52.00015)
				)
				(arc
					(start 117.641878 -53.000402)
					(mid 118.000145 -53.358288)
					(end 118.358158 -53.000148)
				)
			)
		)
		(polygon
			(pts
				(arc
					(start 116.358162 -52.00015)
					(mid 116.000022 -51.64201)
					(end 115.641882 -52.00015)
				)
				(arc
					(start 115.641882 -53.000402)
					(mid 116.000149 -53.358288)
					(end 116.358162 -53.000148)
				)
			)
		)
		(polygon
			(pts
				(arc
					(start 113.358168 -52.00015)
					(mid 113.000028 -51.64201)
					(end 112.641888 -52.00015)
				)
				(arc
					(start 112.641888 -53.000402)
					(mid 113.000155 -53.358288)
					(end 113.358168 -53.000148)
				)
			)
		)
		(polygon
			(pts
				(arc
					(start 111.358172 -52.00015)
					(mid 111.000032 -51.64201)
					(end 110.641892 -52.00015)
				)
				(arc
					(start 110.641892 -53.000402)
					(mid 111.000159 -53.358288)
					(end 111.358172 -53.000148)
				)
			)
		)
		(polygon
			(pts
				(arc
					(start 109.358176 -52.00015)
					(mid 109.000036 -51.64201)
					(end 108.641896 -52.00015)
				)
				(arc
					(start 108.641896 -53.000402)
					(mid 109.000163 -53.358288)
					(end 109.358176 -53.000148)
				)
			)
		)
		(polygon
			(pts
				(arc
					(start 107.35818 -52.00015)
					(mid 107.00004 -51.64201)
					(end 106.6419 -52.00015)
				)
				(arc
					(start 106.6419 -53.000402)
					(mid 107.000167 -53.358288)
					(end 107.35818 -53.000148)
				)
			)
		)
		(polygon
			(pts
				(arc
					(start 105.358184 -52.00015)
					(mid 105.000044 -51.64201)
					(end 104.641904 -52.00015)
				)
				(arc
					(start 104.641904 -53.000402)
					(mid 105.000171 -53.358288)
					(end 105.358184 -53.000148)
				)
			)
		)
		(polygon
			(pts
				(arc
					(start 103.358188 -52.00015)
					(mid 103.000048 -51.64201)
					(end 102.641908 -52.00015)
				)
				(arc
					(start 102.641908 -53.000402)
					(mid 103.000175 -53.358288)
					(end 103.358188 -53.000148)
				)
			)
		)
		(polygon
			(pts
				(arc
					(start 101.358192 -52.00015)
					(mid 101.000052 -51.64201)
					(end 100.641912 -52.00015)
				)
				(arc
					(start 100.641912 -53.000402)
					(mid 101.000179 -53.358288)
					(end 101.358192 -53.000148)
				)
			)
		)
		(polygon
			(pts
				(arc
					(start 146.951446 -50.805588)
					(mid 146.913119 -50.812626)
					(end 146.890994 -50.844704)
				)
				(arc
					(start 146.84883 -51.043586)
					(mid 146.85598 -51.081735)
					(end 146.887946 -51.103784)
				)
				(xy 147.012152 -51.1302) (xy 147.55876 -51.246532)
				(arc
					(start 147.682966 -51.272948)
					(mid 147.721293 -51.26591)
					(end 147.743418 -51.233832)
				)
				(arc
					(start 147.785582 -51.03495)
					(mid 147.778432 -50.996801)
					(end 147.746466 -50.974752)
				)
				(xy 147.62226 -50.948336) (xy 147.075652 -50.832004)
			)
		)
		(polygon
			(pts
				(arc
					(start 123.358148 -51.000152)
					(mid 123.000008 -50.642012)
					(end 122.641868 -51.000152)
				)
				(arc
					(start 122.641868 -52.000404)
					(mid 123.000135 -52.35829)
					(end 123.358148 -52.00015)
				)
			)
		)
		(polygon
			(pts
				(arc
					(start 121.358152 -51.000152)
					(mid 121.000012 -50.642012)
					(end 120.641872 -51.000152)
				)
				(arc
					(start 120.641872 -52.000404)
					(mid 121.000139 -52.35829)
					(end 121.358152 -52.00015)
				)
			)
		)
		(polygon
			(pts
				(arc
					(start 119.358156 -51.000152)
					(mid 119.000016 -50.642012)
					(end 118.641876 -51.000152)
				)
				(arc
					(start 118.641876 -52.000404)
					(mid 119.000143 -52.35829)
					(end 119.358156 -52.00015)
				)
			)
		)
		(polygon
			(pts
				(arc
					(start 117.35816 -51.000152)
					(mid 117.00002 -50.642012)
					(end 116.64188 -51.000152)
				)
				(arc
					(start 116.64188 -52.000404)
					(mid 117.000147 -52.35829)
					(end 117.35816 -52.00015)
				)
			)
		)
		(polygon
			(pts
				(arc
					(start 114.358166 -51.000152)
					(mid 114.000026 -50.642012)
					(end 113.641886 -51.000152)
				)
				(arc
					(start 113.641886 -52.000404)
					(mid 114.000153 -52.35829)
					(end 114.358166 -52.00015)
				)
			)
		)
		(polygon
			(pts
				(arc
					(start 112.35817 -51.000152)
					(mid 112.00003 -50.642012)
					(end 111.64189 -51.000152)
				)
				(arc
					(start 111.64189 -52.000404)
					(mid 112.000157 -52.35829)
					(end 112.35817 -52.00015)
				)
			)
		)
		(polygon
			(pts
				(arc
					(start 110.358174 -51.000152)
					(mid 110.000034 -50.642012)
					(end 109.641894 -51.000152)
				)
				(arc
					(start 109.641894 -52.000404)
					(mid 110.000161 -52.35829)
					(end 110.358174 -52.00015)
				)
			)
		)
		(polygon
			(pts
				(arc
					(start 108.358178 -51.000152)
					(mid 108.000038 -50.642012)
					(end 107.641898 -51.000152)
				)
				(arc
					(start 107.641898 -52.000404)
					(mid 108.000165 -52.35829)
					(end 108.358178 -52.00015)
				)
			)
		)
		(polygon
			(pts
				(arc
					(start 106.358182 -51.000152)
					(mid 106.000042 -50.642012)
					(end 105.641902 -51.000152)
				)
				(arc
					(start 105.641902 -52.000404)
					(mid 106.000169 -52.35829)
					(end 106.358182 -52.00015)
				)
			)
		)
		(polygon
			(pts
				(arc
					(start 104.358186 -51.000152)
					(mid 104.000046 -50.642012)
					(end 103.641906 -51.000152)
				)
				(arc
					(start 103.641906 -52.000404)
					(mid 104.000173 -52.35829)
					(end 104.358186 -52.00015)
				)
			)
		)
		(polygon
			(pts
				(arc
					(start 102.35819 -51.000152)
					(mid 102.00005 -50.642012)
					(end 101.64191 -51.000152)
				)
				(arc
					(start 101.64191 -52.000404)
					(mid 102.000177 -52.35829)
					(end 102.35819 -52.00015)
				)
			)
		)
		(polygon
			(pts
				(arc
					(start 100.358194 -51.000152)
					(mid 100.000054 -50.642012)
					(end 99.641914 -51.000152)
				)
				(arc
					(start 99.641914 -52.000404)
					(mid 100.000181 -52.35829)
					(end 100.358194 -52.00015)
				)
			)
		)
		(polygon
			(pts
				(arc
					(start 147.072858 -50.234342)
					(mid 147.034531 -50.24138)
					(end 147.012406 -50.273458)
				)
				(arc
					(start 146.970242 -50.47234)
					(mid 146.977392 -50.510489)
					(end 147.009358 -50.532538)
				)
				(xy 147.133564 -50.558954) (xy 147.680172 -50.675286)
				(arc
					(start 147.804378 -50.701702)
					(mid 147.842705 -50.694664)
					(end 147.86483 -50.662586)
				)
				(arc
					(start 147.906994 -50.463704)
					(mid 147.899844 -50.425555)
					(end 147.867878 -50.403506)
				)
				(xy 147.743672 -50.37709) (xy 147.197064 -50.260758)
			)
		)
		(polygon
			(pts
				(arc
					(start 149.037294 -50.520092)
					(mid 148.69273 -49.968723)
					(end 148.145246 -50.319686)
				)
				(arc
					(start 147.907502 -51.437794)
					(mid 148.2598 -51.980084)
					(end 148.80209 -51.627786)
				)
			)
		)
		(polygon
			(pts
				(arc
					(start 145.884138 -46.80712)
					(mid 145.845811 -46.814158)
					(end 145.823686 -46.846236)
				)
				(arc
					(start 145.781522 -47.045118)
					(mid 145.788672 -47.083267)
					(end 145.820638 -47.105316)
				)
				(xy 145.944844 -47.131732) (xy 146.491452 -47.248064)
				(arc
					(start 146.615658 -47.27448)
					(mid 146.653985 -47.267442)
					(end 146.67611 -47.235364)
				)
				(arc
					(start 146.718274 -47.036482)
					(mid 146.711124 -46.998333)
					(end 146.679158 -46.976284)
				)
				(xy 146.554952 -46.949868) (xy 146.008344 -46.833536)
			)
		)
		(polygon
			(pts
				(arc
					(start 146.00555 -46.235874)
					(mid 145.967223 -46.242912)
					(end 145.945098 -46.27499)
				)
				(arc
					(start 145.902934 -46.473872)
					(mid 145.910084 -46.512021)
					(end 145.94205 -46.53407)
				)
				(xy 146.066256 -46.560486) (xy 146.612864 -46.676818)
				(arc
					(start 146.73707 -46.703234)
					(mid 146.775397 -46.696196)
					(end 146.797522 -46.664118)
				)
				(arc
					(start 146.839686 -46.465236)
					(mid 146.832536 -46.427087)
					(end 146.80057 -46.405038)
				)
				(xy 146.676364 -46.378622) (xy 146.129756 -46.26229)
			)
		)
		(polygon
			(pts
				(arc
					(start 147.989544 -46.551596)
					(mid 147.64498 -46.000227)
					(end 147.097496 -46.35119)
				)
				(arc
					(start 146.859752 -47.469298)
					(mid 147.21205 -48.011588)
					(end 147.75434 -47.65929)
				)
			)
		)
		(polygon
			(pts
				(arc
					(start 125.139958 -45.858938)
					(mid 124.682758 -45.401738)
					(end 124.225558 -45.858938)
				)
				(arc
					(start 124.225558 -47.002192)
					(mid 124.682885 -47.459138)
					(end 125.139958 -47.001938)
				)
			)
		)
		(polygon
			(pts
				(arc
					(start 127.533908 -45.844206)
					(mid 127.076708 -45.387006)
					(end 126.619508 -45.844206)
				)
				(arc
					(start 126.619508 -46.98746)
					(mid 127.076835 -47.444406)
					(end 127.533908 -46.987206)
				)
			)
		)
		(polygon
			(pts
				(arc
					(start 130.105658 -45.829474)
					(mid 129.648458 -45.372274)
					(end 129.191258 -45.829474)
				)
				(arc
					(start 129.191258 -46.972728)
					(mid 129.648585 -47.429674)
					(end 130.105658 -46.972474)
				)
			)
		)
		(polygon
			(pts
				(arc
					(start 132.677408 -45.814742)
					(mid 132.220208 -45.357542)
					(end 131.763008 -45.814742)
				)
				(arc
					(start 131.763008 -46.957996)
					(mid 132.220335 -47.414942)
					(end 132.677408 -46.957742)
				)
			)
		)
		(polygon
			(pts
				(arc
					(start 148.143976 -44.595034)
					(mid 148.105649 -44.602072)
					(end 148.083524 -44.63415)
				)
				(arc
					(start 148.04136 -44.833032)
					(mid 148.04851 -44.871181)
					(end 148.080476 -44.89323)
				)
				(xy 148.204682 -44.919646) (xy 148.75129 -45.035978)
				(arc
					(start 148.875496 -45.062394)
					(mid 148.913823 -45.055356)
					(end 148.935948 -45.023278)
				)
				(arc
					(start 148.978112 -44.824396)
					(mid 148.970962 -44.786247)
					(end 148.938996 -44.764198)
				)
				(xy 148.81479 -44.737782) (xy 148.268182 -44.62145)
			)
		)
		(polygon
			(pts
				(arc
					(start 126.263146 -44.34078)
					(mid 126.248267 -44.304859)
					(end 126.212346 -44.28998)
				)
				(arc
					(start 126.009146 -44.28998)
					(mid 125.973225 -44.304859)
					(end 125.958346 -44.34078)
				)
				(arc
					(start 125.958346 -45.15358)
					(mid 125.973225 -45.189501)
					(end 126.009146 -45.20438)
				)
				(arc
					(start 126.212346 -45.20438)
					(mid 126.248267 -45.189501)
					(end 126.263146 -45.15358)
				)
			)
		)
		(polygon
			(pts
				(arc
					(start 125.678946 -44.34078)
					(mid 125.664067 -44.304859)
					(end 125.628146 -44.28998)
				)
				(arc
					(start 125.424946 -44.28998)
					(mid 125.389025 -44.304859)
					(end 125.374146 -44.34078)
				)
				(arc
					(start 125.374146 -45.15358)
					(mid 125.389025 -45.189501)
					(end 125.424946 -45.20438)
				)
				(arc
					(start 125.628146 -45.20438)
					(mid 125.664067 -45.189501)
					(end 125.678946 -45.15358)
				)
			)
		)
		(polygon
			(pts
				(arc
					(start 128.73863 -44.326048)
					(mid 128.723751 -44.290127)
					(end 128.68783 -44.275248)
				)
				(arc
					(start 128.48463 -44.275248)
					(mid 128.448709 -44.290127)
					(end 128.43383 -44.326048)
				)
				(arc
					(start 128.43383 -45.138848)
					(mid 128.448709 -45.174769)
					(end 128.48463 -45.189648)
				)
				(arc
					(start 128.68783 -45.189648)
					(mid 128.723751 -45.174769)
					(end 128.73863 -45.138848)
				)
			)
		)
		(polygon
			(pts
				(arc
					(start 128.15443 -44.326048)
					(mid 128.139551 -44.290127)
					(end 128.10363 -44.275248)
				)
				(arc
					(start 127.90043 -44.275248)
					(mid 127.864509 -44.290127)
					(end 127.84963 -44.326048)
				)
				(arc
					(start 127.84963 -45.138848)
					(mid 127.864509 -45.174769)
					(end 127.90043 -45.189648)
				)
				(arc
					(start 128.10363 -45.189648)
					(mid 128.139551 -45.174769)
					(end 128.15443 -45.138848)
				)
			)
		)
		(polygon
			(pts
				(arc
					(start 131.31038 -44.311316)
					(mid 131.295501 -44.275395)
					(end 131.25958 -44.260516)
				)
				(arc
					(start 131.05638 -44.260516)
					(mid 131.020459 -44.275395)
					(end 131.00558 -44.311316)
				)
				(arc
					(start 131.00558 -45.124116)
					(mid 131.020459 -45.160037)
					(end 131.05638 -45.174916)
				)
				(arc
					(start 131.25958 -45.174916)
					(mid 131.295501 -45.160037)
					(end 131.31038 -45.124116)
				)
			)
		)
		(polygon
			(pts
				(arc
					(start 130.72618 -44.311316)
					(mid 130.711301 -44.275395)
					(end 130.67538 -44.260516)
				)
				(arc
					(start 130.47218 -44.260516)
					(mid 130.436259 -44.275395)
					(end 130.42138 -44.311316)
				)
				(arc
					(start 130.42138 -45.124116)
					(mid 130.436259 -45.160037)
					(end 130.47218 -45.174916)
				)
				(arc
					(start 130.67538 -45.174916)
					(mid 130.711301 -45.160037)
					(end 130.72618 -45.124116)
				)
			)
		)
		(polygon
			(pts
				(arc
					(start 133.88213 -44.296584)
					(mid 133.867251 -44.260663)
					(end 133.83133 -44.245784)
				)
				(arc
					(start 133.62813 -44.245784)
					(mid 133.592209 -44.260663)
					(end 133.57733 -44.296584)
				)
				(arc
					(start 133.57733 -45.109384)
					(mid 133.592209 -45.145305)
					(end 133.62813 -45.160184)
				)
				(arc
					(start 133.83133 -45.160184)
					(mid 133.867251 -45.145305)
					(end 133.88213 -45.109384)
				)
			)
		)
		(polygon
			(pts
				(arc
					(start 133.29793 -44.296584)
					(mid 133.283051 -44.260663)
					(end 133.24713 -44.245784)
				)
				(arc
					(start 133.04393 -44.245784)
					(mid 133.008009 -44.260663)
					(end 132.99313 -44.296584)
				)
				(arc
					(start 132.99313 -45.109384)
					(mid 133.008009 -45.145305)
					(end 133.04393 -45.160184)
				)
				(arc
					(start 133.24713 -45.160184)
					(mid 133.283051 -45.145305)
					(end 133.29793 -45.109384)
				)
			)
		)
		(polygon
			(pts
				(arc
					(start 148.265388 -44.023534)
					(mid 148.227061 -44.030572)
					(end 148.204936 -44.06265)
				)
				(arc
					(start 148.162772 -44.261532)
					(mid 148.169922 -44.299681)
					(end 148.201888 -44.32173)
				)
				(xy 148.326094 -44.348146) (xy 148.872702 -44.464478)
				(arc
					(start 148.996908 -44.490894)
					(mid 149.035235 -44.483856)
					(end 149.05736 -44.451778)
				)
				(arc
					(start 149.099524 -44.252896)
					(mid 149.092374 -44.214747)
					(end 149.060408 -44.192698)
				)
				(xy 148.936202 -44.166282) (xy 148.389594 -44.04995)
			)
		)
		(polygon
			(pts
				(arc
					(start 150.230078 -44.309284)
					(mid 149.885514 -43.757915)
					(end 149.33803 -44.108878)
				)
				(arc
					(start 149.100286 -45.226986)
					(mid 149.452584 -45.769276)
					(end 149.994874 -45.416978)
				)
			)
		)
		(polygon
			(pts
				(arc
					(start 147.104354 -40.57523)
					(mid 147.066027 -40.582268)
					(end 147.043902 -40.614346)
				)
				(arc
					(start 147.001738 -40.813228)
					(mid 147.008888 -40.851377)
					(end 147.040854 -40.873426)
				)
				(xy 147.16506 -40.899842) (xy 147.711668 -41.016174)
				(arc
					(start 147.835874 -41.04259)
					(mid 147.874201 -41.035552)
					(end 147.896326 -41.003474)
				)
				(arc
					(start 147.93849 -40.804592)
					(mid 147.93134 -40.766443)
					(end 147.899374 -40.744394)
				)
				(xy 147.775168 -40.717978) (xy 147.22856 -40.601646)
			)
		)
		(polygon
			(pts
				(arc
					(start 147.225766 -40.003984)
					(mid 147.187439 -40.011022)
					(end 147.165314 -40.0431)
				)
				(arc
					(start 147.12315 -40.241982)
					(mid 147.1303 -40.280131)
					(end 147.162266 -40.30218)
				)
				(xy 147.286472 -40.328596) (xy 147.83308 -40.444928)
				(arc
					(start 147.957286 -40.471344)
					(mid 147.995613 -40.464306)
					(end 148.017738 -40.432228)
				)
				(arc
					(start 148.059902 -40.233346)
					(mid 148.052752 -40.195197)
					(end 148.020786 -40.173148)
				)
				(xy 147.89658 -40.146732) (xy 147.349972 -40.0304)
			)
		)
		(polygon
			(pts
				(arc
					(start 149.309328 -40.340788)
					(mid 148.964764 -39.789419)
					(end 148.41728 -40.140382)
				)
				(arc
					(start 148.179536 -41.25849)
					(mid 148.531834 -41.80078)
					(end 149.074124 -41.448482)
				)
			)
		)
		(polygon
			(pts
				(arc
					(start 149.471888 -38.332918)
					(mid 149.433561 -38.339956)
					(end 149.411436 -38.372034)
				)
				(arc
					(start 149.369272 -38.570916)
					(mid 149.376422 -38.609065)
					(end 149.408388 -38.631114)
				)
				(xy 149.532594 -38.65753) (xy 150.079202 -38.773862)
				(arc
					(start 150.203408 -38.800278)
					(mid 150.241735 -38.79324)
					(end 150.26386 -38.761162)
				)
				(arc
					(start 150.306024 -38.56228)
					(mid 150.298874 -38.524131)
					(end 150.266908 -38.502082)
				)
				(xy 150.142702 -38.475666) (xy 149.596094 -38.359334)
			)
		)
		(polygon
			(pts
				(arc
					(start 149.5933 -37.761672)
					(mid 149.554973 -37.76871)
					(end 149.532848 -37.800788)
				)
				(arc
					(start 149.490684 -37.99967)
					(mid 149.497834 -38.037819)
					(end 149.5298 -38.059868)
				)
				(xy 149.654006 -38.086284) (xy 150.200614 -38.202616)
				(arc
					(start 150.32482 -38.229032)
					(mid 150.363147 -38.221994)
					(end 150.385272 -38.189916)
				)
				(arc
					(start 150.427436 -37.991034)
					(mid 150.420286 -37.952885)
					(end 150.38832 -37.930836)
				)
				(xy 150.264114 -37.90442) (xy 149.717506 -37.788088)
			)
		)
		(polygon
			(pts
				(arc
					(start 151.676862 -38.098476)
					(mid 151.332298 -37.547107)
					(end 150.784814 -37.89807)
				)
				(arc
					(start 150.54707 -39.016178)
					(mid 150.899368 -39.558468)
					(end 151.441658 -39.20617)
				)
			)
		)
		(polygon
			(pts
				(arc
					(start 166.58336 -37.59962)
					(mid 166.199693 -37.216334)
					(end 165.81628 -37.599874)
				)
				(arc
					(start 165.81628 -38.399974)
					(mid 166.19982 -38.783514)
					(end 166.58336 -38.399974)
				)
			)
		)
		(polygon
			(pts
				(arc
					(start 166.200074 -37.183568)
					(mid 166.58336 -36.799901)
					(end 166.19982 -36.416488)
				)
				(arc
					(start 165.399974 -36.416488)
					(mid 165.016434 -36.800028)
					(end 165.399974 -37.183568)
				)
			)
		)
		(polygon
			(pts
				(arc
					(start 147.703794 -35.493706)
					(mid 147.665467 -35.500744)
					(end 147.643342 -35.532822)
				)
				(arc
					(start 147.601178 -35.731704)
					(mid 147.608328 -35.769853)
					(end 147.640294 -35.791902)
				)
				(xy 147.7645 -35.818318) (xy 148.311108 -35.93465)
				(arc
					(start 148.435314 -35.961066)
					(mid 148.473641 -35.954028)
					(end 148.495766 -35.92195)
				)
				(arc
					(start 148.53793 -35.723068)
					(mid 148.53078 -35.684919)
					(end 148.498814 -35.66287)
				)
				(xy 148.374608 -35.636454) (xy 147.828 -35.520122)
			)
		)
		(polygon
			(pts
				(xy 18.270474 -34.9885) (xy 5.252466 -34.9885) (xy 4.55168 -35.689286) (xy 4.55168 -63.873634) (xy 5.199126 -64.52108)
				(xy 23.921974 -64.52108) (xy 25.02662 -63.416434) (xy 25.02662 -38.945566) (xy 23.886414 -37.80536)
				(xy 21.087334 -37.80536)
			)
		)
		(polygon
			(pts
				(arc
					(start 147.825206 -34.92246)
					(mid 147.786879 -34.929498)
					(end 147.764754 -34.961576)
				)
				(arc
					(start 147.72259 -35.160458)
					(mid 147.72974 -35.198607)
					(end 147.761706 -35.220656)
				)
				(xy 147.885912 -35.247072) (xy 148.43252 -35.363404)
				(arc
					(start 148.556726 -35.38982)
					(mid 148.595053 -35.382782)
					(end 148.617178 -35.350704)
				)
				(arc
					(start 148.659342 -35.151822)
					(mid 148.652192 -35.113673)
					(end 148.620226 -35.091624)
				)
				(xy 148.49602 -35.065208) (xy 147.949412 -34.948876)
			)
		)
		(polygon
			(pts
				(arc
					(start 166.58336 -35.199574)
					(mid 166.199693 -34.816288)
					(end 165.81628 -35.199828)
				)
				(arc
					(start 165.81628 -35.999928)
					(mid 166.19982 -36.383468)
					(end 166.58336 -35.999928)
				)
			)
		)
		(polygon
			(pts
				(arc
					(start 149.814534 -35.21329)
					(mid 149.46997 -34.661921)
					(end 148.922486 -35.012884)
				)
				(arc
					(start 148.684742 -36.130992)
					(mid 149.03704 -36.673282)
					(end 149.57933 -36.320984)
				)
			)
		)
		(polygon
			(pts
				(arc
					(start 166.200074 -34.783522)
					(mid 166.58336 -34.399855)
					(end 166.19982 -34.016442)
				)
				(arc
					(start 165.399974 -34.016442)
					(mid 165.016434 -34.399982)
					(end 165.399974 -34.783522)
				)
			)
		)
		(polygon
			(pts
				(arc
					(start 144.883378 -32.745934)
					(mid 144.845051 -32.752972)
					(end 144.822926 -32.78505)
				)
				(arc
					(start 144.780762 -32.983932)
					(mid 144.787912 -33.022081)
					(end 144.819878 -33.04413)
				)
				(xy 144.944084 -33.070546) (xy 145.490692 -33.186878)
				(arc
					(start 145.614898 -33.213294)
					(mid 145.653225 -33.206256)
					(end 145.67535 -33.174178)
				)
				(arc
					(start 145.717514 -32.975296)
					(mid 145.710364 -32.937147)
					(end 145.678398 -32.915098)
				)
				(xy 145.554192 -32.888682) (xy 145.007584 -32.77235)
			)
		)
		(polygon
			(pts
				(arc
					(start 166.58336 -32.799782)
					(mid 166.199693 -32.416496)
					(end 165.81628 -32.800036)
				)
				(arc
					(start 165.81628 -33.599882)
					(mid 166.19982 -33.983422)
					(end 166.58336 -33.599882)
				)
			)
		)
		(polygon
			(pts
				(arc
					(start 145.00479 -32.174434)
					(mid 144.966463 -32.181472)
					(end 144.944338 -32.21355)
				)
				(arc
					(start 144.902174 -32.412432)
					(mid 144.909324 -32.450581)
					(end 144.94129 -32.47263)
				)
				(xy 145.065496 -32.499046) (xy 145.612104 -32.615378) (xy 145.73631 -32.641794)
				(arc
					(start 145.746978 -32.64281)
					(mid 145.778915 -32.631515)
					(end 145.796762 -32.602678)
				)
				(arc
					(start 145.838926 -32.403796)
					(mid 145.831776 -32.365647)
					(end 145.79981 -32.343598)
				)
				(xy 145.675604 -32.317182) (xy 145.128996 -32.20085)
			)
		)
		(polygon
			(pts
				(arc
					(start 146.969226 -32.460184)
					(mid 146.624662 -31.908815)
					(end 146.077178 -32.259778)
				)
				(arc
					(start 145.839434 -33.377886)
					(mid 146.191732 -33.920176)
					(end 146.734022 -33.567878)
				)
			)
		)
		(polygon
			(pts
				(arc
					(start 167.000174 -32.383476)
					(mid 167.38346 -31.999809)
					(end 166.99992 -31.616396)
				)
				(arc
					(start 166.200074 -31.616396)
					(mid 165.816534 -31.999936)
					(end 166.200074 -32.383476)
				)
			)
		)
		(polygon
			(pts
				(arc
					(start 176.158144 -30.400244)
					(mid 175.800004 -30.042104)
					(end 175.441864 -30.400244)
				)
				(arc
					(start 175.441864 -31.200344)
					(mid 175.800131 -31.55823)
					(end 176.158144 -31.20009)
				)
			)
		)
		(polygon
			(pts
				(arc
					(start 168.958006 -30.39999)
					(mid 168.599866 -30.04185)
					(end 168.241726 -30.39999)
				)
				(arc
					(start 168.241726 -31.20009)
					(mid 168.599993 -31.557976)
					(end 168.958006 -31.199836)
				)
			)
		)
		(polygon
			(pts
				(arc
					(start 175.358044 -30.39999)
					(mid 174.999777 -30.04185)
					(end 174.641764 -30.400244)
				)
				(arc
					(start 174.642018 -31.199836)
					(mid 175.000158 -31.55823)
					(end 175.358298 -31.199836)
				)
				(xy 175.358044 -30.400244)
			)
		)
		(polygon
			(pts
				(arc
					(start 173.758098 -30.39999)
					(mid 173.399831 -30.04185)
					(end 173.041818 -30.400244)
				)
				(arc
					(start 173.042072 -31.199836)
					(mid 173.400212 -31.55823)
					(end 173.758352 -31.199836)
				)
				(xy 173.758098 -30.400244)
			)
		)
		(polygon
			(pts
				(arc
					(start 172.957998 -30.39999)
					(mid 172.599731 -30.04185)
					(end 172.241718 -30.400244)
				)
				(arc
					(start 172.241972 -31.199836)
					(mid 172.600112 -31.55823)
					(end 172.958252 -31.199836)
				)
				(xy 172.957998 -30.400244)
			)
		)
		(polygon
			(pts
				(arc
					(start 171.358052 -30.39999)
					(mid 170.999785 -30.04185)
					(end 170.641772 -30.400244)
				)
				(arc
					(start 170.642026 -31.199836)
					(mid 171.000166 -31.55823)
					(end 171.358306 -31.199836)
				)
				(xy 171.358052 -30.400244)
			)
		)
		(polygon
			(pts
				(arc
					(start 170.557952 -30.39999)
					(mid 170.199685 -30.04185)
					(end 169.841672 -30.400244)
				)
				(arc
					(start 169.841926 -31.199836)
					(mid 170.200066 -31.55823)
					(end 170.558206 -31.199836)
				)
				(xy 170.557952 -30.400244)
			)
		)
		(polygon
			(pts
				(arc
					(start 168.157906 -30.39999)
					(mid 167.799639 -30.04185)
					(end 167.441626 -30.400244)
				)
				(arc
					(start 167.44188 -31.199582)
					(mid 167.80002 -31.557976)
					(end 168.15816 -31.199582)
				)
				(xy 168.157906 -30.400244)
			)
		)
		(polygon
			(pts
				(arc
					(start 166.58336 -30.399736)
					(mid 166.199693 -30.01645)
					(end 165.81628 -30.39999)
				)
				(arc
					(start 165.81628 -31.199836)
					(mid 166.19982 -31.583376)
					(end 166.58336 -31.199836)
				)
			)
		)
		(polygon
			(pts
				(arc
					(start 166.200074 -29.21635)
					(mid 165.81628 -29.599763)
					(end 166.19982 -29.98343)
				)
				(arc
					(start 166.999412 -29.983684)
					(mid 167.383206 -29.600271)
					(end 166.999666 -29.216604)
				)
			)
		)
		(polygon
			(pts
				(arc
					(start 180.819552 -23.596346)
					(mid 180.436012 -23.212806)
					(end 180.052472 -23.596346)
				)
				(arc
					(start 180.052472 -24.4856)
					(mid 180.436139 -24.868886)
					(end 180.819552 -24.485346)
				)
			)
		)
		(polygon
			(pts
				(arc
					(start 166.508938 -23.166832)
					(mid 166.125398 -22.783292)
					(end 165.741858 -23.166832)
				)
				(arc
					(start 165.741858 -24.056086)
					(mid 166.125525 -24.439372)
					(end 166.508938 -24.055832)
				)
			)
		)
		(polygon
			(pts
				(arc
					(start 168.543478 -23.123906)
					(mid 168.159938 -22.740366)
					(end 167.776398 -23.123906)
				)
				(arc
					(start 167.776398 -24.01316)
					(mid 168.160065 -24.396446)
					(end 168.543478 -24.012906)
				)
			)
		)
		(polygon
			(pts
				(arc
					(start 178.790854 -23.11654)
					(mid 178.407314 -22.733)
					(end 178.023774 -23.11654)
				)
				(arc
					(start 178.023774 -24.005794)
					(mid 178.407441 -24.38908)
					(end 178.790854 -24.00554)
				)
			)
		)
		(polygon
			(pts
				(arc
					(start 170.600624 -23.11527)
					(mid 170.217084 -22.73173)
					(end 169.833544 -23.11527)
				)
				(arc
					(start 169.833544 -24.004524)
					(mid 170.217211 -24.38781)
					(end 170.600624 -24.00427)
				)
			)
		)
		(polygon
			(pts
				(arc
					(start 172.65269 -23.112984)
					(mid 172.26915 -22.729444)
					(end 171.88561 -23.112984)
				)
				(arc
					(start 171.88561 -24.002238)
					(mid 172.269277 -24.385524)
					(end 172.65269 -24.001984)
				)
			)
		)
		(polygon
			(pts
				(arc
					(start 174.698406 -23.112476)
					(mid 174.314866 -22.728936)
					(end 173.931326 -23.112476)
				)
				(arc
					(start 173.931326 -24.00173)
					(mid 174.314993 -24.385016)
					(end 174.698406 -24.001476)
				)
			)
		)
		(polygon
			(pts
				(arc
					(start 176.75225 -23.103332)
					(mid 176.36871 -22.719792)
					(end 175.98517 -23.103332)
				)
				(arc
					(start 175.98517 -23.992586)
					(mid 176.368837 -24.375872)
					(end 176.75225 -23.992332)
				)
			)
		)
		(polygon
			(pts
				(arc
					(start 191.361314 -10.999978)
					(mid 190.799974 -10.438638)
					(end 190.238634 -10.999978)
				)
				(arc
					(start 190.238634 -12.40028)
					(mid 190.800101 -12.961366)
					(end 191.361314 -12.400026)
				)
			)
		)
		(polygon
			(pts
				(arc
					(start 187.761118 -10.999978)
					(mid 187.199778 -10.438638)
					(end 186.638438 -10.999978)
				)
				(arc
					(start 186.638438 -12.40028)
					(mid 187.199905 -12.961366)
					(end 187.761118 -12.400026)
				)
			)
		)
		(polygon
			(pts
				(arc
					(start 184.161176 -10.999978)
					(mid 183.599836 -10.438638)
					(end 183.038496 -10.999978)
				)
				(arc
					(start 183.038496 -12.40028)
					(mid 183.599963 -12.961366)
					(end 184.161176 -12.400026)
				)
			)
		)
		(polygon
			(pts
				(arc
					(start 180.561234 -10.999978)
					(mid 179.999894 -10.438638)
					(end 179.438554 -10.999978)
				)
				(arc
					(start 179.438554 -12.40028)
					(mid 180.000021 -12.961366)
					(end 180.561234 -12.400026)
				)
			)
		)
		(polygon
			(pts
				(arc
					(start 147.761452 -10.999978)
					(mid 147.200112 -10.438638)
					(end 146.638772 -10.999978)
				)
				(arc
					(start 146.638772 -12.40028)
					(mid 147.200239 -12.961366)
					(end 147.761452 -12.400026)
				)
			)
		)
		(polygon
			(pts
				(arc
					(start 144.16151 -10.999978)
					(mid 143.60017 -10.438638)
					(end 143.03883 -10.999978)
				)
				(arc
					(start 143.03883 -12.40028)
					(mid 143.600297 -12.961366)
					(end 144.16151 -12.400026)
				)
			)
		)
		(polygon
			(pts
				(arc
					(start 140.561314 -10.999978)
					(mid 139.999974 -10.438638)
					(end 139.438634 -10.999978)
				)
				(arc
					(start 139.438634 -12.40028)
					(mid 140.000101 -12.961366)
					(end 140.561314 -12.400026)
				)
			)
		)
		(polygon
			(pts
				(arc
					(start 136.961372 -10.999978)
					(mid 136.400032 -10.438638)
					(end 135.838692 -10.999978)
				)
				(arc
					(start 135.838692 -12.40028)
					(mid 136.400159 -12.961366)
					(end 136.961372 -12.400026)
				)
			)
		)
		(polygon
			(pts
				(arc
					(start 133.36143 -10.999978)
					(mid 132.80009 -10.438638)
					(end 132.23875 -10.999978)
				)
				(arc
					(start 132.23875 -12.40028)
					(mid 132.800217 -12.961366)
					(end 133.36143 -12.400026)
				)
			)
		)
		(polygon
			(pts
				(arc
					(start 129.761488 -10.999978)
					(mid 129.200148 -10.438638)
					(end 128.638808 -10.999978)
				)
				(arc
					(start 128.638808 -12.40028)
					(mid 129.200275 -12.961366)
					(end 129.761488 -12.400026)
				)
			)
		)
		(polygon
			(pts
				(arc
					(start 126.161546 -10.999978)
					(mid 125.600206 -10.438638)
					(end 125.038866 -10.999978)
				)
				(arc
					(start 125.038866 -12.40028)
					(mid 125.600333 -12.961366)
					(end 126.161546 -12.400026)
				)
			)
		)
		(polygon
			(pts
				(arc
					(start 122.56135 -10.999978)
					(mid 122.00001 -10.438638)
					(end 121.43867 -10.999978)
				)
				(arc
					(start 121.43867 -12.40028)
					(mid 122.000137 -12.961366)
					(end 122.56135 -12.400026)
				)
			)
		)
		(polygon
			(pts
				(arc
					(start 118.961408 -10.999978)
					(mid 118.400068 -10.438638)
					(end 117.838728 -10.999978)
				)
				(arc
					(start 117.838728 -12.40028)
					(mid 118.400195 -12.961366)
					(end 118.961408 -12.400026)
				)
			)
		)
		(polygon
			(pts
				(arc
					(start 115.361466 -10.999978)
					(mid 114.800126 -10.438638)
					(end 114.238786 -10.999978)
				)
				(arc
					(start 114.238786 -12.40028)
					(mid 114.800253 -12.961366)
					(end 115.361466 -12.400026)
				)
			)
		)
		(polygon
			(pts
				(arc
					(start 111.761524 -10.999978)
					(mid 111.200184 -10.438638)
					(end 110.638844 -10.999978)
				)
				(arc
					(start 110.638844 -12.40028)
					(mid 111.200311 -12.961366)
					(end 111.761524 -12.400026)
				)
			)
		)
		(polygon
			(pts
				(arc
					(start 108.161328 -10.999978)
					(mid 107.599988 -10.438638)
					(end 107.038648 -10.999978)
				)
				(arc
					(start 107.038648 -12.40028)
					(mid 107.600115 -12.961366)
					(end 108.161328 -12.400026)
				)
			)
		)
		(polygon
			(pts
				(arc
					(start 104.561386 -10.999978)
					(mid 104.000046 -10.438638)
					(end 103.438706 -10.999978)
				)
				(arc
					(start 103.438706 -12.40028)
					(mid 104.000173 -12.961366)
					(end 104.561386 -12.400026)
				)
			)
		)
		(polygon
			(pts
				(arc
					(start 100.961444 -10.999978)
					(mid 100.400104 -10.438638)
					(end 99.838764 -10.999978)
				)
				(arc
					(start 99.838764 -12.40028)
					(mid 100.400231 -12.961366)
					(end 100.961444 -12.400026)
				)
			)
		)
		(polygon
			(pts
				(arc
					(start 97.361502 -10.999978)
					(mid 96.800162 -10.438638)
					(end 96.238822 -10.999978)
				)
				(arc
					(start 96.238822 -12.40028)
					(mid 96.800289 -12.961366)
					(end 97.361502 -12.400026)
				)
			)
		)
		(polygon
			(pts
				(arc
					(start 93.761306 -10.999978)
					(mid 93.199966 -10.438638)
					(end 92.638626 -10.999978)
				)
				(arc
					(start 92.638626 -12.40028)
					(mid 93.200093 -12.961366)
					(end 93.761306 -12.400026)
				)
			)
		)
		(polygon
			(pts
				(arc
					(start 90.161364 -10.999978)
					(mid 89.600024 -10.438638)
					(end 89.038684 -10.999978)
				)
				(arc
					(start 89.038684 -12.40028)
					(mid 89.600151 -12.961366)
					(end 90.161364 -12.400026)
				)
			)
		)
		(polygon
			(pts
				(arc
					(start 86.561422 -10.999978)
					(mid 86.000082 -10.438638)
					(end 85.438742 -10.999978)
				)
				(arc
					(start 85.438742 -12.40028)
					(mid 86.000209 -12.961366)
					(end 86.561422 -12.400026)
				)
			)
		)
		(polygon
			(pts
				(arc
					(start 193.161158 -9.800082)
					(mid 192.599818 -9.238742)
					(end 192.038478 -9.800082)
				)
				(arc
					(start 192.038478 -11.200384)
					(mid 192.599945 -11.76147)
					(end 193.161158 -11.20013)
				)
			)
		)
		(polygon
			(pts
				(arc
					(start 189.561216 -9.800082)
					(mid 188.999876 -9.238742)
					(end 188.438536 -9.800082)
				)
				(arc
					(start 188.438536 -11.200384)
					(mid 189.000003 -11.76147)
					(end 189.561216 -11.20013)
				)
			)
		)
		(polygon
			(pts
				(arc
					(start 185.961274 -9.800082)
					(mid 185.399934 -9.238742)
					(end 184.838594 -9.800082)
				)
				(arc
					(start 184.838594 -11.200384)
					(mid 185.400061 -11.76147)
					(end 185.961274 -11.20013)
				)
			)
		)
		(polygon
			(pts
				(arc
					(start 182.361332 -9.800082)
					(mid 181.799992 -9.238742)
					(end 181.238652 -9.800082)
				)
				(arc
					(start 181.238652 -11.200384)
					(mid 181.800119 -11.76147)
					(end 182.361332 -11.20013)
				)
			)
		)
		(polygon
			(pts
				(arc
					(start 149.561296 -9.800082)
					(mid 148.999956 -9.238742)
					(end 148.438616 -9.800082)
				)
				(arc
					(start 148.438616 -11.200384)
					(mid 149.000083 -11.76147)
					(end 149.561296 -11.20013)
				)
			)
		)
		(polygon
			(pts
				(arc
					(start 145.961354 -9.800082)
					(mid 145.400014 -9.238742)
					(end 144.838674 -9.800082)
				)
				(arc
					(start 144.838674 -11.200384)
					(mid 145.400141 -11.76147)
					(end 145.961354 -11.20013)
				)
			)
		)
		(polygon
			(pts
				(arc
					(start 142.361412 -9.800082)
					(mid 141.800072 -9.238742)
					(end 141.238732 -9.800082)
				)
				(arc
					(start 141.238732 -11.200384)
					(mid 141.800199 -11.76147)
					(end 142.361412 -11.20013)
				)
			)
		)
		(polygon
			(pts
				(arc
					(start 138.76147 -9.800082)
					(mid 138.20013 -9.238742)
					(end 137.63879 -9.800082)
				)
				(arc
					(start 137.63879 -11.200384)
					(mid 138.200257 -11.76147)
					(end 138.76147 -11.20013)
				)
			)
		)
		(polygon
			(pts
				(arc
					(start 135.161528 -9.800082)
					(mid 134.600188 -9.238742)
					(end 134.038848 -9.800082)
				)
				(arc
					(start 134.038848 -11.200384)
					(mid 134.600315 -11.76147)
					(end 135.161528 -11.20013)
				)
			)
		)
		(polygon
			(pts
				(arc
					(start 131.561332 -9.800082)
					(mid 130.999992 -9.238742)
					(end 130.438652 -9.800082)
				)
				(arc
					(start 130.438652 -11.200384)
					(mid 131.000119 -11.76147)
					(end 131.561332 -11.20013)
				)
			)
		)
		(polygon
			(pts
				(arc
					(start 127.96139 -9.800082)
					(mid 127.40005 -9.238742)
					(end 126.83871 -9.800082)
				)
				(arc
					(start 126.83871 -11.200384)
					(mid 127.400177 -11.76147)
					(end 127.96139 -11.20013)
				)
			)
		)
		(polygon
			(pts
				(arc
					(start 124.361448 -9.800082)
					(mid 123.800108 -9.238742)
					(end 123.238768 -9.800082)
				)
				(arc
					(start 123.238768 -11.200384)
					(mid 123.800235 -11.76147)
					(end 124.361448 -11.20013)
				)
			)
		)
		(polygon
			(pts
				(arc
					(start 120.761506 -9.800082)
					(mid 120.200166 -9.238742)
					(end 119.638826 -9.800082)
				)
				(arc
					(start 119.638826 -11.200384)
					(mid 120.200293 -11.76147)
					(end 120.761506 -11.20013)
				)
			)
		)
		(polygon
			(pts
				(arc
					(start 117.16131 -9.800082)
					(mid 116.59997 -9.238742)
					(end 116.03863 -9.800082)
				)
				(arc
					(start 116.03863 -11.200384)
					(mid 116.600097 -11.76147)
					(end 117.16131 -11.20013)
				)
			)
		)
		(polygon
			(pts
				(arc
					(start 113.561368 -9.800082)
					(mid 113.000028 -9.238742)
					(end 112.438688 -9.800082)
				)
				(arc
					(start 112.438688 -11.200384)
					(mid 113.000155 -11.76147)
					(end 113.561368 -11.20013)
				)
			)
		)
		(polygon
			(pts
				(arc
					(start 109.961426 -9.800082)
					(mid 109.400086 -9.238742)
					(end 108.838746 -9.800082)
				)
				(arc
					(start 108.838746 -11.200384)
					(mid 109.400213 -11.76147)
					(end 109.961426 -11.20013)
				)
			)
		)
		(polygon
			(pts
				(arc
					(start 106.361484 -9.800082)
					(mid 105.800144 -9.238742)
					(end 105.238804 -9.800082)
				)
				(arc
					(start 105.238804 -11.200384)
					(mid 105.800271 -11.76147)
					(end 106.361484 -11.20013)
				)
			)
		)
		(polygon
			(pts
				(arc
					(start 102.761542 -9.800082)
					(mid 102.200202 -9.238742)
					(end 101.638862 -9.800082)
				)
				(arc
					(start 101.638862 -11.200384)
					(mid 102.200329 -11.76147)
					(end 102.761542 -11.20013)
				)
			)
		)
		(polygon
			(pts
				(arc
					(start 99.161346 -9.800082)
					(mid 98.600006 -9.238742)
					(end 98.038666 -9.800082)
				)
				(arc
					(start 98.038666 -11.200384)
					(mid 98.600133 -11.76147)
					(end 99.161346 -11.20013)
				)
			)
		)
		(polygon
			(pts
				(arc
					(start 95.561404 -9.800082)
					(mid 95.000064 -9.238742)
					(end 94.438724 -9.800082)
				)
				(arc
					(start 94.438724 -11.200384)
					(mid 95.000191 -11.76147)
					(end 95.561404 -11.20013)
				)
			)
		)
		(polygon
			(pts
				(arc
					(start 91.961462 -9.800082)
					(mid 91.400122 -9.238742)
					(end 90.838782 -9.800082)
				)
				(arc
					(start 90.838782 -11.200384)
					(mid 91.400249 -11.76147)
					(end 91.961462 -11.20013)
				)
			)
		)
		(polygon
			(pts
				(arc
					(start 88.36152 -9.800082)
					(mid 87.80018 -9.238742)
					(end 87.23884 -9.800082)
				)
				(arc
					(start 87.23884 -11.200384)
					(mid 87.800307 -11.76147)
					(end 88.36152 -11.20013)
				)
			)
		)
		(polygon
			(pts
				(arc
					(start 180.561234 -7.400036)
					(mid 179.999894 -6.838696)
					(end 179.438554 -7.400036)
				)
				(arc
					(start 179.438554 -8.800338)
					(mid 180.000021 -9.361424)
					(end 180.561234 -8.800084)
				)
			)
		)
		(polygon
			(pts
				(arc
					(start 191.361314 -3.800094)
					(mid 190.799974 -3.238754)
					(end 190.238634 -3.800094)
				)
				(arc
					(start 190.238634 -5.200396)
					(mid 190.800101 -5.761482)
					(end 191.361314 -5.200142)
				)
			)
		)
		(polygon
			(pts
				(arc
					(start 187.761118 -3.800094)
					(mid 187.199778 -3.238754)
					(end 186.638438 -3.800094)
				)
				(arc
					(start 186.638438 -5.200396)
					(mid 187.199905 -5.761482)
					(end 187.761118 -5.200142)
				)
			)
		)
		(polygon
			(pts
				(arc
					(start 184.161176 -3.800094)
					(mid 183.599836 -3.238754)
					(end 183.038496 -3.800094)
				)
				(arc
					(start 183.038496 -5.200396)
					(mid 183.599963 -5.761482)
					(end 184.161176 -5.200142)
				)
			)
		)
		(polygon
			(pts
				(arc
					(start 180.561234 -3.800094)
					(mid 179.999894 -3.238754)
					(end 179.438554 -3.800094)
				)
				(arc
					(start 179.438554 -5.200396)
					(mid 180.000021 -5.761482)
					(end 180.561234 -5.200142)
				)
			)
		)
		(polygon
			(pts
				(arc
					(start 147.761452 -3.800094)
					(mid 147.200112 -3.238754)
					(end 146.638772 -3.800094)
				)
				(arc
					(start 146.638772 -5.200396)
					(mid 147.200239 -5.761482)
					(end 147.761452 -5.200142)
				)
			)
		)
		(polygon
			(pts
				(arc
					(start 144.16151 -3.800094)
					(mid 143.60017 -3.238754)
					(end 143.03883 -3.800094)
				)
				(arc
					(start 143.03883 -5.200396)
					(mid 143.600297 -5.761482)
					(end 144.16151 -5.200142)
				)
			)
		)
		(polygon
			(pts
				(arc
					(start 140.561314 -3.800094)
					(mid 139.999974 -3.238754)
					(end 139.438634 -3.800094)
				)
				(arc
					(start 139.438634 -5.200396)
					(mid 140.000101 -5.761482)
					(end 140.561314 -5.200142)
				)
			)
		)
		(polygon
			(pts
				(arc
					(start 136.961372 -3.800094)
					(mid 136.400032 -3.238754)
					(end 135.838692 -3.800094)
				)
				(arc
					(start 135.838692 -5.200396)
					(mid 136.400159 -5.761482)
					(end 136.961372 -5.200142)
				)
			)
		)
		(polygon
			(pts
				(arc
					(start 133.36143 -3.800094)
					(mid 132.80009 -3.238754)
					(end 132.23875 -3.800094)
				)
				(arc
					(start 132.23875 -5.200396)
					(mid 132.800217 -5.761482)
					(end 133.36143 -5.200142)
				)
			)
		)
		(polygon
			(pts
				(arc
					(start 129.761488 -3.800094)
					(mid 129.200148 -3.238754)
					(end 128.638808 -3.800094)
				)
				(arc
					(start 128.638808 -5.200396)
					(mid 129.200275 -5.761482)
					(end 129.761488 -5.200142)
				)
			)
		)
		(polygon
			(pts
				(arc
					(start 126.161546 -3.800094)
					(mid 125.600206 -3.238754)
					(end 125.038866 -3.800094)
				)
				(arc
					(start 125.038866 -5.200396)
					(mid 125.600333 -5.761482)
					(end 126.161546 -5.200142)
				)
			)
		)
		(polygon
			(pts
				(arc
					(start 122.56135 -3.800094)
					(mid 122.00001 -3.238754)
					(end 121.43867 -3.800094)
				)
				(arc
					(start 121.43867 -5.200396)
					(mid 122.000137 -5.761482)
					(end 122.56135 -5.200142)
				)
			)
		)
		(polygon
			(pts
				(arc
					(start 118.961408 -3.800094)
					(mid 118.400068 -3.238754)
					(end 117.838728 -3.800094)
				)
				(arc
					(start 117.838728 -5.200396)
					(mid 118.400195 -5.761482)
					(end 118.961408 -5.200142)
				)
			)
		)
		(polygon
			(pts
				(arc
					(start 115.361466 -3.800094)
					(mid 114.800126 -3.238754)
					(end 114.238786 -3.800094)
				)
				(arc
					(start 114.238786 -5.200396)
					(mid 114.800253 -5.761482)
					(end 115.361466 -5.200142)
				)
			)
		)
		(polygon
			(pts
				(arc
					(start 111.761524 -3.800094)
					(mid 111.200184 -3.238754)
					(end 110.638844 -3.800094)
				)
				(arc
					(start 110.638844 -5.200396)
					(mid 111.200311 -5.761482)
					(end 111.761524 -5.200142)
				)
			)
		)
		(polygon
			(pts
				(arc
					(start 108.161328 -3.800094)
					(mid 107.599988 -3.238754)
					(end 107.038648 -3.800094)
				)
				(arc
					(start 107.038648 -5.200396)
					(mid 107.600115 -5.761482)
					(end 108.161328 -5.200142)
				)
			)
		)
		(polygon
			(pts
				(arc
					(start 104.561386 -3.800094)
					(mid 104.000046 -3.238754)
					(end 103.438706 -3.800094)
				)
				(arc
					(start 103.438706 -5.200396)
					(mid 104.000173 -5.761482)
					(end 104.561386 -5.200142)
				)
			)
		)
		(polygon
			(pts
				(arc
					(start 100.961444 -3.800094)
					(mid 100.400104 -3.238754)
					(end 99.838764 -3.800094)
				)
				(arc
					(start 99.838764 -5.200396)
					(mid 100.400231 -5.761482)
					(end 100.961444 -5.200142)
				)
			)
		)
		(polygon
			(pts
				(arc
					(start 97.361502 -3.800094)
					(mid 96.800162 -3.238754)
					(end 96.238822 -3.800094)
				)
				(arc
					(start 96.238822 -5.200396)
					(mid 96.800289 -5.761482)
					(end 97.361502 -5.200142)
				)
			)
		)
		(polygon
			(pts
				(arc
					(start 93.761306 -3.800094)
					(mid 93.199966 -3.238754)
					(end 92.638626 -3.800094)
				)
				(arc
					(start 92.638626 -5.200396)
					(mid 93.200093 -5.761482)
					(end 93.761306 -5.200142)
				)
			)
		)
		(polygon
			(pts
				(arc
					(start 90.161364 -3.800094)
					(mid 89.600024 -3.238754)
					(end 89.038684 -3.800094)
				)
				(arc
					(start 89.038684 -5.200396)
					(mid 89.600151 -5.761482)
					(end 90.161364 -5.200142)
				)
			)
		)
		(polygon
			(pts
				(arc
					(start 86.561422 -3.800094)
					(mid 86.000082 -3.238754)
					(end 85.438742 -3.800094)
				)
				(arc
					(start 85.438742 -5.200396)
					(mid 86.000209 -5.761482)
					(end 86.561422 -5.200142)
				)
			)
		)
		(polygon
			(pts
				(arc
					(start 193.161158 -2.600198)
					(mid 192.599818 -2.038858)
					(end 192.038478 -2.600198)
				)
				(arc
					(start 192.038478 -4.000246)
					(mid 192.599945 -4.561332)
					(end 193.161158 -3.999992)
				)
			)
		)
		(polygon
			(pts
				(arc
					(start 189.561216 -2.600198)
					(mid 188.999876 -2.038858)
					(end 188.438536 -2.600198)
				)
				(arc
					(start 188.438536 -4.000246)
					(mid 189.000003 -4.561332)
					(end 189.561216 -3.999992)
				)
			)
		)
		(polygon
			(pts
				(arc
					(start 185.961274 -2.600198)
					(mid 185.399934 -2.038858)
					(end 184.838594 -2.600198)
				)
				(arc
					(start 184.838594 -4.000246)
					(mid 185.400061 -4.561332)
					(end 185.961274 -3.999992)
				)
			)
		)
		(polygon
			(pts
				(arc
					(start 182.361332 -2.600198)
					(mid 181.799992 -2.038858)
					(end 181.238652 -2.600198)
				)
				(arc
					(start 181.238652 -4.000246)
					(mid 181.800119 -4.561332)
					(end 182.361332 -3.999992)
				)
			)
		)
		(polygon
			(pts
				(arc
					(start 149.561296 -2.600198)
					(mid 148.999956 -2.038858)
					(end 148.438616 -2.600198)
				)
				(arc
					(start 148.438616 -4.000246)
					(mid 149.000083 -4.561332)
					(end 149.561296 -3.999992)
				)
			)
		)
		(polygon
			(pts
				(arc
					(start 145.961354 -2.600198)
					(mid 145.400014 -2.038858)
					(end 144.838674 -2.600198)
				)
				(arc
					(start 144.838674 -4.000246)
					(mid 145.400141 -4.561332)
					(end 145.961354 -3.999992)
				)
			)
		)
		(polygon
			(pts
				(arc
					(start 142.361412 -2.600198)
					(mid 141.800072 -2.038858)
					(end 141.238732 -2.600198)
				)
				(arc
					(start 141.238732 -4.000246)
					(mid 141.800199 -4.561332)
					(end 142.361412 -3.999992)
				)
			)
		)
		(polygon
			(pts
				(arc
					(start 138.76147 -2.600198)
					(mid 138.20013 -2.038858)
					(end 137.63879 -2.600198)
				)
				(arc
					(start 137.63879 -4.000246)
					(mid 138.200257 -4.561332)
					(end 138.76147 -3.999992)
				)
			)
		)
		(polygon
			(pts
				(arc
					(start 135.161528 -2.600198)
					(mid 134.600188 -2.038858)
					(end 134.038848 -2.600198)
				)
				(arc
					(start 134.038848 -4.000246)
					(mid 134.600315 -4.561332)
					(end 135.161528 -3.999992)
				)
			)
		)
		(polygon
			(pts
				(arc
					(start 131.561332 -2.600198)
					(mid 130.999992 -2.038858)
					(end 130.438652 -2.600198)
				)
				(arc
					(start 130.438652 -4.000246)
					(mid 131.000119 -4.561332)
					(end 131.561332 -3.999992)
				)
			)
		)
		(polygon
			(pts
				(arc
					(start 127.96139 -2.600198)
					(mid 127.40005 -2.038858)
					(end 126.83871 -2.600198)
				)
				(arc
					(start 126.83871 -4.000246)
					(mid 127.400177 -4.561332)
					(end 127.96139 -3.999992)
				)
			)
		)
		(polygon
			(pts
				(arc
					(start 124.361448 -2.600198)
					(mid 123.800108 -2.038858)
					(end 123.238768 -2.600198)
				)
				(arc
					(start 123.238768 -4.000246)
					(mid 123.800235 -4.561332)
					(end 124.361448 -3.999992)
				)
			)
		)
		(polygon
			(pts
				(arc
					(start 120.761506 -2.600198)
					(mid 120.200166 -2.038858)
					(end 119.638826 -2.600198)
				)
				(arc
					(start 119.638826 -4.000246)
					(mid 120.200293 -4.561332)
					(end 120.761506 -3.999992)
				)
			)
		)
		(polygon
			(pts
				(arc
					(start 117.16131 -2.600198)
					(mid 116.59997 -2.038858)
					(end 116.03863 -2.600198)
				)
				(arc
					(start 116.03863 -4.000246)
					(mid 116.600097 -4.561332)
					(end 117.16131 -3.999992)
				)
			)
		)
		(polygon
			(pts
				(arc
					(start 113.561368 -2.600198)
					(mid 113.000028 -2.038858)
					(end 112.438688 -2.600198)
				)
				(arc
					(start 112.438688 -4.000246)
					(mid 113.000155 -4.561332)
					(end 113.561368 -3.999992)
				)
			)
		)
		(polygon
			(pts
				(arc
					(start 109.961426 -2.600198)
					(mid 109.400086 -2.038858)
					(end 108.838746 -2.600198)
				)
				(arc
					(start 108.838746 -4.000246)
					(mid 109.400213 -4.561332)
					(end 109.961426 -3.999992)
				)
			)
		)
		(polygon
			(pts
				(arc
					(start 106.361484 -2.600198)
					(mid 105.800144 -2.038858)
					(end 105.238804 -2.600198)
				)
				(arc
					(start 105.238804 -4.000246)
					(mid 105.800271 -4.561332)
					(end 106.361484 -3.999992)
				)
			)
		)
		(polygon
			(pts
				(arc
					(start 102.761542 -2.600198)
					(mid 102.200202 -2.038858)
					(end 101.638862 -2.600198)
				)
				(arc
					(start 101.638862 -4.000246)
					(mid 102.200329 -4.561332)
					(end 102.761542 -3.999992)
				)
			)
		)
		(polygon
			(pts
				(arc
					(start 99.161346 -2.600198)
					(mid 98.600006 -2.038858)
					(end 98.038666 -2.600198)
				)
				(arc
					(start 98.038666 -4.000246)
					(mid 98.600133 -4.561332)
					(end 99.161346 -3.999992)
				)
			)
		)
		(polygon
			(pts
				(arc
					(start 95.561404 -2.600198)
					(mid 95.000064 -2.038858)
					(end 94.438724 -2.600198)
				)
				(arc
					(start 94.438724 -4.000246)
					(mid 95.000191 -4.561332)
					(end 95.561404 -3.999992)
				)
			)
		)
		(polygon
			(pts
				(arc
					(start 91.961462 -2.600198)
					(mid 91.400122 -2.038858)
					(end 90.838782 -2.600198)
				)
				(arc
					(start 90.838782 -4.000246)
					(mid 91.400249 -4.561332)
					(end 91.961462 -3.999992)
				)
			)
		)
		(polygon
			(pts
				(arc
					(start 88.36152 -2.600198)
					(mid 87.80018 -2.038858)
					(end 87.23884 -2.600198)
				)
				(arc
					(start 87.23884 -4.000246)
					(mid 87.800307 -4.561332)
					(end 88.36152 -3.999992)
				)
			)
		)
	)
	(zone
		(layers "In1.Cu" "In2.Cu")
		(hatch none 0.5)
		(connect_pads
			(clearance 0)
		)
		(min_thickness 0.25)
		(keepout
			(tracks not_allowed)
			(vias allowed)
			(pads allowed)
			(copperpour not_allowed)
			(footprints allowed)
		)
		(placement
			(enabled no)
			(sheetname "")
		)
		(fill yes
			(thermal_gap 0.5)
			(thermal_bridge_width 0.5)
			(island_removal_mode 0)
		)
		(polygon
			(pts
				(arc
					(start 130.47218 -44.260516)
					(mid 130.436259 -44.275395)
					(end 130.42138 -44.311316)
				)
				(arc
					(start 130.42138 -45.124116)
					(mid 130.436259 -45.160037)
					(end 130.47218 -45.174916)
				)
				(arc
					(start 130.67538 -45.174916)
					(mid 130.711301 -45.160037)
					(end 130.72618 -45.124116)
				)
				(arc
					(start 130.72618 -44.311316)
					(mid 130.711301 -44.275395)
					(end 130.67538 -44.260516)
				)
			)
		)
	)
	(zone
		(layers "In1.Cu" "In2.Cu")
		(hatch none 0.5)
		(connect_pads
			(clearance 0)
		)
		(min_thickness 0.25)
		(keepout
			(tracks not_allowed)
			(vias allowed)
			(pads allowed)
			(copperpour not_allowed)
			(footprints allowed)
		)
		(placement
			(enabled no)
			(sheetname "")
		)
		(fill yes
			(thermal_gap 0.5)
			(thermal_bridge_width 0.5)
			(island_removal_mode 0)
		)
		(polygon
			(pts
				(arc
					(start 142.371826 -63.638684)
					(mid 142.335905 -63.653563)
					(end 142.321026 -63.689484)
				)
				(arc
					(start 142.321026 -63.892684)
					(mid 142.335905 -63.928605)
					(end 142.371826 -63.943484)
				)
				(arc
					(start 143.184626 -63.943484)
					(mid 143.220547 -63.928605)
					(end 143.235426 -63.892684)
				)
				(arc
					(start 143.235426 -63.689484)
					(mid 143.220547 -63.653563)
					(end 143.184626 -63.638684)
				)
			)
		)
	)
	(zone
		(layers "In1.Cu" "In2.Cu")
		(hatch none 0.5)
		(connect_pads
			(clearance 0)
		)
		(min_thickness 0.25)
		(keepout
			(tracks not_allowed)
			(vias allowed)
			(pads allowed)
			(copperpour not_allowed)
			(footprints allowed)
		)
		(placement
			(enabled no)
			(sheetname "")
		)
		(fill yes
			(thermal_gap 0.5)
			(thermal_bridge_width 0.5)
			(island_removal_mode 0)
		)
		(polygon
			(pts
				(arc
					(start 142.58671 -58.1533)
					(mid 142.550789 -58.168179)
					(end 142.53591 -58.2041)
				)
				(arc
					(start 142.53591 -58.4073)
					(mid 142.550789 -58.443221)
					(end 142.58671 -58.4581)
				)
				(arc
					(start 143.39951 -58.4581)
					(mid 143.435431 -58.443221)
					(end 143.45031 -58.4073)
				)
				(arc
					(start 143.45031 -58.2041)
					(mid 143.435431 -58.168179)
					(end 143.39951 -58.1533)
				)
			)
		)
	)
	(zone
		(layers "In1.Cu" "In2.Cu")
		(hatch none 0.5)
		(connect_pads
			(clearance 0)
		)
		(min_thickness 0.25)
		(keepout
			(tracks not_allowed)
			(vias allowed)
			(pads allowed)
			(copperpour not_allowed)
			(footprints allowed)
		)
		(placement
			(enabled no)
			(sheetname "")
		)
		(fill yes
			(thermal_gap 0.5)
			(thermal_bridge_width 0.5)
			(island_removal_mode 0)
		)
		(polygon
			(pts
				(arc
					(start 128.48463 -44.275248)
					(mid 128.448709 -44.290127)
					(end 128.43383 -44.326048)
				)
				(arc
					(start 128.43383 -45.138848)
					(mid 128.448709 -45.174769)
					(end 128.48463 -45.189648)
				)
				(arc
					(start 128.68783 -45.189648)
					(mid 128.723751 -45.174769)
					(end 128.73863 -45.138848)
				)
				(arc
					(start 128.73863 -44.326048)
					(mid 128.723751 -44.290127)
					(end 128.68783 -44.275248)
				)
			)
		)
	)
	(zone
		(layers "In1.Cu" "In2.Cu")
		(hatch none 0.5)
		(connect_pads
			(clearance 0)
		)
		(min_thickness 0.25)
		(keepout
			(tracks not_allowed)
			(vias allowed)
			(pads allowed)
			(copperpour not_allowed)
			(footprints allowed)
		)
		(placement
			(enabled no)
			(sheetname "")
		)
		(fill yes
			(thermal_gap 0.5)
			(thermal_bridge_width 0.5)
			(island_removal_mode 0)
		)
		(polygon
			(pts
				(arc
					(start 135.775192 -77.119734)
					(mid 135.739271 -77.134613)
					(end 135.724392 -77.170534)
				)
				(arc
					(start 135.724392 -77.373734)
					(mid 135.739271 -77.409655)
					(end 135.775192 -77.424534)
				)
				(arc
					(start 136.587992 -77.424534)
					(mid 136.623913 -77.409655)
					(end 136.638792 -77.373734)
				)
				(arc
					(start 136.638792 -77.170534)
					(mid 136.623913 -77.134613)
					(end 136.587992 -77.119734)
				)
			)
		)
	)
	(zone
		(layers "In1.Cu" "In2.Cu")
		(hatch none 0.5)
		(connect_pads
			(clearance 0)
		)
		(min_thickness 0.25)
		(keepout
			(tracks not_allowed)
			(vias allowed)
			(pads allowed)
			(copperpour not_allowed)
			(footprints allowed)
		)
		(placement
			(enabled no)
			(sheetname "")
		)
		(fill yes
			(thermal_gap 0.5)
			(thermal_bridge_width 0.5)
			(island_removal_mode 0)
		)
		(polygon
			(pts
				(arc
					(start 142.58671 -57.5691)
					(mid 142.550789 -57.583979)
					(end 142.53591 -57.6199)
				)
				(arc
					(start 142.53591 -57.8231)
					(mid 142.550789 -57.859021)
					(end 142.58671 -57.8739)
				)
				(arc
					(start 143.39951 -57.8739)
					(mid 143.435431 -57.859021)
					(end 143.45031 -57.8231)
				)
				(arc
					(start 143.45031 -57.6199)
					(mid 143.435431 -57.583979)
					(end 143.39951 -57.5691)
				)
			)
		)
	)
	(zone
		(layers "In1.Cu" "In2.Cu")
		(hatch none 0.5)
		(connect_pads
			(clearance 0)
		)
		(min_thickness 0.25)
		(keepout
			(tracks not_allowed)
			(vias allowed)
			(pads allowed)
			(copperpour not_allowed)
			(footprints allowed)
		)
		(placement
			(enabled no)
			(sheetname "")
		)
		(fill yes
			(thermal_gap 0.5)
			(thermal_bridge_width 0.5)
			(island_removal_mode 0)
		)
		(polygon
			(pts
				(arc
					(start 135.820912 -79.577692)
					(mid 135.784991 -79.592571)
					(end 135.770112 -79.628492)
				)
				(arc
					(start 135.770112 -79.831692)
					(mid 135.784991 -79.867613)
					(end 135.820912 -79.882492)
				)
				(arc
					(start 136.633712 -79.882492)
					(mid 136.669633 -79.867613)
					(end 136.684512 -79.831692)
				)
				(arc
					(start 136.684512 -79.628492)
					(mid 136.669633 -79.592571)
					(end 136.633712 -79.577692)
				)
			)
		)
	)
	(zone
		(layers "In1.Cu" "In2.Cu")
		(hatch none 0.5)
		(connect_pads
			(clearance 0)
		)
		(min_thickness 0.25)
		(keepout
			(tracks not_allowed)
			(vias allowed)
			(pads allowed)
			(copperpour not_allowed)
			(footprints allowed)
		)
		(placement
			(enabled no)
			(sheetname "")
		)
		(fill yes
			(thermal_gap 0.5)
			(thermal_bridge_width 0.5)
			(island_removal_mode 0)
		)
		(polygon
			(pts
				(arc
					(start 125.424946 -44.28998)
					(mid 125.389025 -44.304859)
					(end 125.374146 -44.34078)
				)
				(arc
					(start 125.374146 -45.15358)
					(mid 125.389025 -45.189501)
					(end 125.424946 -45.20438)
				)
				(arc
					(start 125.628146 -45.20438)
					(mid 125.664067 -45.189501)
					(end 125.678946 -45.15358)
				)
				(arc
					(start 125.678946 -44.34078)
					(mid 125.664067 -44.304859)
					(end 125.628146 -44.28998)
				)
			)
		)
	)
	(zone
		(layers "In1.Cu" "In2.Cu")
		(hatch none 0.5)
		(connect_pads
			(clearance 0)
		)
		(min_thickness 0.25)
		(keepout
			(tracks not_allowed)
			(vias allowed)
			(pads allowed)
			(copperpour not_allowed)
			(footprints allowed)
		)
		(placement
			(enabled no)
			(sheetname "")
		)
		(fill yes
			(thermal_gap 0.5)
			(thermal_bridge_width 0.5)
			(island_removal_mode 0)
		)
		(polygon
			(pts
				(arc
					(start 126.009146 -44.28998)
					(mid 125.973225 -44.304859)
					(end 125.958346 -44.34078)
				)
				(arc
					(start 125.958346 -45.15358)
					(mid 125.973225 -45.189501)
					(end 126.009146 -45.20438)
				)
				(arc
					(start 126.212346 -45.20438)
					(mid 126.248267 -45.189501)
					(end 126.263146 -45.15358)
				)
				(arc
					(start 126.263146 -44.34078)
					(mid 126.248267 -44.304859)
					(end 126.212346 -44.28998)
				)
			)
		)
	)
	(zone
		(layers "In1.Cu" "In2.Cu")
		(hatch none 0.5)
		(connect_pads
			(clearance 0)
		)
		(min_thickness 0.25)
		(keepout
			(tracks not_allowed)
			(vias allowed)
			(pads allowed)
			(copperpour not_allowed)
			(footprints allowed)
		)
		(placement
			(enabled no)
			(sheetname "")
		)
		(fill yes
			(thermal_gap 0.5)
			(thermal_bridge_width 0.5)
			(island_removal_mode 0)
		)
		(polygon
			(pts
				(arc
					(start 131.05638 -44.260516)
					(mid 131.020459 -44.275395)
					(end 131.00558 -44.311316)
				)
				(arc
					(start 131.00558 -45.124116)
					(mid 131.020459 -45.160037)
					(end 131.05638 -45.174916)
				)
				(arc
					(start 131.25958 -45.174916)
					(mid 131.295501 -45.160037)
					(end 131.31038 -45.124116)
				)
				(arc
					(start 131.31038 -44.311316)
					(mid 131.295501 -44.275395)
					(end 131.25958 -44.260516)
				)
			)
		)
	)
	(zone
		(layers "In1.Cu" "In2.Cu")
		(hatch none 0.5)
		(connect_pads
			(clearance 0)
		)
		(min_thickness 0.25)
		(keepout
			(tracks not_allowed)
			(vias allowed)
			(pads allowed)
			(copperpour not_allowed)
			(footprints allowed)
		)
		(placement
			(enabled no)
			(sheetname "")
		)
		(fill yes
			(thermal_gap 0.5)
			(thermal_bridge_width 0.5)
			(island_removal_mode 0)
		)
		(polygon
			(pts
				(arc
					(start 141.94536 -62.295786)
					(mid 141.909439 -62.310665)
					(end 141.89456 -62.346586)
				)
				(arc
					(start 141.89456 -62.549786)
					(mid 141.909439 -62.585707)
					(end 141.94536 -62.600586)
				)
				(arc
					(start 142.75816 -62.600586)
					(mid 142.794081 -62.585707)
					(end 142.80896 -62.549786)
				)
				(arc
					(start 142.80896 -62.346586)
					(mid 142.794081 -62.310665)
					(end 142.75816 -62.295786)
				)
			)
		)
	)
	(zone
		(layers "In1.Cu" "In2.Cu")
		(hatch none 0.5)
		(connect_pads
			(clearance 0)
		)
		(min_thickness 0.25)
		(keepout
			(tracks not_allowed)
			(vias allowed)
			(pads allowed)
			(copperpour not_allowed)
			(footprints allowed)
		)
		(placement
			(enabled no)
			(sheetname "")
		)
		(fill yes
			(thermal_gap 0.5)
			(thermal_bridge_width 0.5)
			(island_removal_mode 0)
		)
		(polygon
			(pts
				(arc
					(start 133.04393 -44.245784)
					(mid 133.008009 -44.260663)
					(end 132.99313 -44.296584)
				)
				(arc
					(start 132.99313 -45.109384)
					(mid 133.008009 -45.145305)
					(end 133.04393 -45.160184)
				)
				(arc
					(start 133.24713 -45.160184)
					(mid 133.283051 -45.145305)
					(end 133.29793 -45.109384)
				)
				(arc
					(start 133.29793 -44.296584)
					(mid 133.283051 -44.260663)
					(end 133.24713 -44.245784)
				)
			)
		)
	)
	(zone
		(layers "In1.Cu" "In2.Cu")
		(hatch none 0.5)
		(connect_pads
			(clearance 0)
		)
		(min_thickness 0.25)
		(keepout
			(tracks not_allowed)
			(vias allowed)
			(pads allowed)
			(copperpour not_allowed)
			(footprints allowed)
		)
		(placement
			(enabled no)
			(sheetname "")
		)
		(fill yes
			(thermal_gap 0.5)
			(thermal_bridge_width 0.5)
			(island_removal_mode 0)
		)
		(polygon
			(pts
				(arc
					(start 142.371826 -64.222884)
					(mid 142.335905 -64.237763)
					(end 142.321026 -64.273684)
				)
				(arc
					(start 142.321026 -64.476884)
					(mid 142.335905 -64.512805)
					(end 142.371826 -64.527684)
				)
				(arc
					(start 143.184626 -64.527684)
					(mid 143.220547 -64.512805)
					(end 143.235426 -64.476884)
				)
				(arc
					(start 143.235426 -64.273684)
					(mid 143.220547 -64.237763)
					(end 143.184626 -64.222884)
				)
			)
		)
	)
	(zone
		(layers "In1.Cu" "In2.Cu")
		(hatch none 0.5)
		(connect_pads
			(clearance 0)
		)
		(min_thickness 0.25)
		(keepout
			(tracks not_allowed)
			(vias allowed)
			(pads allowed)
			(copperpour not_allowed)
			(footprints allowed)
		)
		(placement
			(enabled no)
			(sheetname "")
		)
		(fill yes
			(thermal_gap 0.5)
			(thermal_bridge_width 0.5)
			(island_removal_mode 0)
		)
		(polygon
			(pts
				(arc
					(start 142.17142 -59.788552)
					(mid 142.135499 -59.803431)
					(end 142.12062 -59.839352)
				)
				(arc
					(start 142.12062 -60.042552)
					(mid 142.135499 -60.078473)
					(end 142.17142 -60.093352)
				)
				(arc
					(start 142.98422 -60.093352)
					(mid 143.020141 -60.078473)
					(end 143.03502 -60.042552)
				)
				(arc
					(start 143.03502 -59.839352)
					(mid 143.020141 -59.803431)
					(end 142.98422 -59.788552)
				)
			)
		)
	)
	(zone
		(layers "In1.Cu" "In2.Cu")
		(hatch none 0.5)
		(connect_pads
			(clearance 0)
		)
		(min_thickness 0.25)
		(keepout
			(tracks not_allowed)
			(vias allowed)
			(pads allowed)
			(copperpour not_allowed)
			(footprints allowed)
		)
		(placement
			(enabled no)
			(sheetname "")
		)
		(fill yes
			(thermal_gap 0.5)
			(thermal_bridge_width 0.5)
			(island_removal_mode 0)
		)
		(polygon
			(pts
				(arc
					(start 141.94536 -61.711586)
					(mid 141.909439 -61.726465)
					(end 141.89456 -61.762386)
				)
				(arc
					(start 141.89456 -61.965586)
					(mid 141.909439 -62.001507)
					(end 141.94536 -62.016386)
				)
				(arc
					(start 142.75816 -62.016386)
					(mid 142.794081 -62.001507)
					(end 142.80896 -61.965586)
				)
				(arc
					(start 142.80896 -61.762386)
					(mid 142.794081 -61.726465)
					(end 142.75816 -61.711586)
				)
			)
		)
	)
	(zone
		(layers "In1.Cu" "In2.Cu")
		(hatch none 0.5)
		(connect_pads
			(clearance 0)
		)
		(min_thickness 0.25)
		(keepout
			(tracks not_allowed)
			(vias allowed)
			(pads allowed)
			(copperpour not_allowed)
			(footprints allowed)
		)
		(placement
			(enabled no)
			(sheetname "")
		)
		(fill yes
			(thermal_gap 0.5)
			(thermal_bridge_width 0.5)
			(island_removal_mode 0)
		)
		(polygon
			(pts
				(arc
					(start 135.775192 -77.678534)
					(mid 135.739271 -77.693413)
					(end 135.724392 -77.729334)
				)
				(arc
					(start 135.724392 -77.932534)
					(mid 135.739271 -77.968455)
					(end 135.775192 -77.983334)
				)
				(arc
					(start 136.587992 -77.983334)
					(mid 136.623913 -77.968455)
					(end 136.638792 -77.932534)
				)
				(arc
					(start 136.638792 -77.729334)
					(mid 136.623913 -77.693413)
					(end 136.587992 -77.678534)
				)
			)
		)
	)
	(zone
		(layers "In1.Cu" "In2.Cu")
		(hatch none 0.5)
		(connect_pads
			(clearance 0)
		)
		(min_thickness 0.25)
		(keepout
			(tracks not_allowed)
			(vias allowed)
			(pads allowed)
			(copperpour not_allowed)
			(footprints allowed)
		)
		(placement
			(enabled no)
			(sheetname "")
		)
		(fill yes
			(thermal_gap 0.5)
			(thermal_bridge_width 0.5)
			(island_removal_mode 0)
		)
		(polygon
			(pts
				(xy 147.349972 -40.0304)
				(arc
					(start 147.225766 -40.003984)
					(mid 147.187439 -40.011022)
					(end 147.165314 -40.0431)
				)
				(arc
					(start 147.12315 -40.241982)
					(mid 147.1303 -40.280131)
					(end 147.162266 -40.30218)
				)
				(xy 147.286472 -40.328596) (xy 147.83308 -40.444928)
				(arc
					(start 147.957286 -40.471344)
					(mid 147.995613 -40.464306)
					(end 148.017738 -40.432228)
				)
				(arc
					(start 148.059902 -40.233346)
					(mid 148.052752 -40.195197)
					(end 148.020786 -40.173148)
				)
				(xy 147.89658 -40.146732)
			)
		)
	)
	(zone
		(layers "In1.Cu" "In2.Cu")
		(hatch none 0.5)
		(connect_pads
			(clearance 0)
		)
		(min_thickness 0.25)
		(keepout
			(tracks not_allowed)
			(vias allowed)
			(pads allowed)
			(copperpour not_allowed)
			(footprints allowed)
		)
		(placement
			(enabled no)
			(sheetname "")
		)
		(fill yes
			(thermal_gap 0.5)
			(thermal_bridge_width 0.5)
			(island_removal_mode 0)
		)
		(polygon
			(pts
				(arc
					(start 142.17142 -60.372752)
					(mid 142.135499 -60.387631)
					(end 142.12062 -60.423552)
				)
				(arc
					(start 142.12062 -60.626752)
					(mid 142.135499 -60.662673)
					(end 142.17142 -60.677552)
				)
				(arc
					(start 142.98422 -60.677552)
					(mid 143.020141 -60.662673)
					(end 143.03502 -60.626752)
				)
				(arc
					(start 143.03502 -60.423552)
					(mid 143.020141 -60.387631)
					(end 142.98422 -60.372752)
				)
			)
		)
	)
	(zone
		(layers "In1.Cu" "In2.Cu")
		(hatch none 0.5)
		(connect_pads
			(clearance 0)
		)
		(min_thickness 0.25)
		(keepout
			(tracks not_allowed)
			(vias allowed)
			(pads allowed)
			(copperpour not_allowed)
			(footprints allowed)
		)
		(placement
			(enabled no)
			(sheetname "")
		)
		(fill yes
			(thermal_gap 0.5)
			(thermal_bridge_width 0.5)
			(island_removal_mode 0)
		)
		(polygon
			(pts
				(arc
					(start 135.842502 -75.20432)
					(mid 135.806581 -75.219199)
					(end 135.791702 -75.25512)
				)
				(arc
					(start 135.791702 -75.45832)
					(mid 135.806581 -75.494241)
					(end 135.842502 -75.50912)
				)
				(arc
					(start 136.655302 -75.50912)
					(mid 136.691223 -75.494241)
					(end 136.706102 -75.45832)
				)
				(arc
					(start 136.706102 -75.25512)
					(mid 136.691223 -75.219199)
					(end 136.655302 -75.20432)
				)
			)
		)
	)
	(zone
		(layers "In1.Cu" "In2.Cu")
		(hatch none 0.5)
		(connect_pads
			(clearance 0)
		)
		(min_thickness 0.25)
		(keepout
			(tracks not_allowed)
			(vias allowed)
			(pads allowed)
			(copperpour not_allowed)
			(footprints allowed)
		)
		(placement
			(enabled no)
			(sheetname "")
		)
		(fill yes
			(thermal_gap 0.5)
			(thermal_bridge_width 0.5)
			(island_removal_mode 0)
		)
		(polygon
			(pts
				(xy 147.22856 -40.601646)
				(arc
					(start 147.104354 -40.57523)
					(mid 147.066027 -40.582268)
					(end 147.043902 -40.614346)
				)
				(arc
					(start 147.001738 -40.813228)
					(mid 147.008888 -40.851377)
					(end 147.040854 -40.873426)
				)
				(xy 147.16506 -40.899842) (xy 147.711668 -41.016174)
				(arc
					(start 147.835874 -41.04259)
					(mid 147.874201 -41.035552)
					(end 147.896326 -41.003474)
				)
				(arc
					(start 147.93849 -40.804592)
					(mid 147.93134 -40.766443)
					(end 147.899374 -40.744394)
				)
				(xy 147.775168 -40.717978)
			)
		)
	)
	(zone
		(layers "In1.Cu" "In2.Cu")
		(hatch none 0.5)
		(connect_pads
			(clearance 0)
		)
		(min_thickness 0.25)
		(keepout
			(tracks not_allowed)
			(vias allowed)
			(pads allowed)
			(copperpour not_allowed)
			(footprints allowed)
		)
		(placement
			(enabled no)
			(sheetname "")
		)
		(fill yes
			(thermal_gap 0.5)
			(thermal_bridge_width 0.5)
			(island_removal_mode 0)
		)
		(polygon
			(pts
				(arc
					(start 127.90043 -44.275248)
					(mid 127.864509 -44.290127)
					(end 127.84963 -44.326048)
				)
				(arc
					(start 127.84963 -45.138848)
					(mid 127.864509 -45.174769)
					(end 127.90043 -45.189648)
				)
				(arc
					(start 128.10363 -45.189648)
					(mid 128.139551 -45.174769)
					(end 128.15443 -45.138848)
				)
				(arc
					(start 128.15443 -44.326048)
					(mid 128.139551 -44.290127)
					(end 128.10363 -44.275248)
				)
			)
		)
	)
	(zone
		(layers "In1.Cu" "In2.Cu")
		(hatch none 0.5)
		(connect_pads
			(clearance 0)
		)
		(min_thickness 0.25)
		(keepout
			(tracks not_allowed)
			(vias allowed)
			(pads allowed)
			(copperpour not_allowed)
			(footprints allowed)
		)
		(placement
			(enabled no)
			(sheetname "")
		)
		(fill yes
			(thermal_gap 0.5)
			(thermal_bridge_width 0.5)
			(island_removal_mode 0)
		)
		(polygon
			(pts
				(arc
					(start 135.842502 -75.76312)
					(mid 135.806581 -75.777999)
					(end 135.791702 -75.81392)
				)
				(arc
					(start 135.791702 -76.01712)
					(mid 135.806581 -76.053041)
					(end 135.842502 -76.06792)
				)
				(arc
					(start 136.655302 -76.06792)
					(mid 136.691223 -76.053041)
					(end 136.706102 -76.01712)
				)
				(arc
					(start 136.706102 -75.81392)
					(mid 136.691223 -75.777999)
					(end 136.655302 -75.76312)
				)
			)
		)
	)
	(zone
		(layers "In1.Cu" "In2.Cu")
		(hatch none 0.5)
		(connect_pads
			(clearance 0)
		)
		(min_thickness 0.25)
		(keepout
			(tracks not_allowed)
			(vias allowed)
			(pads allowed)
			(copperpour not_allowed)
			(footprints allowed)
		)
		(placement
			(enabled no)
			(sheetname "")
		)
		(fill yes
			(thermal_gap 0.5)
			(thermal_bridge_width 0.5)
			(island_removal_mode 0)
		)
		(polygon
			(pts
				(arc
					(start 133.62813 -44.245784)
					(mid 133.592209 -44.260663)
					(end 133.57733 -44.296584)
				)
				(arc
					(start 133.57733 -45.109384)
					(mid 133.592209 -45.145305)
					(end 133.62813 -45.160184)
				)
				(arc
					(start 133.83133 -45.160184)
					(mid 133.867251 -45.145305)
					(end 133.88213 -45.109384)
				)
				(arc
					(start 133.88213 -44.296584)
					(mid 133.867251 -44.260663)
					(end 133.83133 -44.245784)
				)
			)
		)
	)
	(zone
		(layers "In1.Cu" "In2.Cu")
		(hatch none 0.5)
		(connect_pads
			(clearance 0)
		)
		(min_thickness 0.25)
		(keepout
			(tracks not_allowed)
			(vias allowed)
			(pads allowed)
			(copperpour not_allowed)
			(footprints allowed)
		)
		(placement
			(enabled no)
			(sheetname "")
		)
		(fill yes
			(thermal_gap 0.5)
			(thermal_bridge_width 0.5)
			(island_removal_mode 0)
		)
		(polygon
			(pts
				(arc
					(start 135.820912 -79.018892)
					(mid 135.784991 -79.033771)
					(end 135.770112 -79.069692)
				)
				(arc
					(start 135.770112 -79.272892)
					(mid 135.784991 -79.308813)
					(end 135.820912 -79.323692)
				)
				(arc
					(start 136.633712 -79.323692)
					(mid 136.669633 -79.308813)
					(end 136.684512 -79.272892)
				)
				(arc
					(start 136.684512 -79.069692)
					(mid 136.669633 -79.033771)
					(end 136.633712 -79.018892)
				)
			)
		)
	)
	(zone
		(layers "In1.Cu" "In2.Cu" "In5.Cu" "In6.Cu")
		(hatch none 0.5)
		(connect_pads
			(clearance 0)
		)
		(min_thickness 0.25)
		(keepout
			(tracks not_allowed)
			(vias allowed)
			(pads allowed)
			(copperpour not_allowed)
			(footprints allowed)
		)
		(placement
			(enabled no)
			(sheetname "")
		)
		(fill yes
			(thermal_gap 0.5)
			(thermal_bridge_width 0.5)
			(island_removal_mode 0)
		)
		(polygon
			(pts
				(arc
					(start 135.8392 -80.4164)
					(mid 135.803279 -80.431279)
					(end 135.7884 -80.4672)
				)
				(arc
					(start 135.7884 -80.6704)
					(mid 135.803279 -80.706321)
					(end 135.8392 -80.7212)
				)
				(arc
					(start 136.652 -80.7212)
					(mid 136.687921 -80.706321)
					(end 136.7028 -80.6704)
				)
				(arc
					(start 136.7028 -80.4672)
					(mid 136.687921 -80.431279)
					(end 136.652 -80.4164)
				)
			)
		)
	)
	(zone
		(layers "In1.Cu" "In2.Cu" "In5.Cu" "In6.Cu")
		(hatch none 0.5)
		(connect_pads
			(clearance 0)
		)
		(min_thickness 0.25)
		(keepout
			(tracks not_allowed)
			(vias allowed)
			(pads allowed)
			(copperpour not_allowed)
			(footprints allowed)
		)
		(placement
			(enabled no)
			(sheetname "")
		)
		(fill yes
			(thermal_gap 0.5)
			(thermal_bridge_width 0.5)
			(island_removal_mode 0)
		)
		(polygon
			(pts
				(arc
					(start 135.8392 -80.9752)
					(mid 135.803279 -80.990079)
					(end 135.7884 -81.026)
				)
				(arc
					(start 135.7884 -81.2292)
					(mid 135.803279 -81.265121)
					(end 135.8392 -81.28)
				)
				(arc
					(start 136.652 -81.28)
					(mid 136.687921 -81.265121)
					(end 136.7028 -81.2292)
				)
				(arc
					(start 136.7028 -81.026)
					(mid 136.687921 -80.990079)
					(end 136.652 -80.9752)
				)
			)
		)
	)
	(zone
		(layers "In1.Cu" "In3.Cu" "In4.Cu" "In6.Cu")
		(hatch none 0.5)
		(connect_pads
			(clearance 0)
		)
		(min_thickness 0.25)
		(keepout
			(tracks not_allowed)
			(vias allowed)
			(pads allowed)
			(copperpour not_allowed)
			(footprints allowed)
		)
		(placement
			(enabled no)
			(sheetname "")
		)
		(fill yes
			(thermal_gap 0.5)
			(thermal_bridge_width 0.5)
			(island_removal_mode 0)
		)
		(polygon
			(pts
				(arc
					(start 120.358154 -55.000144)
					(mid 120.000014 -54.642004)
					(end 119.641874 -55.000144)
				)
				(arc
					(start 119.641874 -55.999888)
					(mid 119.999887 -56.358282)
					(end 120.358154 -56.000142)
				)
			)
		)
	)
	(zone
		(layers "In1.Cu" "In3.Cu" "In4.Cu" "In6.Cu")
		(hatch none 0.5)
		(connect_pads
			(clearance 0)
		)
		(min_thickness 0.25)
		(keepout
			(tracks not_allowed)
			(vias allowed)
			(pads allowed)
			(copperpour not_allowed)
			(footprints allowed)
		)
		(placement
			(enabled no)
			(sheetname "")
		)
		(fill yes
			(thermal_gap 0.5)
			(thermal_bridge_width 0.5)
			(island_removal_mode 0)
		)
		(polygon
			(pts
				(arc
					(start 129.761488 -3.800094)
					(mid 129.200148 -3.238754)
					(end 128.638808 -3.800094)
				)
				(arc
					(start 128.638808 -5.199888)
					(mid 129.200021 -5.761482)
					(end 129.761488 -5.200142)
				)
			)
		)
	)
	(zone
		(layers "In1.Cu" "In3.Cu" "In4.Cu" "In6.Cu")
		(hatch none 0.5)
		(connect_pads
			(clearance 0)
		)
		(min_thickness 0.25)
		(keepout
			(tracks not_allowed)
			(vias allowed)
			(pads allowed)
			(copperpour not_allowed)
			(footprints allowed)
		)
		(placement
			(enabled no)
			(sheetname "")
		)
		(fill yes
			(thermal_gap 0.5)
			(thermal_bridge_width 0.5)
			(island_removal_mode 0)
		)
		(polygon
			(pts
				(arc
					(start 139.881864 -65.426844)
					(mid 140.336778 -64.972311)
					(end 139.882118 -64.517524)
				)
				(arc
					(start 138.739118 -64.517524)
					(mid 138.284458 -64.972184)
					(end 138.739118 -65.426844)
				)
			)
		)
	)
	(zone
		(layers "In1.Cu" "In3.Cu" "In4.Cu" "In6.Cu")
		(hatch none 0.5)
		(connect_pads
			(clearance 0)
		)
		(min_thickness 0.25)
		(keepout
			(tracks not_allowed)
			(vias allowed)
			(pads allowed)
			(copperpour not_allowed)
			(footprints allowed)
		)
		(placement
			(enabled no)
			(sheetname "")
		)
		(fill yes
			(thermal_gap 0.5)
			(thermal_bridge_width 0.5)
			(island_removal_mode 0)
		)
		(polygon
			(pts
				(arc
					(start 146.859752 -47.469298)
					(mid 147.21205 -48.011588)
					(end 147.75434 -47.65929)
				)
				(arc
					(start 147.989544 -46.551596)
					(mid 147.64498 -46.000227)
					(end 147.097496 -46.35119)
				)
			)
		)
	)
	(zone
		(layers "In1.Cu" "In3.Cu" "In4.Cu" "In6.Cu")
		(hatch none 0.5)
		(connect_pads
			(clearance 0)
		)
		(min_thickness 0.25)
		(keepout
			(tracks not_allowed)
			(vias allowed)
			(pads allowed)
			(copperpour not_allowed)
			(footprints allowed)
		)
		(placement
			(enabled no)
			(sheetname "")
		)
		(fill yes
			(thermal_gap 0.5)
			(thermal_bridge_width 0.5)
			(island_removal_mode 0)
		)
		(polygon
			(pts
				(arc
					(start 126.000256 -73.641966)
					(mid 125.641862 -73.999979)
					(end 126.000002 -74.358246)
				)
				(arc
					(start 127 -74.358246)
					(mid 127.35814 -74.000106)
					(end 127 -73.641966)
				)
			)
		)
	)
	(zone
		(layers "In1.Cu" "In3.Cu" "In4.Cu" "In6.Cu")
		(hatch none 0.5)
		(connect_pads
			(clearance 0)
		)
		(min_thickness 0.25)
		(keepout
			(tracks not_allowed)
			(vias allowed)
			(pads allowed)
			(copperpour not_allowed)
			(footprints allowed)
		)
		(placement
			(enabled no)
			(sheetname "")
		)
		(fill yes
			(thermal_gap 0.5)
			(thermal_bridge_width 0.5)
			(island_removal_mode 0)
		)
		(polygon
			(pts
				(arc
					(start 180.561234 -7.400036)
					(mid 179.999894 -6.838696)
					(end 179.438554 -7.400036)
				)
				(arc
					(start 179.438554 -8.79983)
					(mid 179.999767 -9.361424)
					(end 180.561234 -8.800084)
				)
			)
		)
	)
	(zone
		(layers "In1.Cu" "In3.Cu" "In4.Cu" "In6.Cu")
		(hatch none 0.5)
		(connect_pads
			(clearance 0)
		)
		(min_thickness 0.25)
		(keepout
			(tracks not_allowed)
			(vias allowed)
			(pads allowed)
			(copperpour not_allowed)
			(footprints allowed)
		)
		(placement
			(enabled no)
			(sheetname "")
		)
		(fill yes
			(thermal_gap 0.5)
			(thermal_bridge_width 0.5)
			(island_removal_mode 0)
		)
		(polygon
			(pts
				(arc
					(start 120.358154 -52.00015)
					(mid 120.000014 -51.64201)
					(end 119.641874 -52.00015)
				)
				(arc
					(start 119.641874 -52.999894)
					(mid 119.999887 -53.358288)
					(end 120.358154 -53.000148)
				)
			)
		)
	)
	(zone
		(layers "In1.Cu" "In3.Cu" "In4.Cu" "In6.Cu")
		(hatch none 0.5)
		(connect_pads
			(clearance 0)
		)
		(min_thickness 0.25)
		(keepout
			(tracks not_allowed)
			(vias allowed)
			(pads allowed)
			(copperpour not_allowed)
			(footprints allowed)
		)
		(placement
			(enabled no)
			(sheetname "")
		)
		(fill yes
			(thermal_gap 0.5)
			(thermal_bridge_width 0.5)
			(island_removal_mode 0)
		)
		(polygon
			(pts
				(arc
					(start 112.35817 -51.000152)
					(mid 112.00003 -50.642012)
					(end 111.64189 -51.000152)
				)
				(arc
					(start 111.64189 -51.999896)
					(mid 111.999903 -52.35829)
					(end 112.35817 -52.00015)
				)
			)
		)
	)
	(zone
		(layers "In1.Cu" "In3.Cu" "In4.Cu" "In6.Cu")
		(hatch none 0.5)
		(connect_pads
			(clearance 0)
		)
		(min_thickness 0.25)
		(keepout
			(tracks not_allowed)
			(vias allowed)
			(pads allowed)
			(copperpour not_allowed)
			(footprints allowed)
		)
		(placement
			(enabled no)
			(sheetname "")
		)
		(fill yes
			(thermal_gap 0.5)
			(thermal_bridge_width 0.5)
			(island_removal_mode 0)
		)
		(polygon
			(pts
				(arc
					(start 172.65269 -23.112984)
					(mid 172.26915 -22.729444)
					(end 171.88561 -23.112984)
				)
				(arc
					(start 171.88561 -24.00173)
					(mid 172.269023 -24.385524)
					(end 172.65269 -24.001984)
				)
			)
		)
	)
	(zone
		(layers "In1.Cu" "In3.Cu" "In4.Cu" "In6.Cu")
		(hatch none 0.5)
		(connect_pads
			(clearance 0)
		)
		(min_thickness 0.25)
		(keepout
			(tracks not_allowed)
			(vias allowed)
			(pads allowed)
			(copperpour not_allowed)
			(footprints allowed)
		)
		(placement
			(enabled no)
			(sheetname "")
		)
		(fill yes
			(thermal_gap 0.5)
			(thermal_bridge_width 0.5)
			(island_removal_mode 0)
		)
		(polygon
			(pts
				(arc
					(start 135.161528 -2.600198)
					(mid 134.600188 -2.038858)
					(end 134.038848 -2.600198)
				)
				(arc
					(start 134.038848 -3.999738)
					(mid 134.600061 -4.561332)
					(end 135.161528 -3.999992)
				)
			)
		)
	)
	(zone
		(layers "In1.Cu" "In3.Cu" "In4.Cu" "In6.Cu")
		(hatch none 0.5)
		(connect_pads
			(clearance 0)
		)
		(min_thickness 0.25)
		(keepout
			(tracks not_allowed)
			(vias allowed)
			(pads allowed)
			(copperpour not_allowed)
			(footprints allowed)
		)
		(placement
			(enabled no)
			(sheetname "")
		)
		(fill yes
			(thermal_gap 0.5)
			(thermal_bridge_width 0.5)
			(island_removal_mode 0)
		)
		(polygon
			(pts
				(arc
					(start 105.358184 -52.00015)
					(mid 105.000044 -51.64201)
					(end 104.641904 -52.00015)
				)
				(arc
					(start 104.641904 -52.999894)
					(mid 104.999917 -53.358288)
					(end 105.358184 -53.000148)
				)
			)
		)
	)
	(zone
		(layers "In1.Cu" "In3.Cu" "In4.Cu" "In6.Cu")
		(hatch none 0.5)
		(connect_pads
			(clearance 0)
		)
		(min_thickness 0.25)
		(keepout
			(tracks not_allowed)
			(vias allowed)
			(pads allowed)
			(copperpour not_allowed)
			(footprints allowed)
		)
		(placement
			(enabled no)
			(sheetname "")
		)
		(fill yes
			(thermal_gap 0.5)
			(thermal_bridge_width 0.5)
			(island_removal_mode 0)
		)
		(polygon
			(pts
				(arc
					(start 144.16151 -10.999978)
					(mid 143.60017 -10.438638)
					(end 143.03883 -10.999978)
				)
				(arc
					(start 143.03883 -12.399772)
					(mid 143.600043 -12.961366)
					(end 144.16151 -12.400026)
				)
			)
		)
	)
	(zone
		(layers "In1.Cu" "In3.Cu" "In4.Cu" "In6.Cu")
		(hatch none 0.5)
		(connect_pads
			(clearance 0)
		)
		(min_thickness 0.25)
		(keepout
			(tracks not_allowed)
			(vias allowed)
			(pads allowed)
			(copperpour not_allowed)
			(footprints allowed)
		)
		(placement
			(enabled no)
			(sheetname "")
		)
		(fill yes
			(thermal_gap 0.5)
			(thermal_bridge_width 0.5)
			(island_removal_mode 0)
		)
		(polygon
			(pts
				(arc
					(start 91.961462 -9.800082)
					(mid 91.400122 -9.238742)
					(end 90.838782 -9.800082)
				)
				(arc
					(start 90.838782 -11.199876)
					(mid 91.399995 -11.76147)
					(end 91.961462 -11.20013)
				)
			)
		)
	)
	(zone
		(layers "In1.Cu" "In3.Cu" "In4.Cu" "In6.Cu")
		(hatch none 0.5)
		(connect_pads
			(clearance 0)
		)
		(min_thickness 0.25)
		(keepout
			(tracks not_allowed)
			(vias allowed)
			(pads allowed)
			(copperpour not_allowed)
			(footprints allowed)
		)
		(placement
			(enabled no)
			(sheetname "")
		)
		(fill yes
			(thermal_gap 0.5)
			(thermal_bridge_width 0.5)
			(island_removal_mode 0)
		)
		(polygon
			(pts
				(arc
					(start 99.358196 -54.000146)
					(mid 99.000056 -53.642006)
					(end 98.641916 -54.000146)
				)
				(arc
					(start 98.641916 -54.99989)
					(mid 98.999929 -55.358284)
					(end 99.358196 -55.000144)
				)
			)
		)
	)
	(zone
		(layers "In1.Cu" "In3.Cu" "In4.Cu" "In6.Cu")
		(hatch none 0.5)
		(connect_pads
			(clearance 0)
		)
		(min_thickness 0.25)
		(keepout
			(tracks not_allowed)
			(vias allowed)
			(pads allowed)
			(copperpour not_allowed)
			(footprints allowed)
		)
		(placement
			(enabled no)
			(sheetname "")
		)
		(fill yes
			(thermal_gap 0.5)
			(thermal_bridge_width 0.5)
			(island_removal_mode 0)
		)
		(polygon
			(pts
				(arc
					(start 102.35819 -55.000144)
					(mid 102.00005 -54.642004)
					(end 101.64191 -55.000144)
				)
				(arc
					(start 101.64191 -55.999888)
					(mid 101.999923 -56.358282)
					(end 102.35819 -56.000142)
				)
			)
		)
	)
	(zone
		(layers "In1.Cu" "In3.Cu" "In4.Cu" "In6.Cu")
		(hatch none 0.5)
		(connect_pads
			(clearance 0)
		)
		(min_thickness 0.25)
		(keepout
			(tracks not_allowed)
			(vias allowed)
			(pads allowed)
			(copperpour not_allowed)
			(footprints allowed)
		)
		(placement
			(enabled no)
			(sheetname "")
		)
		(fill yes
			(thermal_gap 0.5)
			(thermal_bridge_width 0.5)
			(island_removal_mode 0)
		)
		(polygon
			(pts
				(arc
					(start 187.761118 -3.800094)
					(mid 187.199778 -3.238754)
					(end 186.638438 -3.800094)
				)
				(arc
					(start 186.638438 -5.199888)
					(mid 187.199651 -5.761482)
					(end 187.761118 -5.200142)
				)
			)
		)
	)
	(zone
		(layers "In1.Cu" "In3.Cu" "In4.Cu" "In6.Cu")
		(hatch none 0.5)
		(connect_pads
			(clearance 0)
		)
		(min_thickness 0.25)
		(keepout
			(tracks not_allowed)
			(vias allowed)
			(pads allowed)
			(copperpour not_allowed)
			(footprints allowed)
		)
		(placement
			(enabled no)
			(sheetname "")
		)
		(fill yes
			(thermal_gap 0.5)
			(thermal_bridge_width 0.5)
			(island_removal_mode 0)
		)
		(polygon
			(pts
				(arc
					(start 126.000256 -56.642)
					(mid 125.641862 -57.000013)
					(end 126.000002 -57.35828)
				)
				(arc
					(start 127 -57.35828)
					(mid 127.35814 -57.00014)
					(end 127 -56.642)
				)
			)
		)
	)
	(zone
		(layers "In1.Cu" "In3.Cu" "In4.Cu" "In6.Cu")
		(hatch none 0.5)
		(connect_pads
			(clearance 0)
		)
		(min_thickness 0.25)
		(keepout
			(tracks not_allowed)
			(vias allowed)
			(pads allowed)
			(copperpour not_allowed)
			(footprints allowed)
		)
		(placement
			(enabled no)
			(sheetname "")
		)
		(fill yes
			(thermal_gap 0.5)
			(thermal_bridge_width 0.5)
			(island_removal_mode 0)
		)
		(polygon
			(pts
				(xy 138.486134 -78.044294)
				(arc
					(start 138.486134 -78.045056)
					(mid 138.103356 -78.427834)
					(end 138.486134 -78.810612)
				)
				(xy 138.486134 -78.811374) (xy 139.62888 -78.811374) (xy 139.629134 -78.81112)
				(arc
					(start 139.629134 -78.810612)
					(mid 140.011912 -78.427834)
					(end 139.629134 -78.045056)
				)
				(xy 139.629134 -78.044294)
			)
		)
	)
	(zone
		(layers "In1.Cu" "In3.Cu" "In4.Cu" "In6.Cu")
		(hatch none 0.5)
		(connect_pads
			(clearance 0)
		)
		(min_thickness 0.25)
		(keepout
			(tracks not_allowed)
			(vias allowed)
			(pads allowed)
			(copperpour not_allowed)
			(footprints allowed)
		)
		(placement
			(enabled no)
			(sheetname "")
		)
		(fill yes
			(thermal_gap 0.5)
			(thermal_bridge_width 0.5)
			(island_removal_mode 0)
		)
		(polygon
			(pts
				(arc
					(start 148.179536 -41.25849)
					(mid 148.531834 -41.80078)
					(end 149.074124 -41.448482)
				)
				(arc
					(start 149.309328 -40.340788)
					(mid 148.964764 -39.789419)
					(end 148.41728 -40.140382)
				)
			)
		)
	)
	(zone
		(layers "In1.Cu" "In3.Cu" "In4.Cu" "In6.Cu")
		(hatch none 0.5)
		(connect_pads
			(clearance 0)
		)
		(min_thickness 0.25)
		(keepout
			(tracks not_allowed)
			(vias allowed)
			(pads allowed)
			(copperpour not_allowed)
			(footprints allowed)
		)
		(placement
			(enabled no)
			(sheetname "")
		)
		(fill yes
			(thermal_gap 0.5)
			(thermal_bridge_width 0.5)
			(island_removal_mode 0)
		)
		(polygon
			(pts
				(arc
					(start 104.561386 -3.800094)
					(mid 104.000046 -3.238754)
					(end 103.438706 -3.800094)
				)
				(arc
					(start 103.438706 -5.199888)
					(mid 103.999919 -5.761482)
					(end 104.561386 -5.200142)
				)
			)
		)
	)
	(zone
		(layers "In1.Cu" "In3.Cu" "In4.Cu" "In6.Cu")
		(hatch none 0.5)
		(connect_pads
			(clearance 0)
		)
		(min_thickness 0.25)
		(keepout
			(tracks not_allowed)
			(vias allowed)
			(pads allowed)
			(copperpour not_allowed)
			(footprints allowed)
		)
		(placement
			(enabled no)
			(sheetname "")
		)
		(fill yes
			(thermal_gap 0.5)
			(thermal_bridge_width 0.5)
			(island_removal_mode 0)
		)
		(polygon
			(pts
				(arc
					(start 142.361412 -9.800082)
					(mid 141.800072 -9.238742)
					(end 141.238732 -9.800082)
				)
				(arc
					(start 141.238732 -11.199876)
					(mid 141.799945 -11.76147)
					(end 142.361412 -11.20013)
				)
			)
		)
	)
	(zone
		(layers "In1.Cu" "In3.Cu" "In4.Cu" "In6.Cu")
		(hatch none 0.5)
		(connect_pads
			(clearance 0)
		)
		(min_thickness 0.25)
		(keepout
			(tracks not_allowed)
			(vias allowed)
			(pads allowed)
			(copperpour not_allowed)
			(footprints allowed)
		)
		(placement
			(enabled no)
			(sheetname "")
		)
		(fill yes
			(thermal_gap 0.5)
			(thermal_bridge_width 0.5)
			(island_removal_mode 0)
		)
		(polygon
			(pts
				(arc
					(start 120.761506 -2.600198)
					(mid 120.200166 -2.038858)
					(end 119.638826 -2.600198)
				)
				(arc
					(start 119.638826 -3.999738)
					(mid 120.200039 -4.561332)
					(end 120.761506 -3.999992)
				)
			)
		)
	)
	(zone
		(layers "In1.Cu" "In3.Cu" "In4.Cu" "In6.Cu")
		(hatch none 0.5)
		(connect_pads
			(clearance 0)
		)
		(min_thickness 0.25)
		(keepout
			(tracks not_allowed)
			(vias allowed)
			(pads allowed)
			(copperpour not_allowed)
			(footprints allowed)
		)
		(placement
			(enabled no)
			(sheetname "")
		)
		(fill yes
			(thermal_gap 0.5)
			(thermal_bridge_width 0.5)
			(island_removal_mode 0)
		)
		(polygon
			(pts
				(arc
					(start 180.561234 -10.999978)
					(mid 179.999894 -10.438638)
					(end 179.438554 -10.999978)
				)
				(arc
					(start 179.438554 -12.399772)
					(mid 179.999767 -12.961366)
					(end 180.561234 -12.400026)
				)
			)
		)
	)
	(zone
		(layers "In1.Cu" "In3.Cu" "In4.Cu" "In6.Cu")
		(hatch none 0.5)
		(connect_pads
			(clearance 0)
		)
		(min_thickness 0.25)
		(keepout
			(tracks not_allowed)
			(vias allowed)
			(pads allowed)
			(copperpour not_allowed)
			(footprints allowed)
		)
		(placement
			(enabled no)
			(sheetname "")
		)
		(fill yes
			(thermal_gap 0.5)
			(thermal_bridge_width 0.5)
			(island_removal_mode 0)
		)
		(polygon
			(pts
				(arc
					(start 131.561332 -9.800082)
					(mid 130.999992 -9.238742)
					(end 130.438652 -9.800082)
				)
				(arc
					(start 130.438652 -11.199876)
					(mid 130.999865 -11.76147)
					(end 131.561332 -11.20013)
				)
			)
		)
	)
	(zone
		(layers "In1.Cu" "In3.Cu" "In4.Cu" "In6.Cu")
		(hatch none 0.5)
		(connect_pads
			(clearance 0)
		)
		(min_thickness 0.25)
		(keepout
			(tracks not_allowed)
			(vias allowed)
			(pads allowed)
			(copperpour not_allowed)
			(footprints allowed)
		)
		(placement
			(enabled no)
			(sheetname "")
		)
		(fill yes
			(thermal_gap 0.5)
			(thermal_bridge_width 0.5)
			(island_removal_mode 0)
		)
		(polygon
			(pts
				(arc
					(start 166.58336 -32.80029)
					(mid 166.199947 -32.416496)
					(end 165.81628 -32.800036)
				)
				(arc
					(start 165.81628 -33.599882)
					(mid 166.19982 -33.983422)
					(end 166.58336 -33.599882)
				)
			)
		)
	)
	(zone
		(layers "In1.Cu" "In3.Cu" "In4.Cu" "In6.Cu")
		(hatch none 0.5)
		(connect_pads
			(clearance 0)
		)
		(min_thickness 0.25)
		(keepout
			(tracks not_allowed)
			(vias allowed)
			(pads allowed)
			(copperpour not_allowed)
			(footprints allowed)
		)
		(placement
			(enabled no)
			(sheetname "")
		)
		(fill yes
			(thermal_gap 0.5)
			(thermal_bridge_width 0.5)
			(island_removal_mode 0)
		)
		(polygon
			(pts
				(arc
					(start 88.36152 -9.800082)
					(mid 87.80018 -9.238742)
					(end 87.23884 -9.800082)
				)
				(arc
					(start 87.23884 -11.199876)
					(mid 87.800053 -11.76147)
					(end 88.36152 -11.20013)
				)
			)
		)
	)
	(zone
		(layers "In1.Cu" "In3.Cu" "In4.Cu" "In6.Cu")
		(hatch none 0.5)
		(connect_pads
			(clearance 0)
		)
		(min_thickness 0.25)
		(keepout
			(tracks not_allowed)
			(vias allowed)
			(pads allowed)
			(copperpour not_allowed)
			(footprints allowed)
		)
		(placement
			(enabled no)
			(sheetname "")
		)
		(fill yes
			(thermal_gap 0.5)
			(thermal_bridge_width 0.5)
			(island_removal_mode 0)
		)
		(polygon
			(pts
				(arc
					(start 126.000256 -68.641976)
					(mid 125.641862 -68.999989)
					(end 126.000002 -69.358256)
				)
				(arc
					(start 127 -69.358256)
					(mid 127.35814 -69.000116)
					(end 127 -68.641976)
				)
			)
		)
	)
	(zone
		(layers "In1.Cu" "In3.Cu" "In4.Cu" "In6.Cu")
		(hatch none 0.5)
		(connect_pads
			(clearance 0)
		)
		(min_thickness 0.25)
		(keepout
			(tracks not_allowed)
			(vias allowed)
			(pads allowed)
			(copperpour not_allowed)
			(footprints allowed)
		)
		(placement
			(enabled no)
			(sheetname "")
		)
		(fill yes
			(thermal_gap 0.5)
			(thermal_bridge_width 0.5)
			(island_removal_mode 0)
		)
		(polygon
			(pts
				(arc
					(start 102.35819 -51.000152)
					(mid 102.00005 -50.642012)
					(end 101.64191 -51.000152)
				)
				(arc
					(start 101.64191 -51.999896)
					(mid 101.999923 -52.35829)
					(end 102.35819 -52.00015)
				)
			)
		)
	)
	(zone
		(layers "In1.Cu" "In3.Cu" "In4.Cu" "In6.Cu")
		(hatch none 0.5)
		(connect_pads
			(clearance 0)
		)
		(min_thickness 0.25)
		(keepout
			(tracks not_allowed)
			(vias allowed)
			(pads allowed)
			(copperpour not_allowed)
			(footprints allowed)
		)
		(placement
			(enabled no)
			(sheetname "")
		)
		(fill yes
			(thermal_gap 0.5)
			(thermal_bridge_width 0.5)
			(island_removal_mode 0)
		)
		(polygon
			(pts
				(arc
					(start 103.983536 -111.30915)
					(mid 103.759 -110.566454)
					(end 103.016304 -110.79099)
				)
				(xy 102.266496 -112.190784)
				(arc
					(start 102.266496 -112.191038)
					(mid 102.491032 -112.933734)
					(end 103.233728 -112.709198)
				)
			)
		)
	)
	(zone
		(layers "In1.Cu" "In3.Cu" "In4.Cu" "In6.Cu")
		(hatch none 0.5)
		(connect_pads
			(clearance 0)
		)
		(min_thickness 0.25)
		(keepout
			(tracks not_allowed)
			(vias allowed)
			(pads allowed)
			(copperpour not_allowed)
			(footprints allowed)
		)
		(placement
			(enabled no)
			(sheetname "")
		)
		(fill yes
			(thermal_gap 0.5)
			(thermal_bridge_width 0.5)
			(island_removal_mode 0)
		)
		(polygon
			(pts
				(arc
					(start 97.361502 -3.800094)
					(mid 96.800162 -3.238754)
					(end 96.238822 -3.800094)
				)
				(arc
					(start 96.238822 -5.199888)
					(mid 96.800035 -5.761482)
					(end 97.361502 -5.200142)
				)
			)
		)
	)
	(zone
		(layers "In1.Cu" "In3.Cu" "In4.Cu" "In6.Cu")
		(hatch none 0.5)
		(connect_pads
			(clearance 0)
		)
		(min_thickness 0.25)
		(keepout
			(tracks not_allowed)
			(vias allowed)
			(pads allowed)
			(copperpour not_allowed)
			(footprints allowed)
		)
		(placement
			(enabled no)
			(sheetname "")
		)
		(fill yes
			(thermal_gap 0.5)
			(thermal_bridge_width 0.5)
			(island_removal_mode 0)
		)
		(polygon
			(pts
				(arc
					(start 113.561368 -9.800082)
					(mid 113.000028 -9.238742)
					(end 112.438688 -9.800082)
				)
				(arc
					(start 112.438688 -11.199876)
					(mid 112.999901 -11.76147)
					(end 113.561368 -11.20013)
				)
			)
		)
	)
	(zone
		(layers "In1.Cu" "In3.Cu" "In4.Cu" "In6.Cu")
		(hatch none 0.5)
		(connect_pads
			(clearance 0)
		)
		(min_thickness 0.25)
		(keepout
			(tracks not_allowed)
			(vias allowed)
			(pads allowed)
			(copperpour not_allowed)
			(footprints allowed)
		)
		(placement
			(enabled no)
			(sheetname "")
		)
		(fill yes
			(thermal_gap 0.5)
			(thermal_bridge_width 0.5)
			(island_removal_mode 0)
		)
		(polygon
			(pts
				(arc
					(start 123.358148 -55.000144)
					(mid 123.000008 -54.642004)
					(end 122.641868 -55.000144)
				)
				(arc
					(start 122.641868 -55.999888)
					(mid 122.999881 -56.358282)
					(end 123.358148 -56.000142)
				)
			)
		)
	)
	(zone
		(layers "In1.Cu" "In3.Cu" "In4.Cu" "In6.Cu")
		(hatch none 0.5)
		(connect_pads
			(clearance 0)
		)
		(min_thickness 0.25)
		(keepout
			(tracks not_allowed)
			(vias allowed)
			(pads allowed)
			(copperpour not_allowed)
			(footprints allowed)
		)
		(placement
			(enabled no)
			(sheetname "")
		)
		(fill yes
			(thermal_gap 0.5)
			(thermal_bridge_width 0.5)
			(island_removal_mode 0)
		)
		(polygon
			(pts
				(arc
					(start 126.000256 -65.641982)
					(mid 125.641862 -65.999995)
					(end 126.000002 -66.358262)
				)
				(arc
					(start 127 -66.358262)
					(mid 127.35814 -66.000122)
					(end 127 -65.641982)
				)
			)
		)
	)
	(zone
		(layers "In1.Cu" "In3.Cu" "In4.Cu" "In6.Cu")
		(hatch none 0.5)
		(connect_pads
			(clearance 0)
		)
		(min_thickness 0.25)
		(keepout
			(tracks not_allowed)
			(vias allowed)
			(pads allowed)
			(copperpour not_allowed)
			(footprints allowed)
		)
		(placement
			(enabled no)
			(sheetname "")
		)
		(fill yes
			(thermal_gap 0.5)
			(thermal_bridge_width 0.5)
			(island_removal_mode 0)
		)
		(polygon
			(pts
				(arc
					(start 114.358166 -55.000144)
					(mid 114.000026 -54.642004)
					(end 113.641886 -55.000144)
				)
				(arc
					(start 113.641886 -55.999888)
					(mid 113.999899 -56.358282)
					(end 114.358166 -56.000142)
				)
			)
		)
	)
	(zone
		(layers "In1.Cu" "In3.Cu" "In4.Cu" "In6.Cu")
		(hatch none 0.5)
		(connect_pads
			(clearance 0)
		)
		(min_thickness 0.25)
		(keepout
			(tracks not_allowed)
			(vias allowed)
			(pads allowed)
			(copperpour not_allowed)
			(footprints allowed)
		)
		(placement
			(enabled no)
			(sheetname "")
		)
		(fill yes
			(thermal_gap 0.5)
			(thermal_bridge_width 0.5)
			(island_removal_mode 0)
		)
		(polygon
			(pts
				(arc
					(start 107.35818 -55.000144)
					(mid 107.00004 -54.642004)
					(end 106.6419 -55.000144)
				)
				(arc
					(start 106.6419 -55.999888)
					(mid 106.999913 -56.358282)
					(end 107.35818 -56.000142)
				)
			)
		)
	)
	(zone
		(layers "In1.Cu" "In3.Cu" "In4.Cu" "In6.Cu")
		(hatch none 0.5)
		(connect_pads
			(clearance 0)
		)
		(min_thickness 0.25)
		(keepout
			(tracks not_allowed)
			(vias allowed)
			(pads allowed)
			(copperpour not_allowed)
			(footprints allowed)
		)
		(placement
			(enabled no)
			(sheetname "")
		)
		(fill yes
			(thermal_gap 0.5)
			(thermal_bridge_width 0.5)
			(island_removal_mode 0)
		)
		(polygon
			(pts
				(arc
					(start 110.358174 -55.000144)
					(mid 110.000034 -54.642004)
					(end 109.641894 -55.000144)
				)
				(arc
					(start 109.641894 -55.999888)
					(mid 109.999907 -56.358282)
					(end 110.358174 -56.000142)
				)
			)
		)
	)
	(zone
		(layers "In1.Cu" "In3.Cu" "In4.Cu" "In6.Cu")
		(hatch none 0.5)
		(connect_pads
			(clearance 0)
		)
		(min_thickness 0.25)
		(keepout
			(tracks not_allowed)
			(vias allowed)
			(pads allowed)
			(copperpour not_allowed)
			(footprints allowed)
		)
		(placement
			(enabled no)
			(sheetname "")
		)
		(fill yes
			(thermal_gap 0.5)
			(thermal_bridge_width 0.5)
			(island_removal_mode 0)
		)
		(polygon
			(pts
				(arc
					(start 107.35818 -52.00015)
					(mid 107.00004 -51.64201)
					(end 106.6419 -52.00015)
				)
				(arc
					(start 106.6419 -52.999894)
					(mid 106.999913 -53.358288)
					(end 107.35818 -53.000148)
				)
			)
		)
	)
	(zone
		(layers "In1.Cu" "In3.Cu" "In4.Cu" "In6.Cu")
		(hatch none 0.5)
		(connect_pads
			(clearance 0)
		)
		(min_thickness 0.25)
		(keepout
			(tracks not_allowed)
			(vias allowed)
			(pads allowed)
			(copperpour not_allowed)
			(footprints allowed)
		)
		(placement
			(enabled no)
			(sheetname "")
		)
		(fill yes
			(thermal_gap 0.5)
			(thermal_bridge_width 0.5)
			(island_removal_mode 0)
		)
		(polygon
			(pts
				(arc
					(start 122.56135 -3.800094)
					(mid 122.00001 -3.238754)
					(end 121.43867 -3.800094)
				)
				(arc
					(start 121.43867 -5.199888)
					(mid 121.999883 -5.761482)
					(end 122.56135 -5.200142)
				)
			)
		)
	)
	(zone
		(layers "In1.Cu" "In3.Cu" "In4.Cu" "In6.Cu")
		(hatch none 0.5)
		(connect_pads
			(clearance 0)
		)
		(min_thickness 0.25)
		(keepout
			(tracks not_allowed)
			(vias allowed)
			(pads allowed)
			(copperpour not_allowed)
			(footprints allowed)
		)
		(placement
			(enabled no)
			(sheetname "")
		)
		(fill yes
			(thermal_gap 0.5)
			(thermal_bridge_width 0.5)
			(island_removal_mode 0)
		)
		(polygon
			(pts
				(arc
					(start 103.358188 -55.000144)
					(mid 103.000048 -54.642004)
					(end 102.641908 -55.000144)
				)
				(arc
					(start 102.641908 -55.999888)
					(mid 102.999921 -56.358282)
					(end 103.358188 -56.000142)
				)
			)
		)
	)
	(zone
		(layers "In1.Cu" "In3.Cu" "In4.Cu" "In6.Cu")
		(hatch none 0.5)
		(connect_pads
			(clearance 0)
		)
		(min_thickness 0.25)
		(keepout
			(tracks not_allowed)
			(vias allowed)
			(pads allowed)
			(copperpour not_allowed)
			(footprints allowed)
		)
		(placement
			(enabled no)
			(sheetname "")
		)
		(fill yes
			(thermal_gap 0.5)
			(thermal_bridge_width 0.5)
			(island_removal_mode 0)
		)
		(polygon
			(pts
				(arc
					(start 113.561368 -2.600198)
					(mid 113.000028 -2.038858)
					(end 112.438688 -2.600198)
				)
				(arc
					(start 112.438688 -3.999738)
					(mid 112.999901 -4.561332)
					(end 113.561368 -3.999992)
				)
			)
		)
	)
	(zone
		(layers "In1.Cu" "In3.Cu" "In4.Cu" "In6.Cu")
		(hatch none 0.5)
		(connect_pads
			(clearance 0)
		)
		(min_thickness 0.25)
		(keepout
			(tracks not_allowed)
			(vias allowed)
			(pads allowed)
			(copperpour not_allowed)
			(footprints allowed)
		)
		(placement
			(enabled no)
			(sheetname "")
		)
		(fill yes
			(thermal_gap 0.5)
			(thermal_bridge_width 0.5)
			(island_removal_mode 0)
		)
		(polygon
			(pts
				(arc
					(start 166.508938 -23.166832)
					(mid 166.125398 -22.783292)
					(end 165.741858 -23.166832)
				)
				(arc
					(start 165.741858 -24.055578)
					(mid 166.125271 -24.439372)
					(end 166.508938 -24.055832)
				)
			)
		)
	)
	(zone
		(layers "In1.Cu" "In3.Cu" "In4.Cu" "In6.Cu")
		(hatch none 0.5)
		(connect_pads
			(clearance 0)
		)
		(min_thickness 0.25)
		(keepout
			(tracks not_allowed)
			(vias allowed)
			(pads allowed)
			(copperpour not_allowed)
			(footprints allowed)
		)
		(placement
			(enabled no)
			(sheetname "")
		)
		(fill yes
			(thermal_gap 0.5)
			(thermal_bridge_width 0.5)
			(island_removal_mode 0)
		)
		(polygon
			(pts
				(arc
					(start 118.961408 -3.800094)
					(mid 118.400068 -3.238754)
					(end 117.838728 -3.800094)
				)
				(arc
					(start 117.838728 -5.199888)
					(mid 118.399941 -5.761482)
					(end 118.961408 -5.200142)
				)
			)
		)
	)
	(zone
		(layers "In1.Cu" "In3.Cu" "In4.Cu" "In6.Cu")
		(hatch none 0.5)
		(connect_pads
			(clearance 0)
		)
		(min_thickness 0.25)
		(keepout
			(tracks not_allowed)
			(vias allowed)
			(pads allowed)
			(copperpour not_allowed)
			(footprints allowed)
		)
		(placement
			(enabled no)
			(sheetname "")
		)
		(fill yes
			(thermal_gap 0.5)
			(thermal_bridge_width 0.5)
			(island_removal_mode 0)
		)
		(polygon
			(pts
				(arc
					(start 180.819552 -23.596346)
					(mid 180.436012 -23.212806)
					(end 180.052472 -23.596346)
				)
				(arc
					(start 180.052472 -24.485092)
					(mid 180.435885 -24.868886)
					(end 180.819552 -24.485346)
				)
			)
		)
	)
	(zone
		(layers "In1.Cu" "In3.Cu" "In4.Cu" "In6.Cu")
		(hatch none 0.5)
		(connect_pads
			(clearance 0)
		)
		(min_thickness 0.25)
		(keepout
			(tracks not_allowed)
			(vias allowed)
			(pads allowed)
			(copperpour not_allowed)
			(footprints allowed)
		)
		(placement
			(enabled no)
			(sheetname "")
		)
		(fill yes
			(thermal_gap 0.5)
			(thermal_bridge_width 0.5)
			(island_removal_mode 0)
		)
		(polygon
			(pts
				(arc
					(start 132.677408 -45.814742)
					(mid 132.220208 -45.357542)
					(end 131.763008 -45.814742)
				)
				(arc
					(start 131.763008 -46.957488)
					(mid 132.220081 -47.414942)
					(end 132.677408 -46.957742)
				)
			)
		)
	)
	(zone
		(layers "In1.Cu" "In3.Cu" "In4.Cu" "In6.Cu")
		(hatch none 0.5)
		(connect_pads
			(clearance 0)
		)
		(min_thickness 0.25)
		(keepout
			(tracks not_allowed)
			(vias allowed)
			(pads allowed)
			(copperpour not_allowed)
			(footprints allowed)
		)
		(placement
			(enabled no)
			(sheetname "")
		)
		(fill yes
			(thermal_gap 0.5)
			(thermal_bridge_width 0.5)
			(island_removal_mode 0)
		)
		(polygon
			(pts
				(arc
					(start 126.000256 -62.641988)
					(mid 125.641862 -63.000001)
					(end 126.000002 -63.358268)
				)
				(arc
					(start 127 -63.358268)
					(mid 127.35814 -63.000128)
					(end 127 -62.641988)
				)
			)
		)
	)
	(zone
		(layers "In1.Cu" "In3.Cu" "In4.Cu" "In6.Cu")
		(hatch none 0.5)
		(connect_pads
			(clearance 0)
		)
		(min_thickness 0.25)
		(keepout
			(tracks not_allowed)
			(vias allowed)
			(pads allowed)
			(copperpour not_allowed)
			(footprints allowed)
		)
		(placement
			(enabled no)
			(sheetname "")
		)
		(fill yes
			(thermal_gap 0.5)
			(thermal_bridge_width 0.5)
			(island_removal_mode 0)
		)
		(polygon
			(pts
				(arc
					(start 108.161328 -3.800094)
					(mid 107.599988 -3.238754)
					(end 107.038648 -3.800094)
				)
				(arc
					(start 107.038648 -5.199888)
					(mid 107.599861 -5.761482)
					(end 108.161328 -5.200142)
				)
			)
		)
	)
	(zone
		(layers "In1.Cu" "In3.Cu" "In4.Cu" "In6.Cu")
		(hatch none 0.5)
		(connect_pads
			(clearance 0)
		)
		(min_thickness 0.25)
		(keepout
			(tracks not_allowed)
			(vias allowed)
			(pads allowed)
			(copperpour not_allowed)
			(footprints allowed)
		)
		(placement
			(enabled no)
			(sheetname "")
		)
		(fill yes
			(thermal_gap 0.5)
			(thermal_bridge_width 0.5)
			(island_removal_mode 0)
		)
		(polygon
			(pts
				(arc
					(start 126.000256 -60.641992)
					(mid 125.641862 -61.000005)
					(end 126.000002 -61.358272)
				)
				(arc
					(start 127 -61.358272)
					(mid 127.35814 -61.000132)
					(end 127 -60.641992)
				)
			)
		)
	)
	(zone
		(layers "In1.Cu" "In3.Cu" "In4.Cu" "In6.Cu")
		(hatch none 0.5)
		(connect_pads
			(clearance 0)
		)
		(min_thickness 0.25)
		(keepout
			(tracks not_allowed)
			(vias allowed)
			(pads allowed)
			(copperpour not_allowed)
			(footprints allowed)
		)
		(placement
			(enabled no)
			(sheetname "")
		)
		(fill yes
			(thermal_gap 0.5)
			(thermal_bridge_width 0.5)
			(island_removal_mode 0)
		)
		(polygon
			(pts
				(arc
					(start 166.199566 -37.183568)
					(mid 166.58336 -36.800155)
					(end 166.19982 -36.416488)
				)
				(arc
					(start 165.399974 -36.416488)
					(mid 165.016434 -36.800028)
					(end 165.399974 -37.183568)
				)
			)
		)
	)
	(zone
		(layers "In1.Cu" "In3.Cu" "In4.Cu" "In6.Cu")
		(hatch none 0.5)
		(connect_pads
			(clearance 0)
		)
		(min_thickness 0.25)
		(keepout
			(tracks not_allowed)
			(vias allowed)
			(pads allowed)
			(copperpour not_allowed)
			(footprints allowed)
		)
		(placement
			(enabled no)
			(sheetname "")
		)
		(fill yes
			(thermal_gap 0.5)
			(thermal_bridge_width 0.5)
			(island_removal_mode 0)
		)
		(polygon
			(pts
				(arc
					(start 100.961444 -3.800094)
					(mid 100.400104 -3.238754)
					(end 99.838764 -3.800094)
				)
				(arc
					(start 99.838764 -5.199888)
					(mid 100.399977 -5.761482)
					(end 100.961444 -5.200142)
				)
			)
		)
	)
	(zone
		(layers "In1.Cu" "In3.Cu" "In4.Cu" "In6.Cu")
		(hatch none 0.5)
		(connect_pads
			(clearance 0)
		)
		(min_thickness 0.25)
		(keepout
			(tracks not_allowed)
			(vias allowed)
			(pads allowed)
			(copperpour not_allowed)
			(footprints allowed)
		)
		(placement
			(enabled no)
			(sheetname "")
		)
		(fill yes
			(thermal_gap 0.5)
			(thermal_bridge_width 0.5)
			(island_removal_mode 0)
		)
		(polygon
			(pts
				(arc
					(start 126.000256 -61.64199)
					(mid 125.641862 -62.000003)
					(end 126.000002 -62.35827)
				)
				(arc
					(start 127 -62.35827)
					(mid 127.35814 -62.00013)
					(end 127 -61.64199)
				)
			)
		)
	)
	(zone
		(layers "In1.Cu" "In3.Cu" "In4.Cu" "In6.Cu")
		(hatch none 0.5)
		(connect_pads
			(clearance 0)
		)
		(min_thickness 0.25)
		(keepout
			(tracks not_allowed)
			(vias allowed)
			(pads allowed)
			(copperpour not_allowed)
			(footprints allowed)
		)
		(placement
			(enabled no)
			(sheetname "")
		)
		(fill yes
			(thermal_gap 0.5)
			(thermal_bridge_width 0.5)
			(island_removal_mode 0)
		)
		(polygon
			(pts
				(arc
					(start 168.543478 -23.123906)
					(mid 168.159938 -22.740366)
					(end 167.776398 -23.123906)
				)
				(arc
					(start 167.776398 -24.012652)
					(mid 168.159811 -24.396446)
					(end 168.543478 -24.012906)
				)
			)
		)
	)
	(zone
		(layers "In1.Cu" "In3.Cu" "In4.Cu" "In6.Cu")
		(hatch none 0.5)
		(connect_pads
			(clearance 0)
		)
		(min_thickness 0.25)
		(keepout
			(tracks not_allowed)
			(vias allowed)
			(pads allowed)
			(copperpour not_allowed)
			(footprints allowed)
		)
		(placement
			(enabled no)
			(sheetname "")
		)
		(fill yes
			(thermal_gap 0.5)
			(thermal_bridge_width 0.5)
			(island_removal_mode 0)
		)
		(polygon
			(pts
				(arc
					(start 129.761488 -10.999978)
					(mid 129.200148 -10.438638)
					(end 128.638808 -10.999978)
				)
				(arc
					(start 128.638808 -12.399772)
					(mid 129.200021 -12.961366)
					(end 129.761488 -12.400026)
				)
			)
		)
	)
	(zone
		(layers "In1.Cu" "In3.Cu" "In4.Cu" "In6.Cu")
		(hatch none 0.5)
		(connect_pads
			(clearance 0)
		)
		(min_thickness 0.25)
		(keepout
			(tracks not_allowed)
			(vias allowed)
			(pads allowed)
			(copperpour not_allowed)
			(footprints allowed)
		)
		(placement
			(enabled no)
			(sheetname "")
		)
		(fill yes
			(thermal_gap 0.5)
			(thermal_bridge_width 0.5)
			(island_removal_mode 0)
		)
		(polygon
			(pts
				(arc
					(start 182.361332 -9.800082)
					(mid 181.799992 -9.238742)
					(end 181.238652 -9.800082)
				)
				(arc
					(start 181.238652 -11.199876)
					(mid 181.799865 -11.76147)
					(end 182.361332 -11.20013)
				)
			)
		)
	)
	(zone
		(layers "In1.Cu" "In3.Cu" "In4.Cu" "In6.Cu")
		(hatch none 0.5)
		(connect_pads
			(clearance 0)
		)
		(min_thickness 0.25)
		(keepout
			(tracks not_allowed)
			(vias allowed)
			(pads allowed)
			(copperpour not_allowed)
			(footprints allowed)
		)
		(placement
			(enabled no)
			(sheetname "")
		)
		(fill yes
			(thermal_gap 0.5)
			(thermal_bridge_width 0.5)
			(island_removal_mode 0)
		)
		(polygon
			(pts
				(arc
					(start 122.56135 -10.999978)
					(mid 122.00001 -10.438638)
					(end 121.43867 -10.999978)
				)
				(arc
					(start 121.43867 -12.399772)
					(mid 121.999883 -12.961366)
					(end 122.56135 -12.400026)
				)
			)
		)
	)
	(zone
		(layers "In1.Cu" "In3.Cu" "In4.Cu" "In6.Cu")
		(hatch none 0.5)
		(connect_pads
			(clearance 0)
		)
		(min_thickness 0.25)
		(keepout
			(tracks not_allowed)
			(vias allowed)
			(pads allowed)
			(copperpour not_allowed)
			(footprints allowed)
		)
		(placement
			(enabled no)
			(sheetname "")
		)
		(fill yes
			(thermal_gap 0.5)
			(thermal_bridge_width 0.5)
			(island_removal_mode 0)
		)
		(polygon
			(pts
				(arc
					(start 174.698406 -23.112476)
					(mid 174.314866 -22.728936)
					(end 173.931326 -23.112476)
				)
				(arc
					(start 173.931326 -24.001222)
					(mid 174.314739 -24.385016)
					(end 174.698406 -24.001476)
				)
			)
		)
	)
	(zone
		(layers "In1.Cu" "In3.Cu" "In4.Cu" "In6.Cu")
		(hatch none 0.5)
		(connect_pads
			(clearance 0)
		)
		(min_thickness 0.25)
		(keepout
			(tracks not_allowed)
			(vias allowed)
			(pads allowed)
			(copperpour not_allowed)
			(footprints allowed)
		)
		(placement
			(enabled no)
			(sheetname "")
		)
		(fill yes
			(thermal_gap 0.5)
			(thermal_bridge_width 0.5)
			(island_removal_mode 0)
		)
		(polygon
			(pts
				(arc
					(start 133.36143 -3.800094)
					(mid 132.80009 -3.238754)
					(end 132.23875 -3.800094)
				)
				(arc
					(start 132.23875 -5.199888)
					(mid 132.799963 -5.761482)
					(end 133.36143 -5.200142)
				)
			)
		)
	)
	(zone
		(layers "In1.Cu" "In3.Cu" "In4.Cu" "In6.Cu")
		(hatch none 0.5)
		(connect_pads
			(clearance 0)
		)
		(min_thickness 0.25)
		(keepout
			(tracks not_allowed)
			(vias allowed)
			(pads allowed)
			(copperpour not_allowed)
			(footprints allowed)
		)
		(placement
			(enabled no)
			(sheetname "")
		)
		(fill yes
			(thermal_gap 0.5)
			(thermal_bridge_width 0.5)
			(island_removal_mode 0)
		)
		(polygon
			(pts
				(arc
					(start 114.358166 -51.000152)
					(mid 114.000026 -50.642012)
					(end 113.641886 -51.000152)
				)
				(arc
					(start 113.641886 -51.999896)
					(mid 113.999899 -52.35829)
					(end 114.358166 -52.00015)
				)
			)
		)
	)
	(zone
		(layers "In1.Cu" "In3.Cu" "In4.Cu" "In6.Cu")
		(hatch none 0.5)
		(connect_pads
			(clearance 0)
		)
		(min_thickness 0.25)
		(keepout
			(tracks not_allowed)
			(vias allowed)
			(pads allowed)
			(copperpour not_allowed)
			(footprints allowed)
		)
		(placement
			(enabled no)
			(sheetname "")
		)
		(fill yes
			(thermal_gap 0.5)
			(thermal_bridge_width 0.5)
			(island_removal_mode 0)
		)
		(polygon
			(pts
				(arc
					(start 167.44188 -31.199582)
					(mid 167.80002 -31.557976)
					(end 168.15816 -31.199582)
				)
				(arc
					(start 168.157906 -30.39999)
					(mid 167.799639 -30.04185)
					(end 167.441626 -30.400244)
				)
			)
		)
	)
	(zone
		(layers "In1.Cu" "In3.Cu" "In4.Cu" "In6.Cu")
		(hatch none 0.5)
		(connect_pads
			(clearance 0)
		)
		(min_thickness 0.25)
		(keepout
			(tracks not_allowed)
			(vias allowed)
			(pads allowed)
			(copperpour not_allowed)
			(footprints allowed)
		)
		(placement
			(enabled no)
			(sheetname "")
		)
		(fill yes
			(thermal_gap 0.5)
			(thermal_bridge_width 0.5)
			(island_removal_mode 0)
		)
		(polygon
			(pts
				(arc
					(start 144.16151 -3.800094)
					(mid 143.60017 -3.238754)
					(end 143.03883 -3.800094)
				)
				(arc
					(start 143.03883 -5.199888)
					(mid 143.600043 -5.761482)
					(end 144.16151 -5.200142)
				)
			)
		)
	)
	(zone
		(layers "In1.Cu" "In3.Cu" "In4.Cu" "In6.Cu")
		(hatch none 0.5)
		(connect_pads
			(clearance 0)
		)
		(min_thickness 0.25)
		(keepout
			(tracks not_allowed)
			(vias allowed)
			(pads allowed)
			(copperpour not_allowed)
			(footprints allowed)
		)
		(placement
			(enabled no)
			(sheetname "")
		)
		(fill yes
			(thermal_gap 0.5)
			(thermal_bridge_width 0.5)
			(island_removal_mode 0)
		)
		(polygon
			(pts
				(xy 103.189024 -105.08488) (xy 103.938832 -103.685086)
				(arc
					(start 103.93807 -103.684832)
					(mid 103.734616 -103.011986)
					(end 103.06177 -103.21544)
				)
				(xy 103.061008 -103.215186) (xy 102.311454 -104.614726) (xy 102.311454 -104.61498)
				(arc
					(start 102.311962 -104.615234)
					(mid 102.515416 -105.28808)
					(end 103.188262 -105.084626)
				)
			)
		)
	)
	(zone
		(layers "In1.Cu" "In3.Cu" "In4.Cu" "In6.Cu")
		(hatch none 0.5)
		(connect_pads
			(clearance 0)
		)
		(min_thickness 0.25)
		(keepout
			(tracks not_allowed)
			(vias allowed)
			(pads allowed)
			(copperpour not_allowed)
			(footprints allowed)
		)
		(placement
			(enabled no)
			(sheetname "")
		)
		(fill yes
			(thermal_gap 0.5)
			(thermal_bridge_width 0.5)
			(island_removal_mode 0)
		)
		(polygon
			(pts
				(arc
					(start 118.961408 -10.999978)
					(mid 118.400068 -10.438638)
					(end 117.838728 -10.999978)
				)
				(arc
					(start 117.838728 -12.399772)
					(mid 118.399941 -12.961366)
					(end 118.961408 -12.400026)
				)
			)
		)
	)
	(zone
		(layers "In1.Cu" "In3.Cu" "In4.Cu" "In6.Cu")
		(hatch none 0.5)
		(connect_pads
			(clearance 0)
		)
		(min_thickness 0.25)
		(keepout
			(tracks not_allowed)
			(vias allowed)
			(pads allowed)
			(copperpour not_allowed)
			(footprints allowed)
		)
		(placement
			(enabled no)
			(sheetname "")
		)
		(fill yes
			(thermal_gap 0.5)
			(thermal_bridge_width 0.5)
			(island_removal_mode 0)
		)
		(polygon
			(pts
				(arc
					(start 182.361332 -2.600198)
					(mid 181.799992 -2.038858)
					(end 181.238652 -2.600198)
				)
				(arc
					(start 181.238652 -3.999738)
					(mid 181.799865 -4.561332)
					(end 182.361332 -3.999992)
				)
			)
		)
	)
	(zone
		(layers "In1.Cu" "In3.Cu" "In4.Cu" "In6.Cu")
		(hatch none 0.5)
		(connect_pads
			(clearance 0)
		)
		(min_thickness 0.25)
		(keepout
			(tracks not_allowed)
			(vias allowed)
			(pads allowed)
			(copperpour not_allowed)
			(footprints allowed)
		)
		(placement
			(enabled no)
			(sheetname "")
		)
		(fill yes
			(thermal_gap 0.5)
			(thermal_bridge_width 0.5)
			(island_removal_mode 0)
		)
		(polygon
			(pts
				(arc
					(start 130.000248 -63.641986)
					(mid 129.641854 -63.999999)
					(end 129.999994 -64.358266)
				)
				(arc
					(start 130.999992 -64.358266)
					(mid 131.358132 -64.000126)
					(end 130.999992 -63.641986)
				)
			)
		)
	)
	(zone
		(layers "In1.Cu" "In3.Cu" "In4.Cu" "In6.Cu")
		(hatch none 0.5)
		(connect_pads
			(clearance 0)
		)
		(min_thickness 0.25)
		(keepout
			(tracks not_allowed)
			(vias allowed)
			(pads allowed)
			(copperpour not_allowed)
			(footprints allowed)
		)
		(placement
			(enabled no)
			(sheetname "")
		)
		(fill yes
			(thermal_gap 0.5)
			(thermal_bridge_width 0.5)
			(island_removal_mode 0)
		)
		(polygon
			(pts
				(arc
					(start 119.358156 -51.000152)
					(mid 119.000016 -50.642012)
					(end 118.641876 -51.000152)
				)
				(arc
					(start 118.641876 -51.999896)
					(mid 118.999889 -52.35829)
					(end 119.358156 -52.00015)
				)
			)
		)
	)
	(zone
		(layers "In1.Cu" "In3.Cu" "In4.Cu" "In6.Cu")
		(hatch none 0.5)
		(connect_pads
			(clearance 0)
		)
		(min_thickness 0.25)
		(keepout
			(tracks not_allowed)
			(vias allowed)
			(pads allowed)
			(copperpour not_allowed)
			(footprints allowed)
		)
		(placement
			(enabled no)
			(sheetname "")
		)
		(fill yes
			(thermal_gap 0.5)
			(thermal_bridge_width 0.5)
			(island_removal_mode 0)
		)
		(polygon
			(pts
				(arc
					(start 86.561422 -3.800094)
					(mid 86.000082 -3.238754)
					(end 85.438742 -3.800094)
				)
				(arc
					(start 85.438742 -5.199888)
					(mid 85.999955 -5.761482)
					(end 86.561422 -5.200142)
				)
			)
		)
	)
	(zone
		(layers "In1.Cu" "In3.Cu" "In4.Cu" "In6.Cu")
		(hatch none 0.5)
		(connect_pads
			(clearance 0)
		)
		(min_thickness 0.25)
		(keepout
			(tracks not_allowed)
			(vias allowed)
			(pads allowed)
			(copperpour not_allowed)
			(footprints allowed)
		)
		(placement
			(enabled no)
			(sheetname "")
		)
		(fill yes
			(thermal_gap 0.5)
			(thermal_bridge_width 0.5)
			(island_removal_mode 0)
		)
		(polygon
			(pts
				(arc
					(start 166.999666 -32.383476)
					(mid 167.38346 -32.000063)
					(end 166.99992 -31.616396)
				)
				(arc
					(start 166.200074 -31.616396)
					(mid 165.816534 -31.999936)
					(end 166.200074 -32.383476)
				)
			)
		)
	)
	(zone
		(layers "In1.Cu" "In3.Cu" "In4.Cu" "In6.Cu")
		(hatch none 0.5)
		(connect_pads
			(clearance 0)
		)
		(min_thickness 0.25)
		(keepout
			(tracks not_allowed)
			(vias allowed)
			(pads allowed)
			(copperpour not_allowed)
			(footprints allowed)
		)
		(placement
			(enabled no)
			(sheetname "")
		)
		(fill yes
			(thermal_gap 0.5)
			(thermal_bridge_width 0.5)
			(island_removal_mode 0)
		)
		(polygon
			(pts
				(arc
					(start 104.358186 -51.000152)
					(mid 104.000046 -50.642012)
					(end 103.641906 -51.000152)
				)
				(arc
					(start 103.641906 -51.999896)
					(mid 103.999919 -52.35829)
					(end 104.358186 -52.00015)
				)
			)
		)
	)
	(zone
		(layers "In1.Cu" "In3.Cu" "In4.Cu" "In6.Cu")
		(hatch none 0.5)
		(connect_pads
			(clearance 0)
		)
		(min_thickness 0.25)
		(keepout
			(tracks not_allowed)
			(vias allowed)
			(pads allowed)
			(copperpour not_allowed)
			(footprints allowed)
		)
		(placement
			(enabled no)
			(sheetname "")
		)
		(fill yes
			(thermal_gap 0.5)
			(thermal_bridge_width 0.5)
			(island_removal_mode 0)
		)
		(polygon
			(pts
				(arc
					(start 126.000256 -54.642004)
					(mid 125.641862 -55.000017)
					(end 126.000002 -55.358284)
				)
				(arc
					(start 127 -55.358284)
					(mid 127.35814 -55.000144)
					(end 127 -54.642004)
				)
			)
		)
	)
	(zone
		(layers "In1.Cu" "In3.Cu" "In4.Cu" "In6.Cu")
		(hatch none 0.5)
		(connect_pads
			(clearance 0)
		)
		(min_thickness 0.25)
		(keepout
			(tracks not_allowed)
			(vias allowed)
			(pads allowed)
			(copperpour not_allowed)
			(footprints allowed)
		)
		(placement
			(enabled no)
			(sheetname "")
		)
		(fill yes
			(thermal_gap 0.5)
			(thermal_bridge_width 0.5)
			(island_removal_mode 0)
		)
		(polygon
			(pts
				(arc
					(start 127.533908 -45.844206)
					(mid 127.076708 -45.387006)
					(end 126.619508 -45.844206)
				)
				(arc
					(start 126.619508 -46.986952)
					(mid 127.076581 -47.444406)
					(end 127.533908 -46.987206)
				)
			)
		)
	)
	(zone
		(layers "In1.Cu" "In3.Cu" "In4.Cu" "In6.Cu")
		(hatch none 0.5)
		(connect_pads
			(clearance 0)
		)
		(min_thickness 0.25)
		(keepout
			(tracks not_allowed)
			(vias allowed)
			(pads allowed)
			(copperpour not_allowed)
			(footprints allowed)
		)
		(placement
			(enabled no)
			(sheetname "")
		)
		(fill yes
			(thermal_gap 0.5)
			(thermal_bridge_width 0.5)
			(island_removal_mode 0)
		)
		(polygon
			(pts
				(xy 105.438956 -105.085134) (xy 106.189018 -103.68534)
				(arc
					(start 106.188256 -103.684832)
					(mid 105.984802 -103.011986)
					(end 105.311956 -103.21544)
				)
				(xy 105.311194 -103.214932) (xy 104.561386 -104.614472) (xy 104.561386 -104.61498)
				(arc
					(start 104.561894 -104.615234)
					(mid 104.765348 -105.28808)
					(end 105.438194 -105.084626)
				)
			)
		)
	)
	(zone
		(layers "In1.Cu" "In3.Cu" "In4.Cu" "In6.Cu")
		(hatch none 0.5)
		(connect_pads
			(clearance 0)
		)
		(min_thickness 0.25)
		(keepout
			(tracks not_allowed)
			(vias allowed)
			(pads allowed)
			(copperpour not_allowed)
			(footprints allowed)
		)
		(placement
			(enabled no)
			(sheetname "")
		)
		(fill yes
			(thermal_gap 0.5)
			(thermal_bridge_width 0.5)
			(island_removal_mode 0)
		)
		(polygon
			(pts
				(arc
					(start 124.361448 -2.600198)
					(mid 123.800108 -2.038858)
					(end 123.238768 -2.600198)
				)
				(arc
					(start 123.238768 -3.999738)
					(mid 123.799981 -4.561332)
					(end 124.361448 -3.999992)
				)
			)
		)
	)
	(zone
		(layers "In1.Cu" "In3.Cu" "In4.Cu" "In6.Cu")
		(hatch none 0.5)
		(connect_pads
			(clearance 0)
		)
		(min_thickness 0.25)
		(keepout
			(tracks not_allowed)
			(vias allowed)
			(pads allowed)
			(copperpour not_allowed)
			(footprints allowed)
		)
		(placement
			(enabled no)
			(sheetname "")
		)
		(fill yes
			(thermal_gap 0.5)
			(thermal_bridge_width 0.5)
			(island_removal_mode 0)
		)
		(polygon
			(pts
				(arc
					(start 170.600624 -23.11527)
					(mid 170.217084 -22.73173)
					(end 169.833544 -23.11527)
				)
				(arc
					(start 169.833544 -24.004016)
					(mid 170.216957 -24.38781)
					(end 170.600624 -24.00427)
				)
			)
		)
	)
	(zone
		(layers "In1.Cu" "In3.Cu" "In4.Cu" "In6.Cu")
		(hatch none 0.5)
		(connect_pads
			(clearance 0)
		)
		(min_thickness 0.25)
		(keepout
			(tracks not_allowed)
			(vias allowed)
			(pads allowed)
			(copperpour not_allowed)
			(footprints allowed)
		)
		(placement
			(enabled no)
			(sheetname "")
		)
		(fill yes
			(thermal_gap 0.5)
			(thermal_bridge_width 0.5)
			(island_removal_mode 0)
		)
		(polygon
			(pts
				(arc
					(start 126.000256 -55.642002)
					(mid 125.641862 -56.000015)
					(end 126.000002 -56.358282)
				)
				(arc
					(start 127 -56.358282)
					(mid 127.35814 -56.000142)
					(end 127 -55.642002)
				)
			)
		)
	)
	(zone
		(layers "In1.Cu" "In3.Cu" "In4.Cu" "In6.Cu")
		(hatch none 0.5)
		(connect_pads
			(clearance 0)
		)
		(min_thickness 0.25)
		(keepout
			(tracks not_allowed)
			(vias allowed)
			(pads allowed)
			(copperpour not_allowed)
			(footprints allowed)
		)
		(placement
			(enabled no)
			(sheetname "")
		)
		(fill yes
			(thermal_gap 0.5)
			(thermal_bridge_width 0.5)
			(island_removal_mode 0)
		)
		(polygon
			(pts
				(arc
					(start 136.961372 -10.999978)
					(mid 136.400032 -10.438638)
					(end 135.838692 -10.999978)
				)
				(arc
					(start 135.838692 -12.399772)
					(mid 136.399905 -12.961366)
					(end 136.961372 -12.400026)
				)
			)
		)
	)
	(zone
		(layers "In1.Cu" "In3.Cu" "In4.Cu" "In6.Cu")
		(hatch none 0.5)
		(connect_pads
			(clearance 0)
		)
		(min_thickness 0.25)
		(keepout
			(tracks not_allowed)
			(vias allowed)
			(pads allowed)
			(copperpour not_allowed)
			(footprints allowed)
		)
		(placement
			(enabled no)
			(sheetname "")
		)
		(fill yes
			(thermal_gap 0.5)
			(thermal_bridge_width 0.5)
			(island_removal_mode 0)
		)
		(polygon
			(pts
				(arc
					(start 115.361466 -3.800094)
					(mid 114.800126 -3.238754)
					(end 114.238786 -3.800094)
				)
				(arc
					(start 114.238786 -5.199888)
					(mid 114.799999 -5.761482)
					(end 115.361466 -5.200142)
				)
			)
		)
	)
	(zone
		(layers "In1.Cu" "In3.Cu" "In4.Cu" "In6.Cu")
		(hatch none 0.5)
		(connect_pads
			(clearance 0)
		)
		(min_thickness 0.25)
		(keepout
			(tracks not_allowed)
			(vias allowed)
			(pads allowed)
			(copperpour not_allowed)
			(footprints allowed)
		)
		(placement
			(enabled no)
			(sheetname "")
		)
		(fill yes
			(thermal_gap 0.5)
			(thermal_bridge_width 0.5)
			(island_removal_mode 0)
		)
		(polygon
			(pts
				(arc
					(start 106.361484 -9.800082)
					(mid 105.800144 -9.238742)
					(end 105.238804 -9.800082)
				)
				(arc
					(start 105.238804 -11.199876)
					(mid 105.800017 -11.76147)
					(end 106.361484 -11.20013)
				)
			)
		)
	)
	(zone
		(layers "In1.Cu" "In3.Cu" "In4.Cu" "In6.Cu")
		(hatch none 0.5)
		(connect_pads
			(clearance 0)
		)
		(min_thickness 0.25)
		(keepout
			(tracks not_allowed)
			(vias allowed)
			(pads allowed)
			(copperpour not_allowed)
			(footprints allowed)
		)
		(placement
			(enabled no)
			(sheetname "")
		)
		(fill yes
			(thermal_gap 0.5)
			(thermal_bridge_width 0.5)
			(island_removal_mode 0)
		)
		(polygon
			(pts
				(arc
					(start 166.58336 -30.400244)
					(mid 166.199947 -30.01645)
					(end 165.81628 -30.39999)
				)
				(arc
					(start 165.81628 -31.199836)
					(mid 166.19982 -31.583376)
					(end 166.58336 -31.199836)
				)
			)
		)
	)
	(zone
		(layers "In1.Cu" "In3.Cu" "In4.Cu" "In6.Cu")
		(hatch none 0.5)
		(connect_pads
			(clearance 0)
		)
		(min_thickness 0.25)
		(keepout
			(tracks not_allowed)
			(vias allowed)
			(pads allowed)
			(copperpour not_allowed)
			(footprints allowed)
		)
		(placement
			(enabled no)
			(sheetname "")
		)
		(fill yes
			(thermal_gap 0.5)
			(thermal_bridge_width 0.5)
			(island_removal_mode 0)
		)
		(polygon
			(pts
				(arc
					(start 135.161528 -9.800082)
					(mid 134.600188 -9.238742)
					(end 134.038848 -9.800082)
				)
				(arc
					(start 134.038848 -11.199876)
					(mid 134.600061 -11.76147)
					(end 135.161528 -11.20013)
				)
			)
		)
	)
	(zone
		(layers "In1.Cu" "In3.Cu" "In4.Cu" "In6.Cu")
		(hatch none 0.5)
		(connect_pads
			(clearance 0)
		)
		(min_thickness 0.25)
		(keepout
			(tracks not_allowed)
			(vias allowed)
			(pads allowed)
			(copperpour not_allowed)
			(footprints allowed)
		)
		(placement
			(enabled no)
			(sheetname "")
		)
		(fill yes
			(thermal_gap 0.5)
			(thermal_bridge_width 0.5)
			(island_removal_mode 0)
		)
		(polygon
			(pts
				(arc
					(start 106.233722 -115.10899)
					(mid 106.009186 -114.366294)
					(end 105.26649 -114.59083)
				)
				(arc
					(start 104.516428 -115.990624)
					(mid 104.740809 -116.733627)
					(end 105.48366 -116.509038)
				)
			)
		)
	)
	(zone
		(layers "In1.Cu" "In3.Cu" "In4.Cu" "In6.Cu")
		(hatch none 0.5)
		(connect_pads
			(clearance 0)
		)
		(min_thickness 0.25)
		(keepout
			(tracks not_allowed)
			(vias allowed)
			(pads allowed)
			(copperpour not_allowed)
			(footprints allowed)
		)
		(placement
			(enabled no)
			(sheetname "")
		)
		(fill yes
			(thermal_gap 0.5)
			(thermal_bridge_width 0.5)
			(island_removal_mode 0)
		)
		(polygon
			(pts
				(arc
					(start 138.76147 -2.600198)
					(mid 138.20013 -2.038858)
					(end 137.63879 -2.600198)
				)
				(arc
					(start 137.63879 -3.999738)
					(mid 138.200003 -4.561332)
					(end 138.76147 -3.999992)
				)
			)
		)
	)
	(zone
		(layers "In1.Cu" "In3.Cu" "In4.Cu" "In6.Cu")
		(hatch none 0.5)
		(connect_pads
			(clearance 0)
		)
		(min_thickness 0.25)
		(keepout
			(tracks not_allowed)
			(vias allowed)
			(pads allowed)
			(copperpour not_allowed)
			(footprints allowed)
		)
		(placement
			(enabled no)
			(sheetname "")
		)
		(fill yes
			(thermal_gap 0.5)
			(thermal_bridge_width 0.5)
			(island_removal_mode 0)
		)
		(polygon
			(pts
				(arc
					(start 108.358178 -55.000144)
					(mid 108.000038 -54.642004)
					(end 107.641898 -55.000144)
				)
				(arc
					(start 107.641898 -55.999888)
					(mid 107.999911 -56.358282)
					(end 108.358178 -56.000142)
				)
			)
		)
	)
	(zone
		(layers "In1.Cu" "In3.Cu" "In4.Cu" "In6.Cu")
		(hatch none 0.5)
		(connect_pads
			(clearance 0)
		)
		(min_thickness 0.25)
		(keepout
			(tracks not_allowed)
			(vias allowed)
			(pads allowed)
			(copperpour not_allowed)
			(footprints allowed)
		)
		(placement
			(enabled no)
			(sheetname "")
		)
		(fill yes
			(thermal_gap 0.5)
			(thermal_bridge_width 0.5)
			(island_removal_mode 0)
		)
		(polygon
			(pts
				(arc
					(start 103.358188 -52.00015)
					(mid 103.000048 -51.64201)
					(end 102.641908 -52.00015)
				)
				(arc
					(start 102.641908 -52.999894)
					(mid 102.999921 -53.358288)
					(end 103.358188 -53.000148)
				)
			)
		)
	)
	(zone
		(layers "In1.Cu" "In3.Cu" "In4.Cu" "In6.Cu")
		(hatch none 0.5)
		(connect_pads
			(clearance 0)
		)
		(min_thickness 0.25)
		(keepout
			(tracks not_allowed)
			(vias allowed)
			(pads allowed)
			(copperpour not_allowed)
			(footprints allowed)
		)
		(placement
			(enabled no)
			(sheetname "")
		)
		(fill yes
			(thermal_gap 0.5)
			(thermal_bridge_width 0.5)
			(island_removal_mode 0)
		)
		(polygon
			(pts
				(arc
					(start 127.000254 -52.642008)
					(mid 126.64186 -53.000021)
					(end 127 -53.358288)
				)
				(arc
					(start 127.999998 -53.358288)
					(mid 128.358138 -53.000148)
					(end 127.999998 -52.642008)
				)
			)
		)
	)
	(zone
		(layers "In1.Cu" "In3.Cu" "In4.Cu" "In6.Cu")
		(hatch none 0.5)
		(connect_pads
			(clearance 0)
		)
		(min_thickness 0.25)
		(keepout
			(tracks not_allowed)
			(vias allowed)
			(pads allowed)
			(copperpour not_allowed)
			(footprints allowed)
		)
		(placement
			(enabled no)
			(sheetname "")
		)
		(fill yes
			(thermal_gap 0.5)
			(thermal_bridge_width 0.5)
			(island_removal_mode 0)
		)
		(polygon
			(pts
				(arc
					(start 120.761506 -9.800082)
					(mid 120.200166 -9.238742)
					(end 119.638826 -9.800082)
				)
				(arc
					(start 119.638826 -11.199876)
					(mid 120.200039 -11.76147)
					(end 120.761506 -11.20013)
				)
			)
		)
	)
	(zone
		(layers "In1.Cu" "In3.Cu" "In4.Cu" "In6.Cu")
		(hatch none 0.5)
		(connect_pads
			(clearance 0)
		)
		(min_thickness 0.25)
		(keepout
			(tracks not_allowed)
			(vias allowed)
			(pads allowed)
			(copperpour not_allowed)
			(footprints allowed)
		)
		(placement
			(enabled no)
			(sheetname "")
		)
		(fill yes
			(thermal_gap 0.5)
			(thermal_bridge_width 0.5)
			(island_removal_mode 0)
		)
		(polygon
			(pts
				(arc
					(start 189.561216 -2.600198)
					(mid 188.999876 -2.038858)
					(end 188.438536 -2.600198)
				)
				(arc
					(start 188.438536 -3.999738)
					(mid 188.999749 -4.561332)
					(end 189.561216 -3.999992)
				)
			)
		)
	)
	(zone
		(layers "In1.Cu" "In3.Cu" "In4.Cu" "In6.Cu")
		(hatch none 0.5)
		(connect_pads
			(clearance 0)
		)
		(min_thickness 0.25)
		(keepout
			(tracks not_allowed)
			(vias allowed)
			(pads allowed)
			(copperpour not_allowed)
			(footprints allowed)
		)
		(placement
			(enabled no)
			(sheetname "")
		)
		(fill yes
			(thermal_gap 0.5)
			(thermal_bridge_width 0.5)
			(island_removal_mode 0)
		)
		(polygon
			(pts
				(arc
					(start 169.841926 -31.199836)
					(mid 170.200066 -31.55823)
					(end 170.558206 -31.199836)
				)
				(arc
					(start 170.557952 -30.39999)
					(mid 170.199685 -30.04185)
					(end 169.841672 -30.400244)
				)
			)
		)
	)
	(zone
		(layers "In1.Cu" "In3.Cu" "In4.Cu" "In6.Cu")
		(hatch none 0.5)
		(connect_pads
			(clearance 0)
		)
		(min_thickness 0.25)
		(keepout
			(tracks not_allowed)
			(vias allowed)
			(pads allowed)
			(copperpour not_allowed)
			(footprints allowed)
		)
		(placement
			(enabled no)
			(sheetname "")
		)
		(fill yes
			(thermal_gap 0.5)
			(thermal_bridge_width 0.5)
			(island_removal_mode 0)
		)
		(polygon
			(pts
				(arc
					(start 111.358172 -55.000144)
					(mid 111.000032 -54.642004)
					(end 110.641892 -55.000144)
				)
				(arc
					(start 110.641892 -55.999888)
					(mid 110.999905 -56.358282)
					(end 111.358172 -56.000142)
				)
			)
		)
	)
	(zone
		(layers "In1.Cu" "In3.Cu" "In4.Cu" "In6.Cu")
		(hatch none 0.5)
		(connect_pads
			(clearance 0)
		)
		(min_thickness 0.25)
		(keepout
			(tracks not_allowed)
			(vias allowed)
			(pads allowed)
			(copperpour not_allowed)
			(footprints allowed)
		)
		(placement
			(enabled no)
			(sheetname "")
		)
		(fill yes
			(thermal_gap 0.5)
			(thermal_bridge_width 0.5)
			(island_removal_mode 0)
		)
		(polygon
			(pts
				(arc
					(start 90.161364 -3.800094)
					(mid 89.600024 -3.238754)
					(end 89.038684 -3.800094)
				)
				(arc
					(start 89.038684 -5.199888)
					(mid 89.599897 -5.761482)
					(end 90.161364 -5.200142)
				)
			)
		)
	)
	(zone
		(layers "In1.Cu" "In3.Cu" "In4.Cu" "In6.Cu")
		(hatch none 0.5)
		(connect_pads
			(clearance 0)
		)
		(min_thickness 0.25)
		(keepout
			(tracks not_allowed)
			(vias allowed)
			(pads allowed)
			(copperpour not_allowed)
			(footprints allowed)
		)
		(placement
			(enabled no)
			(sheetname "")
		)
		(fill yes
			(thermal_gap 0.5)
			(thermal_bridge_width 0.5)
			(island_removal_mode 0)
		)
		(polygon
			(pts
				(arc
					(start 130.000248 -61.64199)
					(mid 129.641854 -62.000003)
					(end 129.999994 -62.35827)
				)
				(arc
					(start 130.999992 -62.35827)
					(mid 131.358132 -62.00013)
					(end 130.999992 -61.64199)
				)
			)
		)
	)
	(zone
		(layers "In1.Cu" "In3.Cu" "In4.Cu" "In6.Cu")
		(hatch none 0.5)
		(connect_pads
			(clearance 0)
		)
		(min_thickness 0.25)
		(keepout
			(tracks not_allowed)
			(vias allowed)
			(pads allowed)
			(copperpour not_allowed)
			(footprints allowed)
		)
		(placement
			(enabled no)
			(sheetname "")
		)
		(fill yes
			(thermal_gap 0.5)
			(thermal_bridge_width 0.5)
			(island_removal_mode 0)
		)
		(polygon
			(pts
				(arc
					(start 185.961274 -2.600198)
					(mid 185.399934 -2.038858)
					(end 184.838594 -2.600198)
				)
				(arc
					(start 184.838594 -3.999738)
					(mid 185.399807 -4.561332)
					(end 185.961274 -3.999992)
				)
			)
		)
	)
	(zone
		(layers "In1.Cu" "In3.Cu" "In4.Cu" "In6.Cu")
		(hatch none 0.5)
		(connect_pads
			(clearance 0)
		)
		(min_thickness 0.25)
		(keepout
			(tracks not_allowed)
			(vias allowed)
			(pads allowed)
			(copperpour not_allowed)
			(footprints allowed)
		)
		(placement
			(enabled no)
			(sheetname "")
		)
		(fill yes
			(thermal_gap 0.5)
			(thermal_bridge_width 0.5)
			(island_removal_mode 0)
		)
		(polygon
			(pts
				(arc
					(start 129.00025 -64.641984)
					(mid 128.641856 -64.999997)
					(end 128.999996 -65.358264)
				)
				(arc
					(start 129.999994 -65.358264)
					(mid 130.358134 -65.000124)
					(end 129.999994 -64.641984)
				)
			)
		)
	)
	(zone
		(layers "In1.Cu" "In3.Cu" "In4.Cu" "In6.Cu")
		(hatch none 0.5)
		(connect_pads
			(clearance 0)
		)
		(min_thickness 0.25)
		(keepout
			(tracks not_allowed)
			(vias allowed)
			(pads allowed)
			(copperpour not_allowed)
			(footprints allowed)
		)
		(placement
			(enabled no)
			(sheetname "")
		)
		(fill yes
			(thermal_gap 0.5)
			(thermal_bridge_width 0.5)
			(island_removal_mode 0)
		)
		(polygon
			(pts
				(arc
					(start 180.561234 -3.800094)
					(mid 179.999894 -3.238754)
					(end 179.438554 -3.800094)
				)
				(arc
					(start 179.438554 -5.199888)
					(mid 179.999767 -5.761482)
					(end 180.561234 -5.200142)
				)
			)
		)
	)
	(zone
		(layers "In1.Cu" "In3.Cu" "In4.Cu" "In6.Cu")
		(hatch none 0.5)
		(connect_pads
			(clearance 0)
		)
		(min_thickness 0.25)
		(keepout
			(tracks not_allowed)
			(vias allowed)
			(pads allowed)
			(copperpour not_allowed)
			(footprints allowed)
		)
		(placement
			(enabled no)
			(sheetname "")
		)
		(fill yes
			(thermal_gap 0.5)
			(thermal_bridge_width 0.5)
			(island_removal_mode 0)
		)
		(polygon
			(pts
				(arc
					(start 97.361502 -10.999978)
					(mid 96.800162 -10.438638)
					(end 96.238822 -10.999978)
				)
				(arc
					(start 96.238822 -12.399772)
					(mid 96.800035 -12.961366)
					(end 97.361502 -12.400026)
				)
			)
		)
	)
	(zone
		(layers "In1.Cu" "In3.Cu" "In4.Cu" "In6.Cu")
		(hatch none 0.5)
		(connect_pads
			(clearance 0)
		)
		(min_thickness 0.25)
		(keepout
			(tracks not_allowed)
			(vias allowed)
			(pads allowed)
			(copperpour not_allowed)
			(footprints allowed)
		)
		(placement
			(enabled no)
			(sheetname "")
		)
		(fill yes
			(thermal_gap 0.5)
			(thermal_bridge_width 0.5)
			(island_removal_mode 0)
		)
		(polygon
			(pts
				(arc
					(start 165.400228 -34.016442)
					(mid 165.016434 -34.399855)
					(end 165.399974 -34.783522)
				)
				(arc
					(start 166.19982 -34.783522)
					(mid 166.58336 -34.399982)
					(end 166.19982 -34.016442)
				)
			)
		)
	)
	(zone
		(layers "In1.Cu" "In3.Cu" "In4.Cu" "In6.Cu")
		(hatch none 0.5)
		(connect_pads
			(clearance 0)
		)
		(min_thickness 0.25)
		(keepout
			(tracks not_allowed)
			(vias allowed)
			(pads allowed)
			(copperpour not_allowed)
			(footprints allowed)
		)
		(placement
			(enabled no)
			(sheetname "")
		)
		(fill yes
			(thermal_gap 0.5)
			(thermal_bridge_width 0.5)
			(island_removal_mode 0)
		)
		(polygon
			(pts
				(arc
					(start 125.139958 -45.858938)
					(mid 124.682758 -45.401738)
					(end 124.225558 -45.858938)
				)
				(arc
					(start 124.225558 -47.001684)
					(mid 124.682631 -47.459138)
					(end 125.139958 -47.001938)
				)
			)
		)
	)
	(zone
		(layers "In1.Cu" "In3.Cu" "In4.Cu" "In6.Cu")
		(hatch none 0.5)
		(connect_pads
			(clearance 0)
		)
		(min_thickness 0.25)
		(keepout
			(tracks not_allowed)
			(vias allowed)
			(pads allowed)
			(copperpour not_allowed)
			(footprints allowed)
		)
		(placement
			(enabled no)
			(sheetname "")
		)
		(fill yes
			(thermal_gap 0.5)
			(thermal_bridge_width 0.5)
			(island_removal_mode 0)
		)
		(polygon
			(pts
				(arc
					(start 106.233722 -111.30915)
					(mid 106.009186 -110.566454)
					(end 105.26649 -110.79099)
				)
				(arc
					(start 104.516428 -112.190784)
					(mid 104.740809 -112.933787)
					(end 105.48366 -112.709198)
				)
			)
		)
	)
	(zone
		(layers "In1.Cu" "In3.Cu" "In4.Cu" "In6.Cu")
		(hatch none 0.5)
		(connect_pads
			(clearance 0)
		)
		(min_thickness 0.25)
		(keepout
			(tracks not_allowed)
			(vias allowed)
			(pads allowed)
			(copperpour not_allowed)
			(footprints allowed)
		)
		(placement
			(enabled no)
			(sheetname "")
		)
		(fill yes
			(thermal_gap 0.5)
			(thermal_bridge_width 0.5)
			(island_removal_mode 0)
		)
		(polygon
			(pts
				(arc
					(start 118.358158 -55.000144)
					(mid 118.000018 -54.642004)
					(end 117.641878 -55.000144)
				)
				(arc
					(start 117.641878 -55.999888)
					(mid 117.999891 -56.358282)
					(end 118.358158 -56.000142)
				)
			)
		)
	)
	(zone
		(layers "In1.Cu" "In3.Cu" "In4.Cu" "In6.Cu")
		(hatch none 0.5)
		(connect_pads
			(clearance 0)
		)
		(min_thickness 0.25)
		(keepout
			(tracks not_allowed)
			(vias allowed)
			(pads allowed)
			(copperpour not_allowed)
			(footprints allowed)
		)
		(placement
			(enabled no)
			(sheetname "")
		)
		(fill yes
			(thermal_gap 0.5)
			(thermal_bridge_width 0.5)
			(island_removal_mode 0)
		)
		(polygon
			(pts
				(arc
					(start 193.161158 -9.800082)
					(mid 192.599818 -9.238742)
					(end 192.038478 -9.800082)
				)
				(arc
					(start 192.038478 -11.199876)
					(mid 192.599691 -11.76147)
					(end 193.161158 -11.20013)
				)
			)
		)
	)
	(zone
		(layers "In1.Cu" "In3.Cu" "In4.Cu" "In6.Cu")
		(hatch none 0.5)
		(connect_pads
			(clearance 0)
		)
		(min_thickness 0.25)
		(keepout
			(tracks not_allowed)
			(vias allowed)
			(pads allowed)
			(copperpour not_allowed)
			(footprints allowed)
		)
		(placement
			(enabled no)
			(sheetname "")
		)
		(fill yes
			(thermal_gap 0.5)
			(thermal_bridge_width 0.5)
			(island_removal_mode 0)
		)
		(polygon
			(pts
				(arc
					(start 124.358146 -55.000144)
					(mid 124.000006 -54.642004)
					(end 123.641866 -55.000144)
				)
				(arc
					(start 123.641866 -55.999888)
					(mid 123.999879 -56.358282)
					(end 124.358146 -56.000142)
				)
			)
		)
	)
	(zone
		(layers "In1.Cu" "In3.Cu" "In4.Cu" "In6.Cu")
		(hatch none 0.5)
		(connect_pads
			(clearance 0)
		)
		(min_thickness 0.25)
		(keepout
			(tracks not_allowed)
			(vias allowed)
			(pads allowed)
			(copperpour not_allowed)
			(footprints allowed)
		)
		(placement
			(enabled no)
			(sheetname "")
		)
		(fill yes
			(thermal_gap 0.5)
			(thermal_bridge_width 0.5)
			(island_removal_mode 0)
		)
		(polygon
			(pts
				(arc
					(start 130.000248 -65.641982)
					(mid 129.641854 -65.999995)
					(end 129.999994 -66.358262)
				)
				(arc
					(start 130.999992 -66.358262)
					(mid 131.358132 -66.000122)
					(end 130.999992 -65.641982)
				)
			)
		)
	)
	(zone
		(layers "In1.Cu" "In3.Cu" "In4.Cu" "In6.Cu")
		(hatch none 0.5)
		(connect_pads
			(clearance 0)
		)
		(min_thickness 0.25)
		(keepout
			(tracks not_allowed)
			(vias allowed)
			(pads allowed)
			(copperpour not_allowed)
			(footprints allowed)
		)
		(placement
			(enabled no)
			(sheetname "")
		)
		(fill yes
			(thermal_gap 0.5)
			(thermal_bridge_width 0.5)
			(island_removal_mode 0)
		)
		(polygon
			(pts
				(arc
					(start 149.561296 -2.600198)
					(mid 148.999956 -2.038858)
					(end 148.438616 -2.600198)
				)
				(arc
					(start 148.438616 -3.999738)
					(mid 148.999829 -4.561332)
					(end 149.561296 -3.999992)
				)
			)
		)
	)
	(zone
		(layers "In1.Cu" "In3.Cu" "In4.Cu" "In6.Cu")
		(hatch none 0.5)
		(connect_pads
			(clearance 0)
		)
		(min_thickness 0.25)
		(keepout
			(tracks not_allowed)
			(vias allowed)
			(pads allowed)
			(copperpour not_allowed)
			(footprints allowed)
		)
		(placement
			(enabled no)
			(sheetname "")
		)
		(fill yes
			(thermal_gap 0.5)
			(thermal_bridge_width 0.5)
			(island_removal_mode 0)
		)
		(polygon
			(pts
				(arc
					(start 123.358148 -51.000152)
					(mid 123.000008 -50.642012)
					(end 122.641868 -51.000152)
				)
				(arc
					(start 122.641868 -51.999896)
					(mid 122.999881 -52.35829)
					(end 123.358148 -52.00015)
				)
			)
		)
	)
	(zone
		(layers "In1.Cu" "In3.Cu" "In4.Cu" "In6.Cu")
		(hatch none 0.5)
		(connect_pads
			(clearance 0)
		)
		(min_thickness 0.25)
		(keepout
			(tracks not_allowed)
			(vias allowed)
			(pads allowed)
			(copperpour not_allowed)
			(footprints allowed)
		)
		(placement
			(enabled no)
			(sheetname "")
		)
		(fill yes
			(thermal_gap 0.5)
			(thermal_bridge_width 0.5)
			(island_removal_mode 0)
		)
		(polygon
			(pts
				(arc
					(start 147.907502 -51.437794)
					(mid 148.2598 -51.980084)
					(end 148.80209 -51.627786)
				)
				(arc
					(start 149.037294 -50.520092)
					(mid 148.69273 -49.968723)
					(end 148.145246 -50.319686)
				)
			)
		)
	)
	(zone
		(layers "In1.Cu" "In3.Cu" "In4.Cu" "In6.Cu")
		(hatch none 0.5)
		(connect_pads
			(clearance 0)
		)
		(min_thickness 0.25)
		(keepout
			(tracks not_allowed)
			(vias allowed)
			(pads allowed)
			(copperpour not_allowed)
			(footprints allowed)
		)
		(placement
			(enabled no)
			(sheetname "")
		)
		(fill yes
			(thermal_gap 0.5)
			(thermal_bridge_width 0.5)
			(island_removal_mode 0)
		)
		(polygon
			(pts
				(arc
					(start 140.561314 -10.999978)
					(mid 139.999974 -10.438638)
					(end 139.438634 -10.999978)
				)
				(arc
					(start 139.438634 -12.399772)
					(mid 139.999847 -12.961366)
					(end 140.561314 -12.400026)
				)
			)
		)
	)
	(zone
		(layers "In1.Cu" "In3.Cu" "In4.Cu" "In6.Cu")
		(hatch none 0.5)
		(connect_pads
			(clearance 0)
		)
		(min_thickness 0.25)
		(keepout
			(tracks not_allowed)
			(vias allowed)
			(pads allowed)
			(copperpour not_allowed)
			(footprints allowed)
		)
		(placement
			(enabled no)
			(sheetname "")
		)
		(fill yes
			(thermal_gap 0.5)
			(thermal_bridge_width 0.5)
			(island_removal_mode 0)
		)
		(polygon
			(pts
				(arc
					(start 95.561404 -2.600198)
					(mid 95.000064 -2.038858)
					(end 94.438724 -2.600198)
				)
				(arc
					(start 94.438724 -3.999738)
					(mid 94.999937 -4.561332)
					(end 95.561404 -3.999992)
				)
			)
		)
	)
	(zone
		(layers "In1.Cu" "In3.Cu" "In4.Cu" "In6.Cu")
		(hatch none 0.5)
		(connect_pads
			(clearance 0)
		)
		(min_thickness 0.25)
		(keepout
			(tracks not_allowed)
			(vias allowed)
			(pads allowed)
			(copperpour not_allowed)
			(footprints allowed)
		)
		(placement
			(enabled no)
			(sheetname "")
		)
		(fill yes
			(thermal_gap 0.5)
			(thermal_bridge_width 0.5)
			(island_removal_mode 0)
		)
		(polygon
			(pts
				(arc
					(start 130.000248 -70.641972)
					(mid 129.641854 -70.999985)
					(end 129.999994 -71.358252)
				)
				(arc
					(start 130.999992 -71.358252)
					(mid 131.358132 -71.000112)
					(end 130.999992 -70.641972)
				)
			)
		)
	)
	(zone
		(layers "In1.Cu" "In3.Cu" "In4.Cu" "In6.Cu")
		(hatch none 0.5)
		(connect_pads
			(clearance 0)
		)
		(min_thickness 0.25)
		(keepout
			(tracks not_allowed)
			(vias allowed)
			(pads allowed)
			(copperpour not_allowed)
			(footprints allowed)
		)
		(placement
			(enabled no)
			(sheetname "")
		)
		(fill yes
			(thermal_gap 0.5)
			(thermal_bridge_width 0.5)
			(island_removal_mode 0)
		)
		(polygon
			(pts
				(arc
					(start 100.961444 -10.999978)
					(mid 100.400104 -10.438638)
					(end 99.838764 -10.999978)
				)
				(arc
					(start 99.838764 -12.399772)
					(mid 100.399977 -12.961366)
					(end 100.961444 -12.400026)
				)
			)
		)
	)
	(zone
		(layers "In1.Cu" "In3.Cu" "In4.Cu" "In6.Cu")
		(hatch none 0.5)
		(connect_pads
			(clearance 0)
		)
		(min_thickness 0.25)
		(keepout
			(tracks not_allowed)
			(vias allowed)
			(pads allowed)
			(copperpour not_allowed)
			(footprints allowed)
		)
		(placement
			(enabled no)
			(sheetname "")
		)
		(fill yes
			(thermal_gap 0.5)
			(thermal_bridge_width 0.5)
			(island_removal_mode 0)
		)
		(polygon
			(pts
				(arc
					(start 129.00025 -62.641988)
					(mid 128.641856 -63.000001)
					(end 128.999996 -63.358268)
				)
				(arc
					(start 129.999994 -63.358268)
					(mid 130.358134 -63.000128)
					(end 129.999994 -62.641988)
				)
			)
		)
	)
	(zone
		(layers "In1.Cu" "In3.Cu" "In4.Cu" "In6.Cu")
		(hatch none 0.5)
		(connect_pads
			(clearance 0)
		)
		(min_thickness 0.25)
		(keepout
			(tracks not_allowed)
			(vias allowed)
			(pads allowed)
			(copperpour not_allowed)
			(footprints allowed)
		)
		(placement
			(enabled no)
			(sheetname "")
		)
		(fill yes
			(thermal_gap 0.5)
			(thermal_bridge_width 0.5)
			(island_removal_mode 0)
		)
		(polygon
			(pts
				(arc
					(start 145.839434 -33.377886)
					(mid 146.191732 -33.920176)
					(end 146.734022 -33.567878)
				)
				(arc
					(start 146.969226 -32.460184)
					(mid 146.624662 -31.908815)
					(end 146.077178 -32.259778)
				)
			)
		)
	)
	(zone
		(layers "In1.Cu" "In3.Cu" "In4.Cu" "In6.Cu")
		(hatch none 0.5)
		(connect_pads
			(clearance 0)
		)
		(min_thickness 0.25)
		(keepout
			(tracks not_allowed)
			(vias allowed)
			(pads allowed)
			(copperpour not_allowed)
			(footprints allowed)
		)
		(placement
			(enabled no)
			(sheetname "")
		)
		(fill yes
			(thermal_gap 0.5)
			(thermal_bridge_width 0.5)
			(island_removal_mode 0)
		)
		(polygon
			(pts
				(arc
					(start 140.561314 -3.800094)
					(mid 139.999974 -3.238754)
					(end 139.438634 -3.800094)
				)
				(arc
					(start 139.438634 -5.199888)
					(mid 139.999847 -5.761482)
					(end 140.561314 -5.200142)
				)
			)
		)
	)
	(zone
		(layers "In1.Cu" "In3.Cu" "In4.Cu" "In6.Cu")
		(hatch none 0.5)
		(connect_pads
			(clearance 0)
		)
		(min_thickness 0.25)
		(keepout
			(tracks not_allowed)
			(vias allowed)
			(pads allowed)
			(copperpour not_allowed)
			(footprints allowed)
		)
		(placement
			(enabled no)
			(sheetname "")
		)
		(fill yes
			(thermal_gap 0.5)
			(thermal_bridge_width 0.5)
			(island_removal_mode 0)
		)
		(polygon
			(pts
				(arc
					(start 122.35815 -52.00015)
					(mid 122.00001 -51.64201)
					(end 121.64187 -52.00015)
				)
				(arc
					(start 121.64187 -52.999894)
					(mid 121.999883 -53.358288)
					(end 122.35815 -53.000148)
				)
			)
		)
	)
	(zone
		(layers "In1.Cu" "In3.Cu" "In4.Cu" "In6.Cu")
		(hatch none 0.5)
		(connect_pads
			(clearance 0)
		)
		(min_thickness 0.25)
		(keepout
			(tracks not_allowed)
			(vias allowed)
			(pads allowed)
			(copperpour not_allowed)
			(footprints allowed)
		)
		(placement
			(enabled no)
			(sheetname "")
		)
		(fill yes
			(thermal_gap 0.5)
			(thermal_bridge_width 0.5)
			(island_removal_mode 0)
		)
		(polygon
			(pts
				(arc
					(start 126.000256 -74.641964)
					(mid 125.641862 -74.999977)
					(end 126.000002 -75.358244)
				)
				(arc
					(start 127 -75.358244)
					(mid 127.35814 -75.000104)
					(end 127 -74.641964)
				)
			)
		)
	)
	(zone
		(layers "In1.Cu" "In3.Cu" "In4.Cu" "In6.Cu")
		(hatch none 0.5)
		(connect_pads
			(clearance 0)
		)
		(min_thickness 0.25)
		(keepout
			(tracks not_allowed)
			(vias allowed)
			(pads allowed)
			(copperpour not_allowed)
			(footprints allowed)
		)
		(placement
			(enabled no)
			(sheetname "")
		)
		(fill yes
			(thermal_gap 0.5)
			(thermal_bridge_width 0.5)
			(island_removal_mode 0)
		)
		(polygon
			(pts
				(arc
					(start 149.561296 -9.800082)
					(mid 148.999956 -9.238742)
					(end 148.438616 -9.800082)
				)
				(arc
					(start 148.438616 -11.199876)
					(mid 148.999829 -11.76147)
					(end 149.561296 -11.20013)
				)
			)
		)
	)
	(zone
		(layers "In1.Cu" "In3.Cu" "In4.Cu" "In6.Cu")
		(hatch none 0.5)
		(connect_pads
			(clearance 0)
		)
		(min_thickness 0.25)
		(keepout
			(tracks not_allowed)
			(vias allowed)
			(pads allowed)
			(copperpour not_allowed)
			(footprints allowed)
		)
		(placement
			(enabled no)
			(sheetname "")
		)
		(fill yes
			(thermal_gap 0.5)
			(thermal_bridge_width 0.5)
			(island_removal_mode 0)
		)
		(polygon
			(pts
				(arc
					(start 129.00025 -71.64197)
					(mid 128.641856 -71.999983)
					(end 128.999996 -72.35825)
				)
				(arc
					(start 129.999994 -72.35825)
					(mid 130.358134 -72.00011)
					(end 129.999994 -71.64197)
				)
			)
		)
	)
	(zone
		(layers "In1.Cu" "In3.Cu" "In4.Cu" "In6.Cu")
		(hatch none 0.5)
		(connect_pads
			(clearance 0)
		)
		(min_thickness 0.25)
		(keepout
			(tracks not_allowed)
			(vias allowed)
			(pads allowed)
			(copperpour not_allowed)
			(footprints allowed)
		)
		(placement
			(enabled no)
			(sheetname "")
		)
		(fill yes
			(thermal_gap 0.5)
			(thermal_bridge_width 0.5)
			(island_removal_mode 0)
		)
		(polygon
			(pts
				(arc
					(start 166.999412 -29.983684)
					(mid 167.383206 -29.600271)
					(end 166.999666 -29.216604)
				)
				(arc
					(start 166.200074 -29.21635)
					(mid 165.81628 -29.599763)
					(end 166.19982 -29.98343)
				)
			)
		)
	)
	(zone
		(layers "In1.Cu" "In3.Cu" "In4.Cu" "In6.Cu")
		(hatch none 0.5)
		(connect_pads
			(clearance 0)
		)
		(min_thickness 0.25)
		(keepout
			(tracks not_allowed)
			(vias allowed)
			(pads allowed)
			(copperpour not_allowed)
			(footprints allowed)
		)
		(placement
			(enabled no)
			(sheetname "")
		)
		(fill yes
			(thermal_gap 0.5)
			(thermal_bridge_width 0.5)
			(island_removal_mode 0)
		)
		(polygon
			(pts
				(arc
					(start 124.361448 -9.800082)
					(mid 123.800108 -9.238742)
					(end 123.238768 -9.800082)
				)
				(arc
					(start 123.238768 -11.199876)
					(mid 123.799981 -11.76147)
					(end 124.361448 -11.20013)
				)
			)
		)
	)
	(zone
		(layers "In1.Cu" "In3.Cu" "In4.Cu" "In6.Cu")
		(hatch none 0.5)
		(connect_pads
			(clearance 0)
		)
		(min_thickness 0.25)
		(keepout
			(tracks not_allowed)
			(vias allowed)
			(pads allowed)
			(copperpour not_allowed)
			(footprints allowed)
		)
		(placement
			(enabled no)
			(sheetname "")
		)
		(fill yes
			(thermal_gap 0.5)
			(thermal_bridge_width 0.5)
			(island_removal_mode 0)
		)
		(polygon
			(pts
				(arc
					(start 127.96139 -2.600198)
					(mid 127.40005 -2.038858)
					(end 126.83871 -2.600198)
				)
				(arc
					(start 126.83871 -3.999738)
					(mid 127.399923 -4.561332)
					(end 127.96139 -3.999992)
				)
			)
		)
	)
	(zone
		(layers "In1.Cu" "In3.Cu" "In4.Cu" "In6.Cu")
		(hatch none 0.5)
		(connect_pads
			(clearance 0)
		)
		(min_thickness 0.25)
		(keepout
			(tracks not_allowed)
			(vias allowed)
			(pads allowed)
			(copperpour not_allowed)
			(footprints allowed)
		)
		(placement
			(enabled no)
			(sheetname "")
		)
		(fill yes
			(thermal_gap 0.5)
			(thermal_bridge_width 0.5)
			(island_removal_mode 0)
		)
		(polygon
			(pts
				(arc
					(start 113.358168 -55.000144)
					(mid 113.000028 -54.642004)
					(end 112.641888 -55.000144)
				)
				(arc
					(start 112.641888 -55.999888)
					(mid 112.999901 -56.358282)
					(end 113.358168 -56.000142)
				)
			)
		)
	)
	(zone
		(layers "In1.Cu" "In3.Cu" "In4.Cu" "In6.Cu")
		(hatch none 0.5)
		(connect_pads
			(clearance 0)
		)
		(min_thickness 0.25)
		(keepout
			(tracks not_allowed)
			(vias allowed)
			(pads allowed)
			(copperpour not_allowed)
			(footprints allowed)
		)
		(placement
			(enabled no)
			(sheetname "")
		)
		(fill yes
			(thermal_gap 0.5)
			(thermal_bridge_width 0.5)
			(island_removal_mode 0)
		)
		(polygon
			(pts
				(arc
					(start 173.042072 -31.199836)
					(mid 173.400212 -31.55823)
					(end 173.758352 -31.199836)
				)
				(arc
					(start 173.758098 -30.39999)
					(mid 173.399831 -30.04185)
					(end 173.041818 -30.400244)
				)
			)
		)
	)
	(zone
		(layers "In1.Cu" "In3.Cu" "In4.Cu" "In6.Cu")
		(hatch none 0.5)
		(connect_pads
			(clearance 0)
		)
		(min_thickness 0.25)
		(keepout
			(tracks not_allowed)
			(vias allowed)
			(pads allowed)
			(copperpour not_allowed)
			(footprints allowed)
		)
		(placement
			(enabled no)
			(sheetname "")
		)
		(fill yes
			(thermal_gap 0.5)
			(thermal_bridge_width 0.5)
			(island_removal_mode 0)
		)
		(polygon
			(pts
				(arc
					(start 116.358162 -52.00015)
					(mid 116.000022 -51.64201)
					(end 115.641882 -52.00015)
				)
				(arc
					(start 115.641882 -52.999894)
					(mid 115.999895 -53.358288)
					(end 116.358162 -53.000148)
				)
			)
		)
	)
	(zone
		(layers "In1.Cu" "In3.Cu" "In4.Cu" "In6.Cu")
		(hatch none 0.5)
		(connect_pads
			(clearance 0)
		)
		(min_thickness 0.25)
		(keepout
			(tracks not_allowed)
			(vias allowed)
			(pads allowed)
			(copperpour not_allowed)
			(footprints allowed)
		)
		(placement
			(enabled no)
			(sheetname "")
		)
		(fill yes
			(thermal_gap 0.5)
			(thermal_bridge_width 0.5)
			(island_removal_mode 0)
		)
		(polygon
			(pts
				(arc
					(start 187.761118 -10.999978)
					(mid 187.199778 -10.438638)
					(end 186.638438 -10.999978)
				)
				(arc
					(start 186.638438 -12.399772)
					(mid 187.199651 -12.961366)
					(end 187.761118 -12.400026)
				)
			)
		)
	)
	(zone
		(layers "In1.Cu" "In3.Cu" "In4.Cu" "In6.Cu")
		(hatch none 0.5)
		(connect_pads
			(clearance 0)
		)
		(min_thickness 0.25)
		(keepout
			(tracks not_allowed)
			(vias allowed)
			(pads allowed)
			(copperpour not_allowed)
			(footprints allowed)
		)
		(placement
			(enabled no)
			(sheetname "")
		)
		(fill yes
			(thermal_gap 0.5)
			(thermal_bridge_width 0.5)
			(island_removal_mode 0)
		)
		(polygon
			(pts
				(arc
					(start 109.358176 -52.00015)
					(mid 109.000036 -51.64201)
					(end 108.641896 -52.00015)
				)
				(arc
					(start 108.641896 -52.999894)
					(mid 108.999909 -53.358288)
					(end 109.358176 -53.000148)
				)
			)
		)
	)
	(zone
		(layers "In1.Cu" "In3.Cu" "In4.Cu" "In6.Cu")
		(hatch none 0.5)
		(connect_pads
			(clearance 0)
		)
		(min_thickness 0.25)
		(keepout
			(tracks not_allowed)
			(vias allowed)
			(pads allowed)
			(copperpour not_allowed)
			(footprints allowed)
		)
		(placement
			(enabled no)
			(sheetname "")
		)
		(fill yes
			(thermal_gap 0.5)
			(thermal_bridge_width 0.5)
			(island_removal_mode 0)
		)
		(polygon
			(pts
				(arc
					(start 184.161176 -3.800094)
					(mid 183.599836 -3.238754)
					(end 183.038496 -3.800094)
				)
				(arc
					(start 183.038496 -5.199888)
					(mid 183.599709 -5.761482)
					(end 184.161176 -5.200142)
				)
			)
		)
	)
	(zone
		(layers "In1.Cu" "In3.Cu" "In4.Cu" "In6.Cu")
		(hatch none 0.5)
		(connect_pads
			(clearance 0)
		)
		(min_thickness 0.25)
		(keepout
			(tracks not_allowed)
			(vias allowed)
			(pads allowed)
			(copperpour not_allowed)
			(footprints allowed)
		)
		(placement
			(enabled no)
			(sheetname "")
		)
		(fill yes
			(thermal_gap 0.5)
			(thermal_bridge_width 0.5)
			(island_removal_mode 0)
		)
		(polygon
			(pts
				(arc
					(start 105.358184 -55.000144)
					(mid 105.000044 -54.642004)
					(end 104.641904 -55.000144)
				)
				(arc
					(start 104.641904 -55.999888)
					(mid 104.999917 -56.358282)
					(end 105.358184 -56.000142)
				)
			)
		)
	)
	(zone
		(layers "In1.Cu" "In3.Cu" "In4.Cu" "In6.Cu")
		(hatch none 0.5)
		(connect_pads
			(clearance 0)
		)
		(min_thickness 0.25)
		(keepout
			(tracks not_allowed)
			(vias allowed)
			(pads allowed)
			(copperpour not_allowed)
			(footprints allowed)
		)
		(placement
			(enabled no)
			(sheetname "")
		)
		(fill yes
			(thermal_gap 0.5)
			(thermal_bridge_width 0.5)
			(island_removal_mode 0)
		)
		(polygon
			(pts
				(arc
					(start 126.000256 -58.641996)
					(mid 125.641862 -59.000009)
					(end 126.000002 -59.358276)
				)
				(arc
					(start 127 -59.358276)
					(mid 127.35814 -59.000136)
					(end 127 -58.641996)
				)
			)
		)
	)
	(zone
		(layers "In1.Cu" "In3.Cu" "In4.Cu" "In6.Cu")
		(hatch none 0.5)
		(connect_pads
			(clearance 0)
		)
		(min_thickness 0.25)
		(keepout
			(tracks not_allowed)
			(vias allowed)
			(pads allowed)
			(copperpour not_allowed)
			(footprints allowed)
		)
		(placement
			(enabled no)
			(sheetname "")
		)
		(fill yes
			(thermal_gap 0.5)
			(thermal_bridge_width 0.5)
			(island_removal_mode 0)
		)
		(polygon
			(pts
				(arc
					(start 111.761524 -10.999978)
					(mid 111.200184 -10.438638)
					(end 110.638844 -10.999978)
				)
				(arc
					(start 110.638844 -12.399772)
					(mid 111.200057 -12.961366)
					(end 111.761524 -12.400026)
				)
			)
		)
	)
	(zone
		(layers "In1.Cu" "In3.Cu" "In4.Cu" "In6.Cu")
		(hatch none 0.5)
		(connect_pads
			(clearance 0)
		)
		(min_thickness 0.25)
		(keepout
			(tracks not_allowed)
			(vias allowed)
			(pads allowed)
			(copperpour not_allowed)
			(footprints allowed)
		)
		(placement
			(enabled no)
			(sheetname "")
		)
		(fill yes
			(thermal_gap 0.5)
			(thermal_bridge_width 0.5)
			(island_removal_mode 0)
		)
		(polygon
			(pts
				(arc
					(start 191.361314 -10.999978)
					(mid 190.799974 -10.438638)
					(end 190.238634 -10.999978)
				)
				(arc
					(start 190.238634 -12.399772)
					(mid 190.799847 -12.961366)
					(end 191.361314 -12.400026)
				)
			)
		)
	)
	(zone
		(layers "In1.Cu" "In3.Cu" "In4.Cu" "In6.Cu")
		(hatch none 0.5)
		(connect_pads
			(clearance 0)
		)
		(min_thickness 0.25)
		(keepout
			(tracks not_allowed)
			(vias allowed)
			(pads allowed)
			(copperpour not_allowed)
			(footprints allowed)
		)
		(placement
			(enabled no)
			(sheetname "")
		)
		(fill yes
			(thermal_gap 0.5)
			(thermal_bridge_width 0.5)
			(island_removal_mode 0)
		)
		(polygon
			(pts
				(arc
					(start 178.790854 -23.11654)
					(mid 178.407314 -22.733)
					(end 178.023774 -23.11654)
				)
				(arc
					(start 178.023774 -24.005286)
					(mid 178.407187 -24.38908)
					(end 178.790854 -24.00554)
				)
			)
		)
	)
	(zone
		(layers "In1.Cu" "In3.Cu" "In4.Cu" "In6.Cu")
		(hatch none 0.5)
		(connect_pads
			(clearance 0)
		)
		(min_thickness 0.25)
		(keepout
			(tracks not_allowed)
			(vias allowed)
			(pads allowed)
			(copperpour not_allowed)
			(footprints allowed)
		)
		(placement
			(enabled no)
			(sheetname "")
		)
		(fill yes
			(thermal_gap 0.5)
			(thermal_bridge_width 0.5)
			(island_removal_mode 0)
		)
		(polygon
			(pts
				(arc
					(start 145.961354 -9.800082)
					(mid 145.400014 -9.238742)
					(end 144.838674 -9.800082)
				)
				(arc
					(start 144.838674 -11.199876)
					(mid 145.399887 -11.76147)
					(end 145.961354 -11.20013)
				)
			)
		)
	)
	(zone
		(layers "In1.Cu" "In3.Cu" "In4.Cu" "In6.Cu")
		(hatch none 0.5)
		(connect_pads
			(clearance 0)
		)
		(min_thickness 0.25)
		(keepout
			(tracks not_allowed)
			(vias allowed)
			(pads allowed)
			(copperpour not_allowed)
			(footprints allowed)
		)
		(placement
			(enabled no)
			(sheetname "")
		)
		(fill yes
			(thermal_gap 0.5)
			(thermal_bridge_width 0.5)
			(island_removal_mode 0)
		)
		(polygon
			(pts
				(arc
					(start 189.561216 -9.800082)
					(mid 188.999876 -9.238742)
					(end 188.438536 -9.800082)
				)
				(arc
					(start 188.438536 -11.199876)
					(mid 188.999749 -11.76147)
					(end 189.561216 -11.20013)
				)
			)
		)
	)
	(zone
		(layers "In1.Cu" "In3.Cu" "In4.Cu" "In6.Cu")
		(hatch none 0.5)
		(connect_pads
			(clearance 0)
		)
		(min_thickness 0.25)
		(keepout
			(tracks not_allowed)
			(vias allowed)
			(pads allowed)
			(copperpour not_allowed)
			(footprints allowed)
		)
		(placement
			(enabled no)
			(sheetname "")
		)
		(fill yes
			(thermal_gap 0.5)
			(thermal_bridge_width 0.5)
			(island_removal_mode 0)
		)
		(polygon
			(pts
				(arc
					(start 106.361484 -2.600198)
					(mid 105.800144 -2.038858)
					(end 105.238804 -2.600198)
				)
				(arc
					(start 105.238804 -3.999738)
					(mid 105.800017 -4.561332)
					(end 106.361484 -3.999992)
				)
			)
		)
	)
	(zone
		(layers "In1.Cu" "In3.Cu" "In4.Cu" "In6.Cu")
		(hatch none 0.5)
		(connect_pads
			(clearance 0)
		)
		(min_thickness 0.25)
		(keepout
			(tracks not_allowed)
			(vias allowed)
			(pads allowed)
			(copperpour not_allowed)
			(footprints allowed)
		)
		(placement
			(enabled no)
			(sheetname "")
		)
		(fill yes
			(thermal_gap 0.5)
			(thermal_bridge_width 0.5)
			(island_removal_mode 0)
		)
		(polygon
			(pts
				(arc
					(start 126.000256 -75.641962)
					(mid 125.641862 -75.999975)
					(end 126.000002 -76.358242)
				)
				(arc
					(start 127 -76.358242)
					(mid 127.35814 -76.000102)
					(end 127 -75.641962)
				)
			)
		)
	)
	(zone
		(layers "In1.Cu" "In3.Cu" "In4.Cu" "In6.Cu")
		(hatch none 0.5)
		(connect_pads
			(clearance 0)
		)
		(min_thickness 0.25)
		(keepout
			(tracks not_allowed)
			(vias allowed)
			(pads allowed)
			(copperpour not_allowed)
			(footprints allowed)
		)
		(placement
			(enabled no)
			(sheetname "")
		)
		(fill yes
			(thermal_gap 0.5)
			(thermal_bridge_width 0.5)
			(island_removal_mode 0)
		)
		(polygon
			(pts
				(arc
					(start 145.961354 -2.600198)
					(mid 145.400014 -2.038858)
					(end 144.838674 -2.600198)
				)
				(arc
					(start 144.838674 -3.999738)
					(mid 145.399887 -4.561332)
					(end 145.961354 -3.999992)
				)
			)
		)
	)
	(zone
		(layers "In1.Cu" "In3.Cu" "In4.Cu" "In6.Cu")
		(hatch none 0.5)
		(connect_pads
			(clearance 0)
		)
		(min_thickness 0.25)
		(keepout
			(tracks not_allowed)
			(vias allowed)
			(pads allowed)
			(copperpour not_allowed)
			(footprints allowed)
		)
		(placement
			(enabled no)
			(sheetname "")
		)
		(fill yes
			(thermal_gap 0.5)
			(thermal_bridge_width 0.5)
			(island_removal_mode 0)
		)
		(polygon
			(pts
				(arc
					(start 176.158144 -30.400244)
					(mid 175.800004 -30.042104)
					(end 175.441864 -30.400244)
				)
				(arc
					(start 175.441864 -31.199836)
					(mid 175.799877 -31.55823)
					(end 176.158144 -31.20009)
				)
			)
		)
	)
	(zone
		(layers "In1.Cu" "In3.Cu" "In4.Cu" "In6.Cu")
		(hatch none 0.5)
		(connect_pads
			(clearance 0)
		)
		(min_thickness 0.25)
		(keepout
			(tracks not_allowed)
			(vias allowed)
			(pads allowed)
			(copperpour not_allowed)
			(footprints allowed)
		)
		(placement
			(enabled no)
			(sheetname "")
		)
		(fill yes
			(thermal_gap 0.5)
			(thermal_bridge_width 0.5)
			(island_removal_mode 0)
		)
		(polygon
			(pts
				(arc
					(start 148.684742 -36.130992)
					(mid 149.03704 -36.673282)
					(end 149.57933 -36.320984)
				)
				(arc
					(start 149.814534 -35.21329)
					(mid 149.46997 -34.661921)
					(end 148.922486 -35.012884)
				)
			)
		)
	)
	(zone
		(layers "In1.Cu" "In3.Cu" "In4.Cu" "In6.Cu")
		(hatch none 0.5)
		(connect_pads
			(clearance 0)
		)
		(min_thickness 0.25)
		(keepout
			(tracks not_allowed)
			(vias allowed)
			(pads allowed)
			(copperpour not_allowed)
			(footprints allowed)
		)
		(placement
			(enabled no)
			(sheetname "")
		)
		(fill yes
			(thermal_gap 0.5)
			(thermal_bridge_width 0.5)
			(island_removal_mode 0)
		)
		(polygon
			(pts
				(arc
					(start 99.161346 -9.800082)
					(mid 98.600006 -9.238742)
					(end 98.038666 -9.800082)
				)
				(arc
					(start 98.038666 -11.199876)
					(mid 98.599879 -11.76147)
					(end 99.161346 -11.20013)
				)
			)
		)
	)
	(zone
		(layers "In1.Cu" "In3.Cu" "In4.Cu" "In6.Cu")
		(hatch none 0.5)
		(connect_pads
			(clearance 0)
		)
		(min_thickness 0.25)
		(keepout
			(tracks not_allowed)
			(vias allowed)
			(pads allowed)
			(copperpour not_allowed)
			(footprints allowed)
		)
		(placement
			(enabled no)
			(sheetname "")
		)
		(fill yes
			(thermal_gap 0.5)
			(thermal_bridge_width 0.5)
			(island_removal_mode 0)
		)
		(polygon
			(pts
				(arc
					(start 90.161364 -10.999978)
					(mid 89.600024 -10.438638)
					(end 89.038684 -10.999978)
				)
				(arc
					(start 89.038684 -12.399772)
					(mid 89.599897 -12.961366)
					(end 90.161364 -12.400026)
				)
			)
		)
	)
	(zone
		(layers "In1.Cu" "In3.Cu" "In4.Cu" "In6.Cu")
		(hatch none 0.5)
		(connect_pads
			(clearance 0)
		)
		(min_thickness 0.25)
		(keepout
			(tracks not_allowed)
			(vias allowed)
			(pads allowed)
			(copperpour not_allowed)
			(footprints allowed)
		)
		(placement
			(enabled no)
			(sheetname "")
		)
		(fill yes
			(thermal_gap 0.5)
			(thermal_bridge_width 0.5)
			(island_removal_mode 0)
		)
		(polygon
			(pts
				(xy 138.479276 -76.14158) (xy 138.479022 -76.141834)
				(arc
					(start 138.479022 -76.142342)
					(mid 138.096244 -76.52512)
					(end 138.479022 -76.907898)
				)
				(xy 138.479022 -76.90866) (xy 139.622022 -76.90866)
				(arc
					(start 139.622022 -76.907898)
					(mid 140.0048 -76.52512)
					(end 139.622022 -76.142342)
				)
				(xy 139.622022 -76.14158)
			)
		)
	)
	(zone
		(layers "In1.Cu" "In3.Cu" "In4.Cu" "In6.Cu")
		(hatch none 0.5)
		(connect_pads
			(clearance 0)
		)
		(min_thickness 0.25)
		(keepout
			(tracks not_allowed)
			(vias allowed)
			(pads allowed)
			(copperpour not_allowed)
			(footprints allowed)
		)
		(placement
			(enabled no)
			(sheetname "")
		)
		(fill yes
			(thermal_gap 0.5)
			(thermal_bridge_width 0.5)
			(island_removal_mode 0)
		)
		(polygon
			(pts
				(xy 138.500866 -79.813912) (xy 138.500612 -79.814166)
				(arc
					(start 138.500612 -79.814674)
					(mid 138.117834 -80.197452)
					(end 138.500612 -80.58023)
				)
				(xy 138.500612 -80.580992) (xy 139.643612 -80.580992)
				(arc
					(start 139.643612 -80.58023)
					(mid 140.02639 -80.197452)
					(end 139.643612 -79.814674)
				)
				(xy 139.643612 -79.813912)
			)
		)
	)
	(zone
		(layers "In1.Cu" "In3.Cu" "In4.Cu" "In6.Cu")
		(hatch none 0.5)
		(connect_pads
			(clearance 0)
		)
		(min_thickness 0.25)
		(keepout
			(tracks not_allowed)
			(vias allowed)
			(pads allowed)
			(copperpour not_allowed)
			(footprints allowed)
		)
		(placement
			(enabled no)
			(sheetname "")
		)
		(fill yes
			(thermal_gap 0.5)
			(thermal_bridge_width 0.5)
			(island_removal_mode 0)
		)
		(polygon
			(pts
				(arc
					(start 133.36143 -10.999978)
					(mid 132.80009 -10.438638)
					(end 132.23875 -10.999978)
				)
				(arc
					(start 132.23875 -12.399772)
					(mid 132.799963 -12.961366)
					(end 133.36143 -12.400026)
				)
			)
		)
	)
	(zone
		(layers "In1.Cu" "In3.Cu" "In4.Cu" "In6.Cu")
		(hatch none 0.5)
		(connect_pads
			(clearance 0)
		)
		(min_thickness 0.25)
		(keepout
			(tracks not_allowed)
			(vias allowed)
			(pads allowed)
			(copperpour not_allowed)
			(footprints allowed)
		)
		(placement
			(enabled no)
			(sheetname "")
		)
		(fill yes
			(thermal_gap 0.5)
			(thermal_bridge_width 0.5)
			(island_removal_mode 0)
		)
		(polygon
			(pts
				(arc
					(start 109.961426 -9.800082)
					(mid 109.400086 -9.238742)
					(end 108.838746 -9.800082)
				)
				(arc
					(start 108.838746 -11.199876)
					(mid 109.399959 -11.76147)
					(end 109.961426 -11.20013)
				)
			)
		)
	)
	(zone
		(layers "In1.Cu" "In3.Cu" "In4.Cu" "In6.Cu")
		(hatch none 0.5)
		(connect_pads
			(clearance 0)
		)
		(min_thickness 0.25)
		(keepout
			(tracks not_allowed)
			(vias allowed)
			(pads allowed)
			(copperpour not_allowed)
			(footprints allowed)
		)
		(placement
			(enabled no)
			(sheetname "")
		)
		(fill yes
			(thermal_gap 0.5)
			(thermal_bridge_width 0.5)
			(island_removal_mode 0)
		)
		(polygon
			(pts
				(arc
					(start 165.400228 -36.416488)
					(mid 165.016434 -36.799901)
					(end 165.399974 -37.183568)
				)
				(arc
					(start 166.19982 -37.183568)
					(mid 166.58336 -36.800028)
					(end 166.19982 -36.416488)
				)
			)
		)
	)
	(zone
		(layers "In1.Cu" "In3.Cu" "In4.Cu" "In6.Cu")
		(hatch none 0.5)
		(connect_pads
			(clearance 0)
		)
		(min_thickness 0.25)
		(keepout
			(tracks not_allowed)
			(vias allowed)
			(pads allowed)
			(copperpour not_allowed)
			(footprints allowed)
		)
		(placement
			(enabled no)
			(sheetname "")
		)
		(fill yes
			(thermal_gap 0.5)
			(thermal_bridge_width 0.5)
			(island_removal_mode 0)
		)
		(polygon
			(pts
				(arc
					(start 170.642026 -31.199836)
					(mid 171.000166 -31.55823)
					(end 171.358306 -31.199836)
				)
				(arc
					(start 171.358052 -30.39999)
					(mid 170.999785 -30.04185)
					(end 170.641772 -30.400244)
				)
			)
		)
	)
	(zone
		(layers "In1.Cu" "In3.Cu" "In4.Cu" "In6.Cu")
		(hatch none 0.5)
		(connect_pads
			(clearance 0)
		)
		(min_thickness 0.25)
		(keepout
			(tracks not_allowed)
			(vias allowed)
			(pads allowed)
			(copperpour not_allowed)
			(footprints allowed)
		)
		(placement
			(enabled no)
			(sheetname "")
		)
		(fill yes
			(thermal_gap 0.5)
			(thermal_bridge_width 0.5)
			(island_removal_mode 0)
		)
		(polygon
			(pts
				(arc
					(start 101.358192 -55.000144)
					(mid 101.000052 -54.642004)
					(end 100.641912 -55.000144)
				)
				(arc
					(start 100.641912 -55.999888)
					(mid 100.999925 -56.358282)
					(end 101.358192 -56.000142)
				)
			)
		)
	)
	(zone
		(layers "In1.Cu" "In3.Cu" "In4.Cu" "In6.Cu")
		(hatch none 0.5)
		(connect_pads
			(clearance 0)
		)
		(min_thickness 0.25)
		(keepout
			(tracks not_allowed)
			(vias allowed)
			(pads allowed)
			(copperpour not_allowed)
			(footprints allowed)
		)
		(placement
			(enabled no)
			(sheetname "")
		)
		(fill yes
			(thermal_gap 0.5)
			(thermal_bridge_width 0.5)
			(island_removal_mode 0)
		)
		(polygon
			(pts
				(arc
					(start 93.761306 -3.800094)
					(mid 93.199966 -3.238754)
					(end 92.638626 -3.800094)
				)
				(arc
					(start 92.638626 -5.199888)
					(mid 93.199839 -5.761482)
					(end 93.761306 -5.200142)
				)
			)
		)
	)
	(zone
		(layers "In1.Cu" "In3.Cu" "In4.Cu" "In6.Cu")
		(hatch none 0.5)
		(connect_pads
			(clearance 0)
		)
		(min_thickness 0.25)
		(keepout
			(tracks not_allowed)
			(vias allowed)
			(pads allowed)
			(copperpour not_allowed)
			(footprints allowed)
		)
		(placement
			(enabled no)
			(sheetname "")
		)
		(fill yes
			(thermal_gap 0.5)
			(thermal_bridge_width 0.5)
			(island_removal_mode 0)
		)
		(polygon
			(pts
				(arc
					(start 122.35815 -55.000144)
					(mid 122.00001 -54.642004)
					(end 121.64187 -55.000144)
				)
				(arc
					(start 121.64187 -55.999888)
					(mid 121.999883 -56.358282)
					(end 122.35815 -56.000142)
				)
			)
		)
	)
	(zone
		(layers "In1.Cu" "In3.Cu" "In4.Cu" "In6.Cu")
		(hatch none 0.5)
		(connect_pads
			(clearance 0)
		)
		(min_thickness 0.25)
		(keepout
			(tracks not_allowed)
			(vias allowed)
			(pads allowed)
			(copperpour not_allowed)
			(footprints allowed)
		)
		(placement
			(enabled no)
			(sheetname "")
		)
		(fill yes
			(thermal_gap 0.5)
			(thermal_bridge_width 0.5)
			(island_removal_mode 0)
		)
		(polygon
			(pts
				(arc
					(start 142.361412 -2.600198)
					(mid 141.800072 -2.038858)
					(end 141.238732 -2.600198)
				)
				(arc
					(start 141.238732 -3.999738)
					(mid 141.799945 -4.561332)
					(end 142.361412 -3.999992)
				)
			)
		)
	)
	(zone
		(layers "In1.Cu" "In3.Cu" "In4.Cu" "In6.Cu")
		(hatch none 0.5)
		(connect_pads
			(clearance 0)
		)
		(min_thickness 0.25)
		(keepout
			(tracks not_allowed)
			(vias allowed)
			(pads allowed)
			(copperpour not_allowed)
			(footprints allowed)
		)
		(placement
			(enabled no)
			(sheetname "")
		)
		(fill yes
			(thermal_gap 0.5)
			(thermal_bridge_width 0.5)
			(island_removal_mode 0)
		)
		(polygon
			(pts
				(arc
					(start 113.358168 -52.00015)
					(mid 113.000028 -51.64201)
					(end 112.641888 -52.00015)
				)
				(arc
					(start 112.641888 -52.999894)
					(mid 112.999901 -53.358288)
					(end 113.358168 -53.000148)
				)
			)
		)
	)
	(zone
		(layers "In1.Cu" "In3.Cu" "In4.Cu" "In6.Cu")
		(hatch none 0.5)
		(connect_pads
			(clearance 0)
		)
		(min_thickness 0.25)
		(keepout
			(tracks not_allowed)
			(vias allowed)
			(pads allowed)
			(copperpour not_allowed)
			(footprints allowed)
		)
		(placement
			(enabled no)
			(sheetname "")
		)
		(fill yes
			(thermal_gap 0.5)
			(thermal_bridge_width 0.5)
			(island_removal_mode 0)
		)
		(polygon
			(pts
				(arc
					(start 106.358182 -51.000152)
					(mid 106.000042 -50.642012)
					(end 105.641902 -51.000152)
				)
				(arc
					(start 105.641902 -51.999896)
					(mid 105.999915 -52.35829)
					(end 106.358182 -52.00015)
				)
			)
		)
	)
	(zone
		(layers "In1.Cu" "In3.Cu" "In4.Cu" "In6.Cu")
		(hatch none 0.5)
		(connect_pads
			(clearance 0)
		)
		(min_thickness 0.25)
		(keepout
			(tracks not_allowed)
			(vias allowed)
			(pads allowed)
			(copperpour not_allowed)
			(footprints allowed)
		)
		(placement
			(enabled no)
			(sheetname "")
		)
		(fill yes
			(thermal_gap 0.5)
			(thermal_bridge_width 0.5)
			(island_removal_mode 0)
		)
		(polygon
			(pts
				(arc
					(start 117.35816 -51.000152)
					(mid 117.00002 -50.642012)
					(end 116.64188 -51.000152)
				)
				(arc
					(start 116.64188 -51.999896)
					(mid 116.999893 -52.35829)
					(end 117.35816 -52.00015)
				)
			)
		)
	)
	(zone
		(layers "In1.Cu" "In3.Cu" "In4.Cu" "In6.Cu")
		(hatch none 0.5)
		(connect_pads
			(clearance 0)
		)
		(min_thickness 0.25)
		(keepout
			(tracks not_allowed)
			(vias allowed)
			(pads allowed)
			(copperpour not_allowed)
			(footprints allowed)
		)
		(placement
			(enabled no)
			(sheetname "")
		)
		(fill yes
			(thermal_gap 0.5)
			(thermal_bridge_width 0.5)
			(island_removal_mode 0)
		)
		(polygon
			(pts
				(arc
					(start 176.75225 -23.103332)
					(mid 176.36871 -22.719792)
					(end 175.98517 -23.103332)
				)
				(arc
					(start 175.98517 -23.992078)
					(mid 176.368583 -24.375872)
					(end 176.75225 -23.992332)
				)
			)
		)
	)
	(zone
		(layers "In1.Cu" "In3.Cu" "In4.Cu" "In6.Cu")
		(hatch none 0.5)
		(connect_pads
			(clearance 0)
		)
		(min_thickness 0.25)
		(keepout
			(tracks not_allowed)
			(vias allowed)
			(pads allowed)
			(copperpour not_allowed)
			(footprints allowed)
		)
		(placement
			(enabled no)
			(sheetname "")
		)
		(fill yes
			(thermal_gap 0.5)
			(thermal_bridge_width 0.5)
			(island_removal_mode 0)
		)
		(polygon
			(pts
				(arc
					(start 166.58336 -37.600128)
					(mid 166.199947 -37.216334)
					(end 165.81628 -37.599874)
				)
				(arc
					(start 165.81628 -38.399974)
					(mid 166.19982 -38.783514)
					(end 166.58336 -38.399974)
				)
			)
		)
	)
	(zone
		(layers "In1.Cu" "In3.Cu" "In4.Cu" "In6.Cu")
		(hatch none 0.5)
		(connect_pads
			(clearance 0)
		)
		(min_thickness 0.25)
		(keepout
			(tracks not_allowed)
			(vias allowed)
			(pads allowed)
			(copperpour not_allowed)
			(footprints allowed)
		)
		(placement
			(enabled no)
			(sheetname "")
		)
		(fill yes
			(thermal_gap 0.5)
			(thermal_bridge_width 0.5)
			(island_removal_mode 0)
		)
		(polygon
			(pts
				(arc
					(start 124.358146 -52.00015)
					(mid 124.000006 -51.64201)
					(end 123.641866 -52.00015)
				)
				(arc
					(start 123.641866 -52.999894)
					(mid 123.999879 -53.358288)
					(end 124.358146 -53.000148)
				)
			)
		)
	)
	(zone
		(layers "In1.Cu" "In3.Cu" "In4.Cu" "In6.Cu")
		(hatch none 0.5)
		(connect_pads
			(clearance 0)
		)
		(min_thickness 0.25)
		(keepout
			(tracks not_allowed)
			(vias allowed)
			(pads allowed)
			(copperpour not_allowed)
			(footprints allowed)
		)
		(placement
			(enabled no)
			(sheetname "")
		)
		(fill yes
			(thermal_gap 0.5)
			(thermal_bridge_width 0.5)
			(island_removal_mode 0)
		)
		(polygon
			(pts
				(arc
					(start 111.761524 -3.800094)
					(mid 111.200184 -3.238754)
					(end 110.638844 -3.800094)
				)
				(arc
					(start 110.638844 -5.199888)
					(mid 111.200057 -5.761482)
					(end 111.761524 -5.200142)
				)
			)
		)
	)
	(zone
		(layers "In1.Cu" "In3.Cu" "In4.Cu" "In6.Cu")
		(hatch none 0.5)
		(connect_pads
			(clearance 0)
		)
		(min_thickness 0.25)
		(keepout
			(tracks not_allowed)
			(vias allowed)
			(pads allowed)
			(copperpour not_allowed)
			(footprints allowed)
		)
		(placement
			(enabled no)
			(sheetname "")
		)
		(fill yes
			(thermal_gap 0.5)
			(thermal_bridge_width 0.5)
			(island_removal_mode 0)
		)
		(polygon
			(pts
				(arc
					(start 106.358182 -55.000144)
					(mid 106.000042 -54.642004)
					(end 105.641902 -55.000144)
				)
				(arc
					(start 105.641902 -55.999888)
					(mid 105.999915 -56.358282)
					(end 106.358182 -56.000142)
				)
			)
		)
	)
	(zone
		(layers "In1.Cu" "In3.Cu" "In4.Cu" "In6.Cu")
		(hatch none 0.5)
		(connect_pads
			(clearance 0)
		)
		(min_thickness 0.25)
		(keepout
			(tracks not_allowed)
			(vias allowed)
			(pads allowed)
			(copperpour not_allowed)
			(footprints allowed)
		)
		(placement
			(enabled no)
			(sheetname "")
		)
		(fill yes
			(thermal_gap 0.5)
			(thermal_bridge_width 0.5)
			(island_removal_mode 0)
		)
		(polygon
			(pts
				(xy 103.189024 -108.884974) (xy 103.938832 -107.484926)
				(arc
					(start 103.93807 -107.484672)
					(mid 103.734616 -106.811826)
					(end 103.06177 -107.01528)
				)
				(xy 103.061008 -107.015026) (xy 102.311454 -108.41482) (xy 102.311454 -108.415074)
				(arc
					(start 102.311962 -108.415328)
					(mid 102.515416 -109.088174)
					(end 103.188262 -108.88472)
				)
			)
		)
	)
	(zone
		(layers "In1.Cu" "In3.Cu" "In4.Cu" "In6.Cu")
		(hatch none 0.5)
		(connect_pads
			(clearance 0)
		)
		(min_thickness 0.25)
		(keepout
			(tracks not_allowed)
			(vias allowed)
			(pads allowed)
			(copperpour not_allowed)
			(footprints allowed)
		)
		(placement
			(enabled no)
			(sheetname "")
		)
		(fill yes
			(thermal_gap 0.5)
			(thermal_bridge_width 0.5)
			(island_removal_mode 0)
		)
		(polygon
			(pts
				(arc
					(start 86.561422 -10.999978)
					(mid 86.000082 -10.438638)
					(end 85.438742 -10.999978)
				)
				(arc
					(start 85.438742 -12.399772)
					(mid 85.999955 -12.961366)
					(end 86.561422 -12.400026)
				)
			)
		)
	)
	(zone
		(layers "In1.Cu" "In3.Cu" "In4.Cu" "In6.Cu")
		(hatch none 0.5)
		(connect_pads
			(clearance 0)
		)
		(min_thickness 0.25)
		(keepout
			(tracks not_allowed)
			(vias allowed)
			(pads allowed)
			(copperpour not_allowed)
			(footprints allowed)
		)
		(placement
			(enabled no)
			(sheetname "")
		)
		(fill yes
			(thermal_gap 0.5)
			(thermal_bridge_width 0.5)
			(island_removal_mode 0)
		)
		(polygon
			(pts
				(xy 138.843512 -81.924906) (xy 138.843258 -81.92516)
				(arc
					(start 138.843258 -81.925668)
					(mid 138.46048 -82.308446)
					(end 138.843258 -82.691224)
				)
				(xy 138.843258 -82.691986) (xy 139.986258 -82.691986)
				(arc
					(start 139.986258 -82.691224)
					(mid 140.369036 -82.308446)
					(end 139.986258 -81.925668)
				)
				(xy 139.986258 -81.924906)
			)
		)
	)
	(zone
		(layers "In1.Cu" "In3.Cu" "In4.Cu" "In6.Cu")
		(hatch none 0.5)
		(connect_pads
			(clearance 0)
		)
		(min_thickness 0.25)
		(keepout
			(tracks not_allowed)
			(vias allowed)
			(pads allowed)
			(copperpour not_allowed)
			(footprints allowed)
		)
		(placement
			(enabled no)
			(sheetname "")
		)
		(fill yes
			(thermal_gap 0.5)
			(thermal_bridge_width 0.5)
			(island_removal_mode 0)
		)
		(polygon
			(pts
				(arc
					(start 119.358156 -55.000144)
					(mid 119.000016 -54.642004)
					(end 118.641876 -55.000144)
				)
				(arc
					(start 118.641876 -55.999888)
					(mid 118.999889 -56.358282)
					(end 119.358156 -56.000142)
				)
			)
		)
	)
	(zone
		(layers "In1.Cu" "In3.Cu" "In4.Cu" "In6.Cu")
		(hatch none 0.5)
		(connect_pads
			(clearance 0)
		)
		(min_thickness 0.25)
		(keepout
			(tracks not_allowed)
			(vias allowed)
			(pads allowed)
			(copperpour not_allowed)
			(footprints allowed)
		)
		(placement
			(enabled no)
			(sheetname "")
		)
		(fill yes
			(thermal_gap 0.5)
			(thermal_bridge_width 0.5)
			(island_removal_mode 0)
		)
		(polygon
			(pts
				(arc
					(start 127.96139 -9.800082)
					(mid 127.40005 -9.238742)
					(end 126.83871 -9.800082)
				)
				(arc
					(start 126.83871 -11.199876)
					(mid 127.399923 -11.76147)
					(end 127.96139 -11.20013)
				)
			)
		)
	)
	(zone
		(layers "In1.Cu" "In3.Cu" "In4.Cu" "In6.Cu")
		(hatch none 0.5)
		(connect_pads
			(clearance 0)
		)
		(min_thickness 0.25)
		(keepout
			(tracks not_allowed)
			(vias allowed)
			(pads allowed)
			(copperpour not_allowed)
			(footprints allowed)
		)
		(placement
			(enabled no)
			(sheetname "")
		)
		(fill yes
			(thermal_gap 0.5)
			(thermal_bridge_width 0.5)
			(island_removal_mode 0)
		)
		(polygon
			(pts
				(arc
					(start 174.642018 -31.199836)
					(mid 175.000158 -31.55823)
					(end 175.358298 -31.199836)
				)
				(arc
					(start 175.358044 -30.39999)
					(mid 174.999777 -30.04185)
					(end 174.641764 -30.400244)
				)
			)
		)
	)
	(zone
		(layers "In1.Cu" "In3.Cu" "In4.Cu" "In6.Cu")
		(hatch none 0.5)
		(connect_pads
			(clearance 0)
		)
		(min_thickness 0.25)
		(keepout
			(tracks not_allowed)
			(vias allowed)
			(pads allowed)
			(copperpour not_allowed)
			(footprints allowed)
		)
		(placement
			(enabled no)
			(sheetname "")
		)
		(fill yes
			(thermal_gap 0.5)
			(thermal_bridge_width 0.5)
			(island_removal_mode 0)
		)
		(polygon
			(pts
				(arc
					(start 126.000256 -53.642006)
					(mid 125.641862 -54.000019)
					(end 126.000002 -54.358286)
				)
				(arc
					(start 127 -54.358286)
					(mid 127.35814 -54.000146)
					(end 127 -53.642006)
				)
			)
		)
	)
	(zone
		(layers "In1.Cu" "In3.Cu" "In4.Cu" "In6.Cu")
		(hatch none 0.5)
		(connect_pads
			(clearance 0)
		)
		(min_thickness 0.25)
		(keepout
			(tracks not_allowed)
			(vias allowed)
			(pads allowed)
			(copperpour not_allowed)
			(footprints allowed)
		)
		(placement
			(enabled no)
			(sheetname "")
		)
		(fill yes
			(thermal_gap 0.5)
			(thermal_bridge_width 0.5)
			(island_removal_mode 0)
		)
		(polygon
			(pts
				(arc
					(start 126.000256 -71.64197)
					(mid 125.641862 -71.999983)
					(end 126.000002 -72.35825)
				)
				(arc
					(start 127 -72.35825)
					(mid 127.35814 -72.00011)
					(end 127 -71.64197)
				)
			)
		)
	)
	(zone
		(layers "In1.Cu" "In3.Cu" "In4.Cu" "In6.Cu")
		(hatch none 0.5)
		(connect_pads
			(clearance 0)
		)
		(min_thickness 0.25)
		(keepout
			(tracks not_allowed)
			(vias allowed)
			(pads allowed)
			(copperpour not_allowed)
			(footprints allowed)
		)
		(placement
			(enabled no)
			(sheetname "")
		)
		(fill yes
			(thermal_gap 0.5)
			(thermal_bridge_width 0.5)
			(island_removal_mode 0)
		)
		(polygon
			(pts
				(arc
					(start 129.00025 -60.641992)
					(mid 128.641856 -61.000005)
					(end 128.999996 -61.358272)
				)
				(arc
					(start 129.999994 -61.358272)
					(mid 130.358134 -61.000132)
					(end 129.999994 -60.641992)
				)
			)
		)
	)
	(zone
		(layers "In1.Cu" "In3.Cu" "In4.Cu" "In6.Cu")
		(hatch none 0.5)
		(connect_pads
			(clearance 0)
		)
		(min_thickness 0.25)
		(keepout
			(tracks not_allowed)
			(vias allowed)
			(pads allowed)
			(copperpour not_allowed)
			(footprints allowed)
		)
		(placement
			(enabled no)
			(sheetname "")
		)
		(fill yes
			(thermal_gap 0.5)
			(thermal_bridge_width 0.5)
			(island_removal_mode 0)
		)
		(polygon
			(pts
				(arc
					(start 117.35816 -55.000144)
					(mid 117.00002 -54.642004)
					(end 116.64188 -55.000144)
				)
				(arc
					(start 116.64188 -55.999888)
					(mid 116.999893 -56.358282)
					(end 117.35816 -56.000142)
				)
			)
		)
	)
	(zone
		(layers "In1.Cu" "In3.Cu" "In4.Cu" "In6.Cu")
		(hatch none 0.5)
		(connect_pads
			(clearance 0)
		)
		(min_thickness 0.25)
		(keepout
			(tracks not_allowed)
			(vias allowed)
			(pads allowed)
			(copperpour not_allowed)
			(footprints allowed)
		)
		(placement
			(enabled no)
			(sheetname "")
		)
		(fill yes
			(thermal_gap 0.5)
			(thermal_bridge_width 0.5)
			(island_removal_mode 0)
		)
		(polygon
			(pts
				(arc
					(start 91.961462 -2.600198)
					(mid 91.400122 -2.038858)
					(end 90.838782 -2.600198)
				)
				(arc
					(start 90.838782 -3.999738)
					(mid 91.399995 -4.561332)
					(end 91.961462 -3.999992)
				)
			)
		)
	)
	(zone
		(layers "In1.Cu" "In3.Cu" "In4.Cu" "In6.Cu")
		(hatch none 0.5)
		(connect_pads
			(clearance 0)
		)
		(min_thickness 0.25)
		(keepout
			(tracks not_allowed)
			(vias allowed)
			(pads allowed)
			(copperpour not_allowed)
			(footprints allowed)
		)
		(placement
			(enabled no)
			(sheetname "")
		)
		(fill yes
			(thermal_gap 0.5)
			(thermal_bridge_width 0.5)
			(island_removal_mode 0)
		)
		(polygon
			(pts
				(arc
					(start 115.361466 -10.999978)
					(mid 114.800126 -10.438638)
					(end 114.238786 -10.999978)
				)
				(arc
					(start 114.238786 -12.399772)
					(mid 114.799999 -12.961366)
					(end 115.361466 -12.400026)
				)
			)
		)
	)
	(zone
		(layers "In1.Cu" "In3.Cu" "In4.Cu" "In6.Cu")
		(hatch none 0.5)
		(connect_pads
			(clearance 0)
		)
		(min_thickness 0.25)
		(keepout
			(tracks not_allowed)
			(vias allowed)
			(pads allowed)
			(copperpour not_allowed)
			(footprints allowed)
		)
		(placement
			(enabled no)
			(sheetname "")
		)
		(fill yes
			(thermal_gap 0.5)
			(thermal_bridge_width 0.5)
			(island_removal_mode 0)
		)
		(polygon
			(pts
				(arc
					(start 150.54707 -39.016178)
					(mid 150.899368 -39.558468)
					(end 151.441658 -39.20617)
				)
				(arc
					(start 151.676862 -38.098476)
					(mid 151.332298 -37.547107)
					(end 150.784814 -37.89807)
				)
			)
		)
	)
	(zone
		(layers "In1.Cu" "In3.Cu" "In4.Cu" "In6.Cu")
		(hatch none 0.5)
		(connect_pads
			(clearance 0)
		)
		(min_thickness 0.25)
		(keepout
			(tracks not_allowed)
			(vias allowed)
			(pads allowed)
			(copperpour not_allowed)
			(footprints allowed)
		)
		(placement
			(enabled no)
			(sheetname "")
		)
		(fill yes
			(thermal_gap 0.5)
			(thermal_bridge_width 0.5)
			(island_removal_mode 0)
		)
		(polygon
			(pts
				(arc
					(start 126.000256 -70.641972)
					(mid 125.641862 -70.999985)
					(end 126.000002 -71.358252)
				)
				(arc
					(start 127 -71.358252)
					(mid 127.35814 -71.000112)
					(end 127 -70.641972)
				)
			)
		)
	)
	(zone
		(layers "In1.Cu" "In3.Cu" "In4.Cu" "In6.Cu")
		(hatch none 0.5)
		(connect_pads
			(clearance 0)
		)
		(min_thickness 0.25)
		(keepout
			(tracks not_allowed)
			(vias allowed)
			(pads allowed)
			(copperpour not_allowed)
			(footprints allowed)
		)
		(placement
			(enabled no)
			(sheetname "")
		)
		(fill yes
			(thermal_gap 0.5)
			(thermal_bridge_width 0.5)
			(island_removal_mode 0)
		)
		(polygon
			(pts
				(arc
					(start 109.961426 -2.600198)
					(mid 109.400086 -2.038858)
					(end 108.838746 -2.600198)
				)
				(arc
					(start 108.838746 -3.999738)
					(mid 109.399959 -4.561332)
					(end 109.961426 -3.999992)
				)
			)
		)
	)
	(zone
		(layers "In1.Cu" "In3.Cu" "In4.Cu" "In6.Cu")
		(hatch none 0.5)
		(connect_pads
			(clearance 0)
		)
		(min_thickness 0.25)
		(keepout
			(tracks not_allowed)
			(vias allowed)
			(pads allowed)
			(copperpour not_allowed)
			(footprints allowed)
		)
		(placement
			(enabled no)
			(sheetname "")
		)
		(fill yes
			(thermal_gap 0.5)
			(thermal_bridge_width 0.5)
			(island_removal_mode 0)
		)
		(polygon
			(pts
				(arc
					(start 100.358194 -51.000152)
					(mid 100.000054 -50.642012)
					(end 99.641914 -51.000152)
				)
				(arc
					(start 99.641914 -51.999896)
					(mid 99.999927 -52.35829)
					(end 100.358194 -52.00015)
				)
			)
		)
	)
	(zone
		(layers "In1.Cu" "In3.Cu" "In4.Cu" "In6.Cu")
		(hatch none 0.5)
		(connect_pads
			(clearance 0)
		)
		(min_thickness 0.25)
		(keepout
			(tracks not_allowed)
			(vias allowed)
			(pads allowed)
			(copperpour not_allowed)
			(footprints allowed)
		)
		(placement
			(enabled no)
			(sheetname "")
		)
		(fill yes
			(thermal_gap 0.5)
			(thermal_bridge_width 0.5)
			(island_removal_mode 0)
		)
		(polygon
			(pts
				(arc
					(start 149.100286 -45.226986)
					(mid 149.452584 -45.769276)
					(end 149.994874 -45.416978)
				)
				(arc
					(start 150.230078 -44.309284)
					(mid 149.885514 -43.757915)
					(end 149.33803 -44.108878)
				)
			)
		)
	)
	(zone
		(layers "In1.Cu" "In3.Cu" "In4.Cu" "In6.Cu")
		(hatch none 0.5)
		(connect_pads
			(clearance 0)
		)
		(min_thickness 0.25)
		(keepout
			(tracks not_allowed)
			(vias allowed)
			(pads allowed)
			(copperpour not_allowed)
			(footprints allowed)
		)
		(placement
			(enabled no)
			(sheetname "")
		)
		(fill yes
			(thermal_gap 0.5)
			(thermal_bridge_width 0.5)
			(island_removal_mode 0)
		)
		(polygon
			(pts
				(arc
					(start 129.00025 -67.641978)
					(mid 128.641856 -67.999991)
					(end 128.999996 -68.358258)
				)
				(arc
					(start 129.999994 -68.358258)
					(mid 130.358134 -68.000118)
					(end 129.999994 -67.641978)
				)
			)
		)
	)
	(zone
		(layers "In1.Cu" "In3.Cu" "In4.Cu" "In6.Cu")
		(hatch none 0.5)
		(connect_pads
			(clearance 0)
		)
		(min_thickness 0.25)
		(keepout
			(tracks not_allowed)
			(vias allowed)
			(pads allowed)
			(copperpour not_allowed)
			(footprints allowed)
		)
		(placement
			(enabled no)
			(sheetname "")
		)
		(fill yes
			(thermal_gap 0.5)
			(thermal_bridge_width 0.5)
			(island_removal_mode 0)
		)
		(polygon
			(pts
				(arc
					(start 126.000256 -63.641986)
					(mid 125.641862 -63.999999)
					(end 126.000002 -64.358266)
				)
				(arc
					(start 127 -64.358266)
					(mid 127.35814 -64.000126)
					(end 127 -63.641986)
				)
			)
		)
	)
	(zone
		(layers "In1.Cu" "In3.Cu" "In4.Cu" "In6.Cu")
		(hatch none 0.5)
		(connect_pads
			(clearance 0)
		)
		(min_thickness 0.25)
		(keepout
			(tracks not_allowed)
			(vias allowed)
			(pads allowed)
			(copperpour not_allowed)
			(footprints allowed)
		)
		(placement
			(enabled no)
			(sheetname "")
		)
		(fill yes
			(thermal_gap 0.5)
			(thermal_bridge_width 0.5)
			(island_removal_mode 0)
		)
		(polygon
			(pts
				(arc
					(start 116.358162 -55.000144)
					(mid 116.000022 -54.642004)
					(end 115.641882 -55.000144)
				)
				(arc
					(start 115.641882 -55.999888)
					(mid 115.999895 -56.358282)
					(end 116.358162 -56.000142)
				)
			)
		)
	)
	(zone
		(layers "In1.Cu" "In3.Cu" "In4.Cu" "In6.Cu")
		(hatch none 0.5)
		(connect_pads
			(clearance 0)
		)
		(min_thickness 0.25)
		(keepout
			(tracks not_allowed)
			(vias allowed)
			(pads allowed)
			(copperpour not_allowed)
			(footprints allowed)
		)
		(placement
			(enabled no)
			(sheetname "")
		)
		(fill yes
			(thermal_gap 0.5)
			(thermal_bridge_width 0.5)
			(island_removal_mode 0)
		)
		(polygon
			(pts
				(arc
					(start 126.000256 -72.641968)
					(mid 125.641862 -72.999981)
					(end 126.000002 -73.358248)
				)
				(arc
					(start 127 -73.358248)
					(mid 127.35814 -73.000108)
					(end 127 -72.641968)
				)
			)
		)
	)
	(zone
		(layers "In1.Cu" "In3.Cu" "In4.Cu" "In6.Cu")
		(hatch none 0.5)
		(connect_pads
			(clearance 0)
		)
		(min_thickness 0.25)
		(keepout
			(tracks not_allowed)
			(vias allowed)
			(pads allowed)
			(copperpour not_allowed)
			(footprints allowed)
		)
		(placement
			(enabled no)
			(sheetname "")
		)
		(fill yes
			(thermal_gap 0.5)
			(thermal_bridge_width 0.5)
			(island_removal_mode 0)
		)
		(polygon
			(pts
				(arc
					(start 136.961372 -3.800094)
					(mid 136.400032 -3.238754)
					(end 135.838692 -3.800094)
				)
				(arc
					(start 135.838692 -5.199888)
					(mid 136.399905 -5.761482)
					(end 136.961372 -5.200142)
				)
			)
		)
	)
	(zone
		(layers "In1.Cu" "In3.Cu" "In4.Cu" "In6.Cu")
		(hatch none 0.5)
		(connect_pads
			(clearance 0)
		)
		(min_thickness 0.25)
		(keepout
			(tracks not_allowed)
			(vias allowed)
			(pads allowed)
			(copperpour not_allowed)
			(footprints allowed)
		)
		(placement
			(enabled no)
			(sheetname "")
		)
		(fill yes
			(thermal_gap 0.5)
			(thermal_bridge_width 0.5)
			(island_removal_mode 0)
		)
		(polygon
			(pts
				(arc
					(start 140.588746 -59.35726)
					(mid 141.04366 -58.902727)
					(end 140.589 -58.44794)
				)
				(arc
					(start 139.446 -58.44794)
					(mid 138.99134 -58.9026)
					(end 139.446 -59.35726)
				)
			)
		)
	)
	(zone
		(layers "In1.Cu" "In3.Cu" "In4.Cu" "In6.Cu")
		(hatch none 0.5)
		(connect_pads
			(clearance 0)
		)
		(min_thickness 0.25)
		(keepout
			(tracks not_allowed)
			(vias allowed)
			(pads allowed)
			(copperpour not_allowed)
			(footprints allowed)
		)
		(placement
			(enabled no)
			(sheetname "")
		)
		(fill yes
			(thermal_gap 0.5)
			(thermal_bridge_width 0.5)
			(island_removal_mode 0)
		)
		(polygon
			(pts
				(arc
					(start 95.561404 -9.800082)
					(mid 95.000064 -9.238742)
					(end 94.438724 -9.800082)
				)
				(arc
					(start 94.438724 -11.199876)
					(mid 94.999937 -11.76147)
					(end 95.561404 -11.20013)
				)
			)
		)
	)
	(zone
		(layers "In1.Cu" "In3.Cu" "In4.Cu" "In6.Cu")
		(hatch none 0.5)
		(connect_pads
			(clearance 0)
		)
		(min_thickness 0.25)
		(keepout
			(tracks not_allowed)
			(vias allowed)
			(pads allowed)
			(copperpour not_allowed)
			(footprints allowed)
		)
		(placement
			(enabled no)
			(sheetname "")
		)
		(fill yes
			(thermal_gap 0.5)
			(thermal_bridge_width 0.5)
			(island_removal_mode 0)
		)
		(polygon
			(pts
				(arc
					(start 129.00025 -69.641974)
					(mid 128.641856 -69.999987)
					(end 128.999996 -70.358254)
				)
				(arc
					(start 129.999994 -70.358254)
					(mid 130.358134 -70.000114)
					(end 129.999994 -69.641974)
				)
			)
		)
	)
	(zone
		(layers "In1.Cu" "In3.Cu" "In4.Cu" "In6.Cu")
		(hatch none 0.5)
		(connect_pads
			(clearance 0)
		)
		(min_thickness 0.25)
		(keepout
			(tracks not_allowed)
			(vias allowed)
			(pads allowed)
			(copperpour not_allowed)
			(footprints allowed)
		)
		(placement
			(enabled no)
			(sheetname "")
		)
		(fill yes
			(thermal_gap 0.5)
			(thermal_bridge_width 0.5)
			(island_removal_mode 0)
		)
		(polygon
			(pts
				(arc
					(start 118.358158 -52.00015)
					(mid 118.000018 -51.64201)
					(end 117.641878 -52.00015)
				)
				(arc
					(start 117.641878 -52.999894)
					(mid 117.999891 -53.358288)
					(end 118.358158 -53.000148)
				)
			)
		)
	)
	(zone
		(layers "In1.Cu" "In3.Cu" "In4.Cu" "In6.Cu")
		(hatch none 0.5)
		(connect_pads
			(clearance 0)
		)
		(min_thickness 0.25)
		(keepout
			(tracks not_allowed)
			(vias allowed)
			(pads allowed)
			(copperpour not_allowed)
			(footprints allowed)
		)
		(placement
			(enabled no)
			(sheetname "")
		)
		(fill yes
			(thermal_gap 0.5)
			(thermal_bridge_width 0.5)
			(island_removal_mode 0)
		)
		(polygon
			(pts
				(arc
					(start 172.241972 -31.199836)
					(mid 172.600112 -31.55823)
					(end 172.958252 -31.199836)
				)
				(arc
					(start 172.957998 -30.39999)
					(mid 172.599731 -30.04185)
					(end 172.241718 -30.400244)
				)
			)
		)
	)
	(zone
		(layers "In1.Cu" "In3.Cu" "In4.Cu" "In6.Cu")
		(hatch none 0.5)
		(connect_pads
			(clearance 0)
		)
		(min_thickness 0.25)
		(keepout
			(tracks not_allowed)
			(vias allowed)
			(pads allowed)
			(copperpour not_allowed)
			(footprints allowed)
		)
		(placement
			(enabled no)
			(sheetname "")
		)
		(fill yes
			(thermal_gap 0.5)
			(thermal_bridge_width 0.5)
			(island_removal_mode 0)
		)
		(polygon
			(pts
				(arc
					(start 166.58336 -35.200082)
					(mid 166.199947 -34.816288)
					(end 165.81628 -35.199828)
				)
				(arc
					(start 165.81628 -35.999928)
					(mid 166.19982 -36.383468)
					(end 166.58336 -35.999928)
				)
			)
		)
	)
	(zone
		(layers "In1.Cu" "In3.Cu" "In4.Cu" "In6.Cu")
		(hatch none 0.5)
		(connect_pads
			(clearance 0)
		)
		(min_thickness 0.25)
		(keepout
			(tracks not_allowed)
			(vias allowed)
			(pads allowed)
			(copperpour not_allowed)
			(footprints allowed)
		)
		(placement
			(enabled no)
			(sheetname "")
		)
		(fill yes
			(thermal_gap 0.5)
			(thermal_bridge_width 0.5)
			(island_removal_mode 0)
		)
		(polygon
			(pts
				(arc
					(start 126.000256 -57.641998)
					(mid 125.641862 -58.000011)
					(end 126.000002 -58.358278)
				)
				(arc
					(start 127 -58.358278)
					(mid 127.35814 -58.000138)
					(end 127 -57.641998)
				)
			)
		)
	)
	(zone
		(layers "In1.Cu" "In3.Cu" "In4.Cu" "In6.Cu")
		(hatch none 0.5)
		(connect_pads
			(clearance 0)
		)
		(min_thickness 0.25)
		(keepout
			(tracks not_allowed)
			(vias allowed)
			(pads allowed)
			(copperpour not_allowed)
			(footprints allowed)
		)
		(placement
			(enabled no)
			(sheetname "")
		)
		(fill yes
			(thermal_gap 0.5)
			(thermal_bridge_width 0.5)
			(island_removal_mode 0)
		)
		(polygon
			(pts
				(arc
					(start 130.000248 -68.641976)
					(mid 129.641854 -68.999989)
					(end 129.999994 -69.358256)
				)
				(arc
					(start 130.999992 -69.358256)
					(mid 131.358132 -69.000116)
					(end 130.999992 -68.641976)
				)
			)
		)
	)
	(zone
		(layers "In1.Cu" "In3.Cu" "In4.Cu" "In6.Cu")
		(hatch none 0.5)
		(connect_pads
			(clearance 0)
		)
		(min_thickness 0.25)
		(keepout
			(tracks not_allowed)
			(vias allowed)
			(pads allowed)
			(copperpour not_allowed)
			(footprints allowed)
		)
		(placement
			(enabled no)
			(sheetname "")
		)
		(fill yes
			(thermal_gap 0.5)
			(thermal_bridge_width 0.5)
			(island_removal_mode 0)
		)
		(polygon
			(pts
				(arc
					(start 108.161328 -10.999978)
					(mid 107.599988 -10.438638)
					(end 107.038648 -10.999978)
				)
				(arc
					(start 107.038648 -12.399772)
					(mid 107.599861 -12.961366)
					(end 108.161328 -12.400026)
				)
			)
		)
	)
	(zone
		(layers "In1.Cu" "In3.Cu" "In4.Cu" "In6.Cu")
		(hatch none 0.5)
		(connect_pads
			(clearance 0)
		)
		(min_thickness 0.25)
		(keepout
			(tracks not_allowed)
			(vias allowed)
			(pads allowed)
			(copperpour not_allowed)
			(footprints allowed)
		)
		(placement
			(enabled no)
			(sheetname "")
		)
		(fill yes
			(thermal_gap 0.5)
			(thermal_bridge_width 0.5)
			(island_removal_mode 0)
		)
		(polygon
			(pts
				(arc
					(start 191.361314 -3.800094)
					(mid 190.799974 -3.238754)
					(end 190.238634 -3.800094)
				)
				(arc
					(start 190.238634 -5.199888)
					(mid 190.799847 -5.761482)
					(end 191.361314 -5.200142)
				)
			)
		)
	)
	(zone
		(layers "In1.Cu" "In3.Cu" "In4.Cu" "In6.Cu")
		(hatch none 0.5)
		(connect_pads
			(clearance 0)
		)
		(min_thickness 0.25)
		(keepout
			(tracks not_allowed)
			(vias allowed)
			(pads allowed)
			(copperpour not_allowed)
			(footprints allowed)
		)
		(placement
			(enabled no)
			(sheetname "")
		)
		(fill yes
			(thermal_gap 0.5)
			(thermal_bridge_width 0.5)
			(island_removal_mode 0)
		)
		(polygon
			(pts
				(arc
					(start 126.161546 -3.800094)
					(mid 125.600206 -3.238754)
					(end 125.038866 -3.800094)
				)
				(arc
					(start 125.038866 -5.199888)
					(mid 125.600079 -5.761482)
					(end 126.161546 -5.200142)
				)
			)
		)
	)
	(zone
		(layers "In1.Cu" "In3.Cu" "In4.Cu" "In6.Cu")
		(hatch none 0.5)
		(connect_pads
			(clearance 0)
		)
		(min_thickness 0.25)
		(keepout
			(tracks not_allowed)
			(vias allowed)
			(pads allowed)
			(copperpour not_allowed)
			(footprints allowed)
		)
		(placement
			(enabled no)
			(sheetname "")
		)
		(fill yes
			(thermal_gap 0.5)
			(thermal_bridge_width 0.5)
			(island_removal_mode 0)
		)
		(polygon
			(pts
				(arc
					(start 110.358174 -51.000152)
					(mid 110.000034 -50.642012)
					(end 109.641894 -51.000152)
				)
				(arc
					(start 109.641894 -51.999896)
					(mid 109.999907 -52.35829)
					(end 110.358174 -52.00015)
				)
			)
		)
	)
	(zone
		(layers "In1.Cu" "In3.Cu" "In4.Cu" "In6.Cu")
		(hatch none 0.5)
		(connect_pads
			(clearance 0)
		)
		(min_thickness 0.25)
		(keepout
			(tracks not_allowed)
			(vias allowed)
			(pads allowed)
			(copperpour not_allowed)
			(footprints allowed)
		)
		(placement
			(enabled no)
			(sheetname "")
		)
		(fill yes
			(thermal_gap 0.5)
			(thermal_bridge_width 0.5)
			(island_removal_mode 0)
		)
		(polygon
			(pts
				(arc
					(start 117.16131 -9.800082)
					(mid 116.59997 -9.238742)
					(end 116.03863 -9.800082)
				)
				(arc
					(start 116.03863 -11.199876)
					(mid 116.599843 -11.76147)
					(end 117.16131 -11.20013)
				)
			)
		)
	)
	(zone
		(layers "In1.Cu" "In3.Cu" "In4.Cu" "In6.Cu")
		(hatch none 0.5)
		(connect_pads
			(clearance 0)
		)
		(min_thickness 0.25)
		(keepout
			(tracks not_allowed)
			(vias allowed)
			(pads allowed)
			(copperpour not_allowed)
			(footprints allowed)
		)
		(placement
			(enabled no)
			(sheetname "")
		)
		(fill yes
			(thermal_gap 0.5)
			(thermal_bridge_width 0.5)
			(island_removal_mode 0)
		)
		(polygon
			(pts
				(arc
					(start 108.358178 -51.000152)
					(mid 108.000038 -50.642012)
					(end 107.641898 -51.000152)
				)
				(arc
					(start 107.641898 -51.999896)
					(mid 107.999911 -52.35829)
					(end 108.358178 -52.00015)
				)
			)
		)
	)
	(zone
		(layers "In1.Cu" "In3.Cu" "In4.Cu" "In6.Cu")
		(hatch none 0.5)
		(connect_pads
			(clearance 0)
		)
		(min_thickness 0.25)
		(keepout
			(tracks not_allowed)
			(vias allowed)
			(pads allowed)
			(copperpour not_allowed)
			(footprints allowed)
		)
		(placement
			(enabled no)
			(sheetname "")
		)
		(fill yes
			(thermal_gap 0.5)
			(thermal_bridge_width 0.5)
			(island_removal_mode 0)
		)
		(polygon
			(pts
				(arc
					(start 121.358152 -51.000152)
					(mid 121.000012 -50.642012)
					(end 120.641872 -51.000152)
				)
				(arc
					(start 120.641872 -51.999896)
					(mid 120.999885 -52.35829)
					(end 121.358152 -52.00015)
				)
			)
		)
	)
	(zone
		(layers "In1.Cu" "In3.Cu" "In4.Cu" "In6.Cu")
		(hatch none 0.5)
		(connect_pads
			(clearance 0)
		)
		(min_thickness 0.25)
		(keepout
			(tracks not_allowed)
			(vias allowed)
			(pads allowed)
			(copperpour not_allowed)
			(footprints allowed)
		)
		(placement
			(enabled no)
			(sheetname "")
		)
		(fill yes
			(thermal_gap 0.5)
			(thermal_bridge_width 0.5)
			(island_removal_mode 0)
		)
		(polygon
			(pts
				(arc
					(start 193.161158 -2.600198)
					(mid 192.599818 -2.038858)
					(end 192.038478 -2.600198)
				)
				(arc
					(start 192.038478 -3.999738)
					(mid 192.599691 -4.561332)
					(end 193.161158 -3.999992)
				)
			)
		)
	)
	(zone
		(layers "In1.Cu" "In3.Cu" "In4.Cu" "In6.Cu")
		(hatch none 0.5)
		(connect_pads
			(clearance 0)
		)
		(min_thickness 0.25)
		(keepout
			(tracks not_allowed)
			(vias allowed)
			(pads allowed)
			(copperpour not_allowed)
			(footprints allowed)
		)
		(placement
			(enabled no)
			(sheetname "")
		)
		(fill yes
			(thermal_gap 0.5)
			(thermal_bridge_width 0.5)
			(island_removal_mode 0)
		)
		(polygon
			(pts
				(arc
					(start 139.947396 -63.499746)
					(mid 140.40231 -63.045213)
					(end 139.94765 -62.590426)
				)
				(arc
					(start 138.80465 -62.590426)
					(mid 138.34999 -63.045086)
					(end 138.80465 -63.499746)
				)
			)
		)
	)
	(zone
		(layers "In1.Cu" "In3.Cu" "In4.Cu" "In6.Cu")
		(hatch none 0.5)
		(connect_pads
			(clearance 0)
		)
		(min_thickness 0.25)
		(keepout
			(tracks not_allowed)
			(vias allowed)
			(pads allowed)
			(copperpour not_allowed)
			(footprints allowed)
		)
		(placement
			(enabled no)
			(sheetname "")
		)
		(fill yes
			(thermal_gap 0.5)
			(thermal_bridge_width 0.5)
			(island_removal_mode 0)
		)
		(polygon
			(pts
				(arc
					(start 104.561386 -10.999978)
					(mid 104.000046 -10.438638)
					(end 103.438706 -10.999978)
				)
				(arc
					(start 103.438706 -12.399772)
					(mid 103.999919 -12.961366)
					(end 104.561386 -12.400026)
				)
			)
		)
	)
	(zone
		(layers "In1.Cu" "In3.Cu" "In4.Cu" "In6.Cu")
		(hatch none 0.5)
		(connect_pads
			(clearance 0)
		)
		(min_thickness 0.25)
		(keepout
			(tracks not_allowed)
			(vias allowed)
			(pads allowed)
			(copperpour not_allowed)
			(footprints allowed)
		)
		(placement
			(enabled no)
			(sheetname "")
		)
		(fill yes
			(thermal_gap 0.5)
			(thermal_bridge_width 0.5)
			(island_removal_mode 0)
		)
		(polygon
			(pts
				(arc
					(start 138.76147 -9.800082)
					(mid 138.20013 -9.238742)
					(end 137.63879 -9.800082)
				)
				(arc
					(start 137.63879 -11.199876)
					(mid 138.200003 -11.76147)
					(end 138.76147 -11.20013)
				)
			)
		)
	)
	(zone
		(layers "In1.Cu" "In3.Cu" "In4.Cu" "In6.Cu")
		(hatch none 0.5)
		(connect_pads
			(clearance 0)
		)
		(min_thickness 0.25)
		(keepout
			(tracks not_allowed)
			(vias allowed)
			(pads allowed)
			(copperpour not_allowed)
			(footprints allowed)
		)
		(placement
			(enabled no)
			(sheetname "")
		)
		(fill yes
			(thermal_gap 0.5)
			(thermal_bridge_width 0.5)
			(island_removal_mode 0)
		)
		(polygon
			(pts
				(arc
					(start 109.358176 -55.000144)
					(mid 109.000036 -54.642004)
					(end 108.641896 -55.000144)
				)
				(arc
					(start 108.641896 -55.999888)
					(mid 108.999909 -56.358282)
					(end 109.358176 -56.000142)
				)
			)
		)
	)
	(zone
		(layers "In1.Cu" "In3.Cu" "In4.Cu" "In6.Cu")
		(hatch none 0.5)
		(connect_pads
			(clearance 0)
		)
		(min_thickness 0.25)
		(keepout
			(tracks not_allowed)
			(vias allowed)
			(pads allowed)
			(copperpour not_allowed)
			(footprints allowed)
		)
		(placement
			(enabled no)
			(sheetname "")
		)
		(fill yes
			(thermal_gap 0.5)
			(thermal_bridge_width 0.5)
			(island_removal_mode 0)
		)
		(polygon
			(pts
				(arc
					(start 130.000248 -72.641968)
					(mid 129.641854 -72.999981)
					(end 129.999994 -73.358248)
				)
				(arc
					(start 130.999992 -73.358248)
					(mid 131.358132 -73.000108)
					(end 130.999992 -72.641968)
				)
			)
		)
	)
	(zone
		(layers "In1.Cu" "In3.Cu" "In4.Cu" "In6.Cu")
		(hatch none 0.5)
		(connect_pads
			(clearance 0)
		)
		(min_thickness 0.25)
		(keepout
			(tracks not_allowed)
			(vias allowed)
			(pads allowed)
			(copperpour not_allowed)
			(footprints allowed)
		)
		(placement
			(enabled no)
			(sheetname "")
		)
		(fill yes
			(thermal_gap 0.5)
			(thermal_bridge_width 0.5)
			(island_removal_mode 0)
		)
		(polygon
			(pts
				(arc
					(start 126.000256 -59.641994)
					(mid 125.641862 -60.000007)
					(end 126.000002 -60.358274)
				)
				(arc
					(start 127 -60.358274)
					(mid 127.35814 -60.000134)
					(end 127 -59.641994)
				)
			)
		)
	)
	(zone
		(layers "In1.Cu" "In3.Cu" "In4.Cu" "In6.Cu")
		(hatch none 0.5)
		(connect_pads
			(clearance 0)
		)
		(min_thickness 0.25)
		(keepout
			(tracks not_allowed)
			(vias allowed)
			(pads allowed)
			(copperpour not_allowed)
			(footprints allowed)
		)
		(placement
			(enabled no)
			(sheetname "")
		)
		(fill yes
			(thermal_gap 0.5)
			(thermal_bridge_width 0.5)
			(island_removal_mode 0)
		)
		(polygon
			(pts
				(arc
					(start 126.000256 -69.641974)
					(mid 125.641862 -69.999987)
					(end 126.000002 -70.358254)
				)
				(arc
					(start 127 -70.358254)
					(mid 127.35814 -70.000114)
					(end 127 -69.641974)
				)
			)
		)
	)
	(zone
		(layers "In1.Cu" "In3.Cu" "In4.Cu" "In6.Cu")
		(hatch none 0.5)
		(connect_pads
			(clearance 0)
		)
		(min_thickness 0.25)
		(keepout
			(tracks not_allowed)
			(vias allowed)
			(pads allowed)
			(copperpour not_allowed)
			(footprints allowed)
		)
		(placement
			(enabled no)
			(sheetname "")
		)
		(fill yes
			(thermal_gap 0.5)
			(thermal_bridge_width 0.5)
			(island_removal_mode 0)
		)
		(polygon
			(pts
				(arc
					(start 184.161176 -10.999978)
					(mid 183.599836 -10.438638)
					(end 183.038496 -10.999978)
				)
				(arc
					(start 183.038496 -12.399772)
					(mid 183.599709 -12.961366)
					(end 184.161176 -12.400026)
				)
			)
		)
	)
	(zone
		(layers "In1.Cu" "In3.Cu" "In4.Cu" "In6.Cu")
		(hatch none 0.5)
		(connect_pads
			(clearance 0)
		)
		(min_thickness 0.25)
		(keepout
			(tracks not_allowed)
			(vias allowed)
			(pads allowed)
			(copperpour not_allowed)
			(footprints allowed)
		)
		(placement
			(enabled no)
			(sheetname "")
		)
		(fill yes
			(thermal_gap 0.5)
			(thermal_bridge_width 0.5)
			(island_removal_mode 0)
		)
		(polygon
			(pts
				(arc
					(start 130.105658 -45.829474)
					(mid 129.648458 -45.372274)
					(end 129.191258 -45.829474)
				)
				(arc
					(start 129.191258 -46.97222)
					(mid 129.648331 -47.429674)
					(end 130.105658 -46.972474)
				)
			)
		)
	)
	(zone
		(layers "In1.Cu" "In3.Cu" "In4.Cu" "In6.Cu")
		(hatch none 0.5)
		(connect_pads
			(clearance 0)
		)
		(min_thickness 0.25)
		(keepout
			(tracks not_allowed)
			(vias allowed)
			(pads allowed)
			(copperpour not_allowed)
			(footprints allowed)
		)
		(placement
			(enabled no)
			(sheetname "")
		)
		(fill yes
			(thermal_gap 0.5)
			(thermal_bridge_width 0.5)
			(island_removal_mode 0)
		)
		(polygon
			(pts
				(arc
					(start 102.761542 -2.600198)
					(mid 102.200202 -2.038858)
					(end 101.638862 -2.600198)
				)
				(arc
					(start 101.638862 -3.999738)
					(mid 102.200075 -4.561332)
					(end 102.761542 -3.999992)
				)
			)
		)
	)
	(zone
		(layers "In1.Cu" "In3.Cu" "In4.Cu" "In6.Cu")
		(hatch none 0.5)
		(connect_pads
			(clearance 0)
		)
		(min_thickness 0.25)
		(keepout
			(tracks not_allowed)
			(vias allowed)
			(pads allowed)
			(copperpour not_allowed)
			(footprints allowed)
		)
		(placement
			(enabled no)
			(sheetname "")
		)
		(fill yes
			(thermal_gap 0.5)
			(thermal_bridge_width 0.5)
			(island_removal_mode 0)
		)
		(polygon
			(pts
				(arc
					(start 126.161546 -10.999978)
					(mid 125.600206 -10.438638)
					(end 125.038866 -10.999978)
				)
				(arc
					(start 125.038866 -12.399772)
					(mid 125.600079 -12.961366)
					(end 126.161546 -12.400026)
				)
			)
		)
	)
	(zone
		(layers "In1.Cu" "In3.Cu" "In4.Cu" "In6.Cu")
		(hatch none 0.5)
		(connect_pads
			(clearance 0)
		)
		(min_thickness 0.25)
		(keepout
			(tracks not_allowed)
			(vias allowed)
			(pads allowed)
			(copperpour not_allowed)
			(footprints allowed)
		)
		(placement
			(enabled no)
			(sheetname "")
		)
		(fill yes
			(thermal_gap 0.5)
			(thermal_bridge_width 0.5)
			(island_removal_mode 0)
		)
		(polygon
			(pts
				(arc
					(start 140.173456 -61.576712)
					(mid 140.62837 -61.122179)
					(end 140.17371 -60.667392)
				)
				(arc
					(start 139.03071 -60.667392)
					(mid 138.57605 -61.122052)
					(end 139.03071 -61.576712)
				)
			)
		)
	)
	(zone
		(layers "In1.Cu" "In3.Cu" "In4.Cu" "In6.Cu")
		(hatch none 0.5)
		(connect_pads
			(clearance 0)
		)
		(min_thickness 0.25)
		(keepout
			(tracks not_allowed)
			(vias allowed)
			(pads allowed)
			(copperpour not_allowed)
			(footprints allowed)
		)
		(placement
			(enabled no)
			(sheetname "")
		)
		(fill yes
			(thermal_gap 0.5)
			(thermal_bridge_width 0.5)
			(island_removal_mode 0)
		)
		(polygon
			(pts
				(arc
					(start 166.199566 -34.783522)
					(mid 166.58336 -34.400109)
					(end 166.19982 -34.016442)
				)
				(arc
					(start 165.399974 -34.016442)
					(mid 165.016434 -34.399982)
					(end 165.399974 -34.783522)
				)
			)
		)
	)
	(zone
		(layers "In1.Cu" "In3.Cu" "In4.Cu" "In6.Cu")
		(hatch none 0.5)
		(connect_pads
			(clearance 0)
		)
		(min_thickness 0.25)
		(keepout
			(tracks not_allowed)
			(vias allowed)
			(pads allowed)
			(copperpour not_allowed)
			(footprints allowed)
		)
		(placement
			(enabled no)
			(sheetname "")
		)
		(fill yes
			(thermal_gap 0.5)
			(thermal_bridge_width 0.5)
			(island_removal_mode 0)
		)
		(polygon
			(pts
				(arc
					(start 131.561332 -2.600198)
					(mid 130.999992 -2.038858)
					(end 130.438652 -2.600198)
				)
				(arc
					(start 130.438652 -3.999738)
					(mid 130.999865 -4.561332)
					(end 131.561332 -3.999992)
				)
			)
		)
	)
	(zone
		(layers "In1.Cu" "In3.Cu" "In4.Cu" "In6.Cu")
		(hatch none 0.5)
		(connect_pads
			(clearance 0)
		)
		(min_thickness 0.25)
		(keepout
			(tracks not_allowed)
			(vias allowed)
			(pads allowed)
			(copperpour not_allowed)
			(footprints allowed)
		)
		(placement
			(enabled no)
			(sheetname "")
		)
		(fill yes
			(thermal_gap 0.5)
			(thermal_bridge_width 0.5)
			(island_removal_mode 0)
		)
		(polygon
			(pts
				(arc
					(start 112.35817 -55.000144)
					(mid 112.00003 -54.642004)
					(end 111.64189 -55.000144)
				)
				(arc
					(start 111.64189 -55.999888)
					(mid 111.999903 -56.358282)
					(end 112.35817 -56.000142)
				)
			)
		)
	)
	(zone
		(layers "In1.Cu" "In3.Cu" "In4.Cu" "In6.Cu")
		(hatch none 0.5)
		(connect_pads
			(clearance 0)
		)
		(min_thickness 0.25)
		(keepout
			(tracks not_allowed)
			(vias allowed)
			(pads allowed)
			(copperpour not_allowed)
			(footprints allowed)
		)
		(placement
			(enabled no)
			(sheetname "")
		)
		(fill yes
			(thermal_gap 0.5)
			(thermal_bridge_width 0.5)
			(island_removal_mode 0)
		)
		(polygon
			(pts
				(arc
					(start 102.761542 -9.800082)
					(mid 102.200202 -9.238742)
					(end 101.638862 -9.800082)
				)
				(arc
					(start 101.638862 -11.199876)
					(mid 102.200075 -11.76147)
					(end 102.761542 -11.20013)
				)
			)
		)
	)
	(zone
		(layers "In1.Cu" "In3.Cu" "In4.Cu" "In6.Cu")
		(hatch none 0.5)
		(connect_pads
			(clearance 0)
		)
		(min_thickness 0.25)
		(keepout
			(tracks not_allowed)
			(vias allowed)
			(pads allowed)
			(copperpour not_allowed)
			(footprints allowed)
		)
		(placement
			(enabled no)
			(sheetname "")
		)
		(fill yes
			(thermal_gap 0.5)
			(thermal_bridge_width 0.5)
			(island_removal_mode 0)
		)
		(polygon
			(pts
				(arc
					(start 88.36152 -2.600198)
					(mid 87.80018 -2.038858)
					(end 87.23884 -2.600198)
				)
				(arc
					(start 87.23884 -3.999738)
					(mid 87.800053 -4.561332)
					(end 88.36152 -3.999992)
				)
			)
		)
	)
	(zone
		(layers "In1.Cu" "In3.Cu" "In4.Cu" "In6.Cu")
		(hatch none 0.5)
		(connect_pads
			(clearance 0)
		)
		(min_thickness 0.25)
		(keepout
			(tracks not_allowed)
			(vias allowed)
			(pads allowed)
			(copperpour not_allowed)
			(footprints allowed)
		)
		(placement
			(enabled no)
			(sheetname "")
		)
		(fill yes
			(thermal_gap 0.5)
			(thermal_bridge_width 0.5)
			(island_removal_mode 0)
		)
		(polygon
			(pts
				(arc
					(start 101.358192 -52.00015)
					(mid 101.000052 -51.64201)
					(end 100.641912 -52.00015)
				)
				(arc
					(start 100.641912 -52.999894)
					(mid 100.999925 -53.358288)
					(end 101.358192 -53.000148)
				)
			)
		)
	)
	(zone
		(layers "In1.Cu" "In3.Cu" "In4.Cu" "In6.Cu")
		(hatch none 0.5)
		(connect_pads
			(clearance 0)
		)
		(min_thickness 0.25)
		(keepout
			(tracks not_allowed)
			(vias allowed)
			(pads allowed)
			(copperpour not_allowed)
			(footprints allowed)
		)
		(placement
			(enabled no)
			(sheetname "")
		)
		(fill yes
			(thermal_gap 0.5)
			(thermal_bridge_width 0.5)
			(island_removal_mode 0)
		)
		(polygon
			(pts
				(arc
					(start 147.761452 -3.800094)
					(mid 147.200112 -3.238754)
					(end 146.638772 -3.800094)
				)
				(arc
					(start 146.638772 -5.199888)
					(mid 147.199985 -5.761482)
					(end 147.761452 -5.200142)
				)
			)
		)
	)
	(zone
		(layers "In1.Cu" "In3.Cu" "In4.Cu" "In6.Cu")
		(hatch none 0.5)
		(connect_pads
			(clearance 0)
		)
		(min_thickness 0.25)
		(keepout
			(tracks not_allowed)
			(vias allowed)
			(pads allowed)
			(copperpour not_allowed)
			(footprints allowed)
		)
		(placement
			(enabled no)
			(sheetname "")
		)
		(fill yes
			(thermal_gap 0.5)
			(thermal_bridge_width 0.5)
			(island_removal_mode 0)
		)
		(polygon
			(pts
				(arc
					(start 126.000256 -76.64196)
					(mid 125.641862 -76.999973)
					(end 126.000002 -77.35824)
				)
				(arc
					(start 127 -77.35824)
					(mid 127.35814 -77.0001)
					(end 127 -76.64196)
				)
			)
		)
	)
	(zone
		(layers "In1.Cu" "In3.Cu" "In4.Cu" "In6.Cu")
		(hatch none 0.5)
		(connect_pads
			(clearance 0)
		)
		(min_thickness 0.25)
		(keepout
			(tracks not_allowed)
			(vias allowed)
			(pads allowed)
			(copperpour not_allowed)
			(footprints allowed)
		)
		(placement
			(enabled no)
			(sheetname "")
		)
		(fill yes
			(thermal_gap 0.5)
			(thermal_bridge_width 0.5)
			(island_removal_mode 0)
		)
		(polygon
			(pts
				(arc
					(start 126.000256 -64.641984)
					(mid 125.641862 -64.999997)
					(end 126.000002 -65.358264)
				)
				(arc
					(start 127 -65.358264)
					(mid 127.35814 -65.000124)
					(end 127 -64.641984)
				)
			)
		)
	)
	(zone
		(layers "In1.Cu" "In3.Cu" "In4.Cu" "In6.Cu")
		(hatch none 0.5)
		(connect_pads
			(clearance 0)
		)
		(min_thickness 0.25)
		(keepout
			(tracks not_allowed)
			(vias allowed)
			(pads allowed)
			(copperpour not_allowed)
			(footprints allowed)
		)
		(placement
			(enabled no)
			(sheetname "")
		)
		(fill yes
			(thermal_gap 0.5)
			(thermal_bridge_width 0.5)
			(island_removal_mode 0)
		)
		(polygon
			(pts
				(arc
					(start 185.961274 -9.800082)
					(mid 185.399934 -9.238742)
					(end 184.838594 -9.800082)
				)
				(arc
					(start 184.838594 -11.199876)
					(mid 185.399807 -11.76147)
					(end 185.961274 -11.20013)
				)
			)
		)
	)
	(zone
		(layers "In1.Cu" "In3.Cu" "In4.Cu" "In6.Cu")
		(hatch none 0.5)
		(connect_pads
			(clearance 0)
		)
		(min_thickness 0.25)
		(keepout
			(tracks not_allowed)
			(vias allowed)
			(pads allowed)
			(copperpour not_allowed)
			(footprints allowed)
		)
		(placement
			(enabled no)
			(sheetname "")
		)
		(fill yes
			(thermal_gap 0.5)
			(thermal_bridge_width 0.5)
			(island_removal_mode 0)
		)
		(polygon
			(pts
				(arc
					(start 121.358152 -55.000144)
					(mid 121.000012 -54.642004)
					(end 120.641872 -55.000144)
				)
				(arc
					(start 120.641872 -55.999888)
					(mid 120.999885 -56.358282)
					(end 121.358152 -56.000142)
				)
			)
		)
	)
	(zone
		(layers "In1.Cu" "In3.Cu" "In4.Cu" "In6.Cu")
		(hatch none 0.5)
		(connect_pads
			(clearance 0)
		)
		(min_thickness 0.25)
		(keepout
			(tracks not_allowed)
			(vias allowed)
			(pads allowed)
			(copperpour not_allowed)
			(footprints allowed)
		)
		(placement
			(enabled no)
			(sheetname "")
		)
		(fill yes
			(thermal_gap 0.5)
			(thermal_bridge_width 0.5)
			(island_removal_mode 0)
		)
		(polygon
			(pts
				(arc
					(start 93.761306 -10.999978)
					(mid 93.199966 -10.438638)
					(end 92.638626 -10.999978)
				)
				(arc
					(start 92.638626 -12.399772)
					(mid 93.199839 -12.961366)
					(end 93.761306 -12.400026)
				)
			)
		)
	)
	(zone
		(layers "In1.Cu" "In3.Cu" "In4.Cu" "In6.Cu")
		(hatch none 0.5)
		(connect_pads
			(clearance 0)
		)
		(min_thickness 0.25)
		(keepout
			(tracks not_allowed)
			(vias allowed)
			(pads allowed)
			(copperpour not_allowed)
			(footprints allowed)
		)
		(placement
			(enabled no)
			(sheetname "")
		)
		(fill yes
			(thermal_gap 0.5)
			(thermal_bridge_width 0.5)
			(island_removal_mode 0)
		)
		(polygon
			(pts
				(xy 105.438956 -108.885228) (xy 106.189018 -107.48518)
				(arc
					(start 106.188256 -107.484672)
					(mid 105.984802 -106.811826)
					(end 105.311956 -107.01528)
				)
				(xy 105.311194 -107.014772) (xy 104.561386 -108.41482) (xy 104.561386 -108.415074)
				(arc
					(start 104.561894 -108.415328)
					(mid 104.765348 -109.088174)
					(end 105.438194 -108.88472)
				)
			)
		)
	)
	(zone
		(layers "In1.Cu" "In3.Cu" "In4.Cu" "In6.Cu")
		(hatch none 0.5)
		(connect_pads
			(clearance 0)
		)
		(min_thickness 0.25)
		(keepout
			(tracks not_allowed)
			(vias allowed)
			(pads allowed)
			(copperpour not_allowed)
			(footprints allowed)
		)
		(placement
			(enabled no)
			(sheetname "")
		)
		(fill yes
			(thermal_gap 0.5)
			(thermal_bridge_width 0.5)
			(island_removal_mode 0)
		)
		(polygon
			(pts
				(arc
					(start 111.358172 -52.00015)
					(mid 111.000032 -51.64201)
					(end 110.641892 -52.00015)
				)
				(arc
					(start 110.641892 -52.999894)
					(mid 110.999905 -53.358288)
					(end 111.358172 -53.000148)
				)
			)
		)
	)
	(zone
		(layers "In1.Cu" "In3.Cu" "In4.Cu" "In6.Cu")
		(hatch none 0.5)
		(connect_pads
			(clearance 0)
		)
		(min_thickness 0.25)
		(keepout
			(tracks not_allowed)
			(vias allowed)
			(pads allowed)
			(copperpour not_allowed)
			(footprints allowed)
		)
		(placement
			(enabled no)
			(sheetname "")
		)
		(fill yes
			(thermal_gap 0.5)
			(thermal_bridge_width 0.5)
			(island_removal_mode 0)
		)
		(polygon
			(pts
				(arc
					(start 104.358186 -55.000144)
					(mid 104.000046 -54.642004)
					(end 103.641906 -55.000144)
				)
				(arc
					(start 103.641906 -55.999888)
					(mid 103.999919 -56.358282)
					(end 104.358186 -56.000142)
				)
			)
		)
	)
	(zone
		(layers "In1.Cu" "In3.Cu" "In4.Cu" "In6.Cu")
		(hatch none 0.5)
		(connect_pads
			(clearance 0)
		)
		(min_thickness 0.25)
		(keepout
			(tracks not_allowed)
			(vias allowed)
			(pads allowed)
			(copperpour not_allowed)
			(footprints allowed)
		)
		(placement
			(enabled no)
			(sheetname "")
		)
		(fill yes
			(thermal_gap 0.5)
			(thermal_bridge_width 0.5)
			(island_removal_mode 0)
		)
		(polygon
			(pts
				(arc
					(start 99.161346 -2.600198)
					(mid 98.600006 -2.038858)
					(end 98.038666 -2.600198)
				)
				(arc
					(start 98.038666 -3.999738)
					(mid 98.599879 -4.561332)
					(end 99.161346 -3.999992)
				)
			)
		)
	)
	(zone
		(layers "In1.Cu" "In3.Cu" "In4.Cu" "In6.Cu")
		(hatch none 0.5)
		(connect_pads
			(clearance 0)
		)
		(min_thickness 0.25)
		(keepout
			(tracks not_allowed)
			(vias allowed)
			(pads allowed)
			(copperpour not_allowed)
			(footprints allowed)
		)
		(placement
			(enabled no)
			(sheetname "")
		)
		(fill yes
			(thermal_gap 0.5)
			(thermal_bridge_width 0.5)
			(island_removal_mode 0)
		)
		(polygon
			(pts
				(arc
					(start 126.000256 -67.641978)
					(mid 125.641862 -67.999991)
					(end 126.000002 -68.358258)
				)
				(arc
					(start 127 -68.358258)
					(mid 127.35814 -68.000118)
					(end 127 -67.641978)
				)
			)
		)
	)
	(zone
		(layers "In1.Cu" "In3.Cu" "In4.Cu" "In6.Cu")
		(hatch none 0.5)
		(connect_pads
			(clearance 0)
		)
		(min_thickness 0.25)
		(keepout
			(tracks not_allowed)
			(vias allowed)
			(pads allowed)
			(copperpour not_allowed)
			(footprints allowed)
		)
		(placement
			(enabled no)
			(sheetname "")
		)
		(fill yes
			(thermal_gap 0.5)
			(thermal_bridge_width 0.5)
			(island_removal_mode 0)
		)
		(polygon
			(pts
				(arc
					(start 147.761452 -10.999978)
					(mid 147.200112 -10.438638)
					(end 146.638772 -10.999978)
				)
				(arc
					(start 146.638772 -12.399772)
					(mid 147.199985 -12.961366)
					(end 147.761452 -12.400026)
				)
			)
		)
	)
	(zone
		(layers "In1.Cu" "In3.Cu" "In4.Cu" "In6.Cu")
		(hatch none 0.5)
		(connect_pads
			(clearance 0)
		)
		(min_thickness 0.25)
		(keepout
			(tracks not_allowed)
			(vias allowed)
			(pads allowed)
			(copperpour not_allowed)
			(footprints allowed)
		)
		(placement
			(enabled no)
			(sheetname "")
		)
		(fill yes
			(thermal_gap 0.5)
			(thermal_bridge_width 0.5)
			(island_removal_mode 0)
		)
		(polygon
			(pts
				(arc
					(start 103.983536 -115.10899)
					(mid 103.759 -114.366294)
					(end 103.016304 -114.59083)
				)
				(xy 102.266496 -115.990624)
				(arc
					(start 102.266496 -115.990878)
					(mid 102.491032 -116.733574)
					(end 103.233728 -116.509038)
				)
			)
		)
	)
	(zone
		(layers "In1.Cu" "In3.Cu" "In4.Cu" "In6.Cu")
		(hatch none 0.5)
		(connect_pads
			(clearance 0)
		)
		(min_thickness 0.25)
		(keepout
			(tracks not_allowed)
			(vias allowed)
			(pads allowed)
			(copperpour not_allowed)
			(footprints allowed)
		)
		(placement
			(enabled no)
			(sheetname "")
		)
		(fill yes
			(thermal_gap 0.5)
			(thermal_bridge_width 0.5)
			(island_removal_mode 0)
		)
		(polygon
			(pts
				(arc
					(start 148.957792 -55.395876)
					(mid 149.302356 -55.947245)
					(end 149.84984 -55.596282)
				)
				(arc
					(start 150.087584 -54.478174)
					(mid 149.735286 -53.935884)
					(end 149.192996 -54.288182)
				)
			)
		)
	)
	(zone
		(layers "In1.Cu" "In3.Cu" "In4.Cu" "In6.Cu")
		(hatch none 0.5)
		(connect_pads
			(clearance 0)
		)
		(min_thickness 0.25)
		(keepout
			(tracks not_allowed)
			(vias allowed)
			(pads allowed)
			(copperpour not_allowed)
			(footprints allowed)
		)
		(placement
			(enabled no)
			(sheetname "")
		)
		(fill yes
			(thermal_gap 0.5)
			(thermal_bridge_width 0.5)
			(island_removal_mode 0)
		)
		(polygon
			(pts
				(arc
					(start 117.16131 -2.600198)
					(mid 116.59997 -2.038858)
					(end 116.03863 -2.600198)
				)
				(arc
					(start 116.03863 -3.999738)
					(mid 116.599843 -4.561332)
					(end 117.16131 -3.999992)
				)
			)
		)
	)
	(zone
		(layers "In1.Cu" "In3.Cu" "In4.Cu" "In6.Cu")
		(hatch none 0.5)
		(connect_pads
			(clearance 0)
		)
		(min_thickness 0.25)
		(keepout
			(tracks not_allowed)
			(vias allowed)
			(pads allowed)
			(copperpour not_allowed)
			(footprints allowed)
		)
		(placement
			(enabled no)
			(sheetname "")
		)
		(fill yes
			(thermal_gap 0.5)
			(thermal_bridge_width 0.5)
			(island_removal_mode 0)
		)
		(polygon
			(pts
				(arc
					(start 168.958006 -30.39999)
					(mid 168.599866 -30.04185)
					(end 168.241726 -30.39999)
				)
				(arc
					(start 168.241726 -31.199582)
					(mid 168.599739 -31.557976)
					(end 168.958006 -31.199836)
				)
			)
		)
	)
	(zone
		(net "P1V8_E")
		(layer "In2.Cu")
		(hatch none 0.5)
		(connect_pads
			(clearance 0.5)
		)
		(min_thickness 0.25)
		(fill yes
			(thermal_gap 0.5)
			(thermal_bridge_width 0.5)
			(island_removal_mode 0)
		)
		(polygon
			(pts
				(xy 162.5727 -98.3361) (xy 162.5727 -101.1301) (xy 164.9984 -103.5558) (xy 164.9984 -110.1344) (xy 168.3004 -113.4364)
				(xy 168.3004 -119.6086) (xy 170.4848 -121.793) (xy 175.5394 -121.793) (xy 175.7172 -121.9708) (xy 175.7172 -124.206)
				(xy 175.4378 -124.4854) (xy 167.9956 -124.4854) (xy 165.1762 -121.666) (xy 165.1762 -115.0112) (xy 162.306 -112.141)
				(xy 162.306 -107.0356) (xy 160.7439 -105.4735) (xy 160.7439 -101.6127) (xy 159.9057 -100.7745) (xy 159.9057 -100.2411)
				(xy 159.9057 -98.3234) (xy 160.1343 -98.0948) (xy 162.3314 -98.0948)
			)
		)
	)
	(zone
		(layer "In2.Cu")
		(hatch none 0.5)
		(connect_pads
			(clearance 0)
		)
		(min_thickness 0.25)
		(keepout
			(tracks not_allowed)
			(vias allowed)
			(pads allowed)
			(copperpour not_allowed)
			(footprints allowed)
		)
		(placement
			(enabled no)
			(sheetname "")
		)
		(fill
			(thermal_gap 0.5)
			(thermal_bridge_width 0.5)
			(island_removal_mode 0)
		)
		(polygon
			(pts
				(arc
					(start 166.58336 -30.400244)
					(mid 166.199947 -30.01645)
					(end 165.81628 -30.39999)
				)
				(xy 165.81628 -30.494224) (xy 165.911784 -30.589728)
				(arc
					(start 166.012368 -30.589728)
					(mid 166.288904 -30.148588)
					(end 166.225982 -30.66542)
				)
				(arc
					(start 166.225982 -30.66542)
					(mid 166.187573 -30.696695)
					(end 166.141146 -30.713934)
				)
				(xy 166.138352 -30.716728) (xy 165.911784 -30.716728) (xy 165.858952 -30.716728) (xy 165.821868 -30.679644)
				(xy 165.81628 -30.674056) (xy 165.81628 -30.894528) (xy 166.103808 -30.894528)
				(arc
					(start 166.10584 -30.896814)
					(mid 166.1507 -30.909714)
					(end 166.19093 -30.93339)
				)
				(arc
					(start 166.19093 -30.93339)
					(mid 166.311954 -31.441573)
					(end 166.001446 -31.021528)
				)
				(xy 165.81628 -31.021528)
				(arc
					(start 165.81628 -31.199836)
					(mid 165.881064 -31.413138)
					(end 166.053516 -31.55442)
				)
				(arc
					(start 166.346124 -31.55442)
					(mid 166.51861 -31.413161)
					(end 166.58336 -31.199836)
				)
			)
		)
	)
	(zone
		(layer "In2.Cu")
		(hatch none 0.5)
		(connect_pads
			(clearance 0)
		)
		(min_thickness 0.25)
		(keepout
			(tracks not_allowed)
			(vias allowed)
			(pads allowed)
			(copperpour not_allowed)
			(footprints allowed)
		)
		(placement
			(enabled no)
			(sheetname "")
		)
		(fill
			(thermal_gap 0.5)
			(thermal_bridge_width 0.5)
			(island_removal_mode 0)
		)
		(polygon
			(pts
				(arc
					(start 126.000256 -55.642002)
					(mid 125.641862 -56.000015)
					(end 126.000002 -56.358282)
				)
				(arc
					(start 127 -56.358282)
					(mid 127.355913 -56.040015)
					(end 127.079248 -55.650892)
				)
				(arc
					(start 126.810516 -55.650892)
					(mid 126.749876 -55.662972)
					(end 126.698502 -55.697374)
				)
				(arc
					(start 126.698502 -55.697374)
					(mid 126.664294 -55.748664)
					(end 126.652274 -55.809134)
				)
				(arc
					(start 126.652274 -55.911242)
					(mid 126.661573 -55.933693)
					(end 126.684024 -55.942992)
				)
				(arc
					(start 126.765558 -55.942992)
					(mid 127.241307 -56.000142)
					(end 126.765558 -56.057292)
				)
				(xy 126.660402 -56.057292)
				(arc
					(start 126.658116 -56.055006)
					(mid 126.58073 -56.014536)
					(end 126.54026 -55.93715)
				)
				(xy 126.537974 -55.934864) (xy 126.537974 -55.785512)
				(arc
					(start 126.53899 -55.784242)
					(mid 126.55697 -55.709069)
					(end 126.595378 -55.642002)
				)
				(arc
					(start 126.504446 -55.642002)
					(mid 126.47262 -55.722889)
					(end 126.461774 -55.809134)
				)
				(xy 126.461774 -55.934864)
				(arc
					(start 126.459488 -55.93715)
					(mid 126.419018 -56.014536)
					(end 126.341632 -56.055006)
				)
				(xy 126.339346 -56.057292)
				(arc
					(start 126.234444 -56.057292)
					(mid 125.758695 -56.000142)
					(end 126.234444 -55.942992)
				)
				(arc
					(start 126.315724 -55.942992)
					(mid 126.338175 -55.933693)
					(end 126.347474 -55.911242)
				)
				(xy 126.347474 -55.785512)
				(arc
					(start 126.348236 -55.78475)
					(mid 126.357817 -55.712168)
					(end 126.378716 -55.642002)
				)
			)
		)
	)
	(zone
		(layer "In2.Cu")
		(hatch none 0.5)
		(connect_pads
			(clearance 0)
		)
		(min_thickness 0.25)
		(keepout
			(tracks not_allowed)
			(vias allowed)
			(pads allowed)
			(copperpour not_allowed)
			(footprints allowed)
		)
		(placement
			(enabled no)
			(sheetname "")
		)
		(fill
			(thermal_gap 0.5)
			(thermal_bridge_width 0.5)
			(island_removal_mode 0)
		)
		(polygon
			(pts
				(xy 146.008344 -46.833536)
				(arc
					(start 145.884138 -46.80712)
					(mid 145.845811 -46.814158)
					(end 145.823686 -46.846236)
				)
				(arc
					(start 145.781522 -47.045118)
					(mid 145.788672 -47.083267)
					(end 145.820638 -47.105316)
				)
				(xy 145.944844 -47.131732) (xy 146.491452 -47.248064)
				(arc
					(start 146.615658 -47.27448)
					(mid 146.653985 -47.267442)
					(end 146.67611 -47.235364)
				)
				(arc
					(start 146.718274 -47.036482)
					(mid 146.711124 -46.998333)
					(end 146.679158 -46.976284)
				)
				(xy 146.554952 -46.949868)
			)
		)
	)
	(zone
		(layer "In2.Cu")
		(hatch none 0.5)
		(connect_pads
			(clearance 0)
		)
		(min_thickness 0.25)
		(keepout
			(tracks not_allowed)
			(vias allowed)
			(pads allowed)
			(copperpour not_allowed)
			(footprints allowed)
		)
		(placement
			(enabled no)
			(sheetname "")
		)
		(fill
			(thermal_gap 0.5)
			(thermal_bridge_width 0.5)
			(island_removal_mode 0)
		)
		(polygon
			(pts
				(xy 148.268182 -44.62145)
				(arc
					(start 148.143976 -44.595034)
					(mid 148.105649 -44.602072)
					(end 148.083524 -44.63415)
				)
				(arc
					(start 148.04136 -44.833032)
					(mid 148.04851 -44.871181)
					(end 148.080476 -44.89323)
				)
				(xy 148.204682 -44.919646) (xy 148.75129 -45.035978)
				(arc
					(start 148.875496 -45.062394)
					(mid 148.913823 -45.055356)
					(end 148.935948 -45.023278)
				)
				(arc
					(start 148.978112 -44.824396)
					(mid 148.970962 -44.786247)
					(end 148.938996 -44.764198)
				)
				(xy 148.81479 -44.737782)
			)
		)
	)
	(zone
		(layer "In2.Cu")
		(hatch none 0.5)
		(connect_pads
			(clearance 0)
		)
		(min_thickness 0.25)
		(keepout
			(tracks allowed)
			(vias allowed)
			(pads allowed)
			(copperpour allowed)
			(footprints allowed)
		)
		(placement
			(enabled no)
			(sheetname "")
		)
		(fill
			(thermal_gap 0.5)
			(thermal_bridge_width 0.5)
			(island_removal_mode 0)
		)
		(polygon
			(pts
				(xy 95.419418 -8.76173) (xy 96.393 -8.76173) (xy 96.393 -13.204444) (xy 95.419418 -13.204444)
			)
		)
	)
	(zone
		(layer "In2.Cu")
		(hatch none 0.5)
		(connect_pads
			(clearance 0)
		)
		(min_thickness 0.25)
		(keepout
			(tracks not_allowed)
			(vias allowed)
			(pads allowed)
			(copperpour not_allowed)
			(footprints allowed)
		)
		(placement
			(enabled no)
			(sheetname "")
		)
		(fill
			(thermal_gap 0.5)
			(thermal_bridge_width 0.5)
			(island_removal_mode 0)
		)
		(polygon
			(pts
				(arc
					(start 126.000256 -53.642006)
					(mid 125.641862 -54.000019)
					(end 126.000002 -54.358286)
				)
				(arc
					(start 127 -54.358286)
					(mid 127.355343 -54.044822)
					(end 127.088646 -53.653182)
				)
				(arc
					(start 126.733046 -53.653182)
					(mid 126.702122 -53.659315)
					(end 126.675896 -53.676804)
				)
				(arc
					(start 126.675896 -53.676804)
					(mid 126.658429 -53.703039)
					(end 126.652274 -53.733954)
				)
				(arc
					(start 126.652274 -53.911246)
					(mid 126.661573 -53.933697)
					(end 126.684024 -53.942996)
				)
				(arc
					(start 126.765558 -53.942996)
					(mid 127.241307 -54.000146)
					(end 126.765558 -54.057296)
				)
				(xy 126.660402 -54.057296)
				(arc
					(start 126.658116 -54.05501)
					(mid 126.58073 -54.01454)
					(end 126.54026 -53.937154)
				)
				(xy 126.537974 -53.934868) (xy 126.537974 -53.710332)
				(arc
					(start 126.539498 -53.708554)
					(mid 126.54728 -53.674302)
					(end 126.561088 -53.642006)
				)
				(arc
					(start 126.477776 -53.642006)
					(mid 126.465862 -53.687039)
					(end 126.461774 -53.733446)
				)
				(xy 126.461774 -53.934868)
				(arc
					(start 126.459488 -53.937154)
					(mid 126.419018 -54.01454)
					(end 126.341632 -54.05501)
				)
				(xy 126.339346 -54.057296)
				(arc
					(start 126.234444 -54.057296)
					(mid 125.758695 -54.000146)
					(end 126.234444 -53.942996)
				)
				(arc
					(start 126.315724 -53.942996)
					(mid 126.338175 -53.933697)
					(end 126.347474 -53.911246)
				)
				(xy 126.347474 -53.710332)
				(arc
					(start 126.348236 -53.70957)
					(mid 126.351818 -53.675563)
					(end 126.358396 -53.642006)
				)
			)
		)
	)
	(zone
		(layer "In2.Cu")
		(hatch none 0.5)
		(connect_pads
			(clearance 0)
		)
		(min_thickness 0.25)
		(keepout
			(tracks not_allowed)
			(vias allowed)
			(pads allowed)
			(copperpour not_allowed)
			(footprints allowed)
		)
		(placement
			(enabled no)
			(sheetname "")
		)
		(fill
			(thermal_gap 0.5)
			(thermal_bridge_width 0.5)
			(island_removal_mode 0)
		)
		(polygon
			(pts
				(arc
					(start 127.533908 -45.844206)
					(mid 127.076708 -45.387006)
					(end 126.619508 -45.844206)
				)
				(arc
					(start 126.619508 -46.986952)
					(mid 127.076581 -47.444406)
					(end 127.533908 -46.987206)
				)
				(xy 127.533908 -46.631606)
				(arc
					(start 127.197358 -46.631606)
					(mid 127.182944 -46.634438)
					(end 127.170688 -46.642528)
				)
				(arc
					(start 127.160782 -46.652688)
					(mid 127.145618 -46.675294)
					(end 127.140208 -46.701964)
				)
				(arc
					(start 127.140208 -46.728126)
					(mid 127.076708 -47.253954)
					(end 127.013208 -46.728126)
				)
				(xy 127.013208 -46.675548)
				(arc
					(start 127.01524 -46.673516)
					(mid 127.028331 -46.626482)
					(end 127.052578 -46.584108)
				)
				(xy 127.052578 -46.58106) (xy 127.070866 -46.563026) (xy 127.07112 -46.562518) (xy 127.080518 -46.55312)
				(xy 127.081026 -46.552612) (xy 127.09906 -46.534578)
				(arc
					(start 127.102616 -46.534578)
					(mid 127.13401 -46.517264)
					(end 127.168402 -46.507146)
				)
				(xy 127.170942 -46.504606) (xy 127.533908 -46.504606) (xy 127.533908 -46.326806) (xy 127.18415 -46.326806)
				(arc
					(start 127.182118 -46.324774)
					(mid 127.122147 -46.305897)
					(end 127.07112 -46.269148)
				)
				(arc
					(start 127.07112 -46.269148)
					(mid 127.034149 -46.217917)
					(end 127.01524 -46.157642)
				)
				(xy 127.013208 -46.15561)
				(arc
					(start 127.013208 -46.103286)
					(mid 127.076708 -45.577458)
					(end 127.140208 -46.103286)
				)
				(arc
					(start 127.140208 -46.129194)
					(mid 127.145617 -46.156299)
					(end 127.161036 -46.179232)
				)
				(arc
					(start 127.161036 -46.179232)
					(mid 127.183746 -46.19447)
					(end 127.210566 -46.199806)
				)
				(xy 127.533908 -46.199806)
			)
		)
	)
	(zone
		(layer "In2.Cu")
		(hatch none 0.5)
		(connect_pads
			(clearance 0)
		)
		(min_thickness 0.25)
		(keepout
			(tracks not_allowed)
			(vias allowed)
			(pads allowed)
			(copperpour not_allowed)
			(footprints allowed)
		)
		(placement
			(enabled no)
			(sheetname "")
		)
		(fill
			(thermal_gap 0.5)
			(thermal_bridge_width 0.5)
			(island_removal_mode 0)
		)
		(polygon
			(pts
				(arc
					(start 138.80465 -62.590426)
					(mid 138.34999 -63.045086)
					(end 138.80465 -63.499746)
				)
				(arc
					(start 139.947396 -63.499746)
					(mid 140.40231 -63.045213)
					(end 139.94765 -62.590426)
				)
				(xy 139.590018 -62.590426) (xy 139.591542 -62.61227) (xy 139.59205 -62.612778)
				(arc
					(start 139.59205 -62.877192)
					(mid 139.600046 -62.91721)
					(end 139.622784 -62.951106)
				)
				(arc
					(start 139.622784 -62.951106)
					(mid 139.652953 -62.97216)
					(end 139.68857 -62.981332)
				)
				(arc
					(start 139.68857 -62.981332)
					(mid 140.214459 -63.045209)
					(end 139.68857 -63.108586)
				)
				(xy 139.669774 -63.108586)
				(arc
					(start 139.66825 -63.106808)
					(mid 139.595034 -63.085274)
					(end 139.532868 -63.041022)
				)
				(arc
					(start 139.532868 -63.041022)
					(mid 139.488461 -62.978613)
					(end 139.466828 -62.905132)
				)
				(xy 139.46505 -62.903608)
				(arc
					(start 139.46505 -62.639194)
					(mid 139.464425 -62.614777)
					(end 139.46251 -62.590426)
				)
				(xy 139.282932 -62.590426) (xy 139.28598 -62.611508) (xy 139.28725 -62.612778) (xy 139.28725 -62.887352)
				(arc
					(start 139.285726 -62.888876)
					(mid 139.268491 -62.955501)
					(end 139.233656 -63.01486)
				)
				(xy 139.233656 -63.0174) (xy 139.196318 -63.054738)
				(arc
					(start 139.194032 -63.054738)
					(mid 139.134342 -63.089812)
					(end 139.067286 -63.107062)
				)
				(xy 139.065762 -63.108586)
				(arc
					(start 139.06373 -63.108586)
					(mid 138.537904 -63.046256)
					(end 139.063222 -62.9793)
				)
				(arc
					(start 139.063222 -62.9793)
					(mid 139.096547 -62.967384)
					(end 139.124944 -62.94628)
				)
				(arc
					(start 139.125198 -62.94628)
					(mid 139.151148 -62.907068)
					(end 139.16025 -62.860936)
				)
				(arc
					(start 139.16025 -62.639194)
					(mid 139.158283 -62.614493)
					(end 139.152376 -62.590426)
				)
			)
		)
	)
	(zone
		(layer "In2.Cu")
		(hatch none 0.5)
		(connect_pads
			(clearance 0)
		)
		(min_thickness 0.25)
		(keepout
			(tracks not_allowed)
			(vias allowed)
			(pads allowed)
			(copperpour not_allowed)
			(footprints allowed)
		)
		(placement
			(enabled no)
			(sheetname "")
		)
		(fill
			(thermal_gap 0.5)
			(thermal_bridge_width 0.5)
			(island_removal_mode 0)
		)
		(polygon
			(pts
				(arc
					(start 130.105658 -45.829474)
					(mid 129.648458 -45.372274)
					(end 129.191258 -45.829474)
				)
				(arc
					(start 129.191258 -46.97222)
					(mid 129.648331 -47.429674)
					(end 130.105658 -46.972474)
				)
				(xy 130.105658 -46.616874)
				(arc
					(start 129.769108 -46.616874)
					(mid 129.754694 -46.619706)
					(end 129.742438 -46.627796)
				)
				(arc
					(start 129.732532 -46.637956)
					(mid 129.717368 -46.660562)
					(end 129.711958 -46.687232)
				)
				(arc
					(start 129.711958 -46.713394)
					(mid 129.648458 -47.239222)
					(end 129.584958 -46.713394)
				)
				(xy 129.584958 -46.660816)
				(arc
					(start 129.58699 -46.658784)
					(mid 129.600081 -46.61175)
					(end 129.624328 -46.569376)
				)
				(xy 129.624328 -46.566328) (xy 129.642616 -46.548294) (xy 129.64287 -46.547786) (xy 129.652268 -46.538388)
				(xy 129.652776 -46.53788) (xy 129.67081 -46.519846)
				(arc
					(start 129.674366 -46.519846)
					(mid 129.70576 -46.502532)
					(end 129.740152 -46.492414)
				)
				(xy 129.742692 -46.489874) (xy 130.105658 -46.489874) (xy 130.105658 -46.312074) (xy 129.7559 -46.312074)
				(arc
					(start 129.753868 -46.310042)
					(mid 129.693897 -46.291165)
					(end 129.64287 -46.254416)
				)
				(arc
					(start 129.64287 -46.254416)
					(mid 129.605899 -46.203185)
					(end 129.58699 -46.14291)
				)
				(xy 129.584958 -46.140878)
				(arc
					(start 129.584958 -46.088554)
					(mid 129.648458 -45.562726)
					(end 129.711958 -46.088554)
				)
				(arc
					(start 129.711958 -46.114462)
					(mid 129.717367 -46.141567)
					(end 129.732786 -46.1645)
				)
				(arc
					(start 129.732786 -46.1645)
					(mid 129.755496 -46.179738)
					(end 129.782316 -46.185074)
				)
				(xy 130.105658 -46.185074)
			)
		)
	)
	(zone
		(layer "In2.Cu")
		(hatch none 0.5)
		(connect_pads
			(clearance 0)
		)
		(min_thickness 0.25)
		(keepout
			(tracks not_allowed)
			(vias allowed)
			(pads allowed)
			(copperpour not_allowed)
			(footprints allowed)
		)
		(placement
			(enabled no)
			(sheetname "")
		)
		(fill
			(thermal_gap 0.5)
			(thermal_bridge_width 0.5)
			(island_removal_mode 0)
		)
		(polygon
			(pts
				(xy 148.195284 -54.21884)
				(arc
					(start 148.071078 -54.192424)
					(mid 148.032751 -54.199462)
					(end 148.010626 -54.23154)
				)
				(arc
					(start 147.968462 -54.430422)
					(mid 147.975612 -54.468571)
					(end 148.007578 -54.49062)
				)
				(xy 148.131784 -54.517036) (xy 148.678392 -54.633368)
				(arc
					(start 148.802598 -54.659784)
					(mid 148.840925 -54.652746)
					(end 148.86305 -54.620668)
				)
				(arc
					(start 148.905214 -54.421786)
					(mid 148.898064 -54.383637)
					(end 148.866098 -54.361588)
				)
				(xy 148.741892 -54.335172)
			)
		)
	)
	(zone
		(layer "In2.Cu")
		(hatch none 0.5)
		(connect_pads
			(clearance 0)
		)
		(min_thickness 0.25)
		(keepout
			(tracks not_allowed)
			(vias allowed)
			(pads allowed)
			(copperpour not_allowed)
			(footprints allowed)
		)
		(placement
			(enabled no)
			(sheetname "")
		)
		(fill
			(thermal_gap 0.5)
			(thermal_bridge_width 0.5)
			(island_removal_mode 0)
		)
		(polygon
			(pts
				(xy 148.94941 -50.934874) (xy 148.831808 -50.950368) (xy 148.821902 -50.956718) (xy 148.806662 -50.953416)
				(xy 148.791422 -50.955448) (xy 148.782024 -50.948336) (xy 148.594064 -50.908458)
				(arc
					(start 148.592032 -50.90541)
					(mid 148.539458 -50.874607)
					(end 148.498814 -50.82921)
				)
				(arc
					(start 148.498814 -50.82921)
					(mid 148.473321 -50.771431)
					(end 148.467318 -50.70856)
				)
				(xy 148.465794 -50.70602) (xy 148.471128 -50.680366)
				(arc
					(start 148.476716 -50.654966)
					(mid 148.647335 -50.153794)
					(end 148.600922 -50.681128)
				)
				(arc
					(start 148.595588 -50.706782)
					(mid 148.595227 -50.734437)
					(end 148.605494 -50.760122)
				)
				(arc
					(start 148.605494 -50.760122)
					(mid 148.62353 -50.778884)
					(end 148.64715 -50.78984)
				)
				(xy 148.811742 -50.824892) (xy 148.97735 -50.803048)
				(arc
					(start 149.037294 -50.520092)
					(mid 148.69273 -49.968723)
					(end 148.145246 -50.319686)
				)
				(arc
					(start 147.907502 -51.437794)
					(mid 148.2598 -51.980084)
					(end 148.80209 -51.627786)
				)
				(xy 148.8821 -51.251104) (xy 148.819616 -51.259486) (xy 148.809456 -51.265836) (xy 148.79447 -51.262534)
				(xy 148.77923 -51.264566) (xy 148.769832 -51.257454)
				(arc
					(start 148.546566 -51.209956)
					(mid 148.531831 -51.209856)
					(end 148.518118 -51.21529)
				)
				(arc
					(start 148.505418 -51.223672)
					(mid 148.486559 -51.24244)
					(end 148.475954 -51.266852)
				)
				(arc
					(start 148.47062 -51.292506)
					(mid 148.300001 -51.793678)
					(end 148.346414 -51.266344)
				)
				(xy 148.357336 -51.214782)
				(arc
					(start 148.359876 -51.213004)
					(mid 148.382353 -51.169831)
					(end 148.41474 -51.133502)
				)
				(xy 148.415248 -51.130962) (xy 148.43506 -51.118008) (xy 148.437346 -51.116484) (xy 148.470366 -51.09464)
				(arc
					(start 148.473922 -51.095402)
					(mid 148.508514 -51.08502)
					(end 148.544534 -51.082448)
				)
				(xy 148.547582 -51.080416) (xy 148.572982 -51.08575) (xy 148.573236 -51.08575) (xy 148.79955 -51.13401)
				(xy 148.91004 -51.119278)
			)
		)
	)
	(zone
		(layer "In2.Cu")
		(hatch none 0.5)
		(connect_pads
			(clearance 0)
		)
		(min_thickness 0.25)
		(keepout
			(tracks not_allowed)
			(vias allowed)
			(pads allowed)
			(copperpour not_allowed)
			(footprints allowed)
		)
		(placement
			(enabled no)
			(sheetname "")
		)
		(fill
			(thermal_gap 0.5)
			(thermal_bridge_width 0.5)
			(island_removal_mode 0)
		)
		(polygon
			(pts
				(xy 149.596094 -38.359334)
				(arc
					(start 149.471888 -38.332918)
					(mid 149.433561 -38.339956)
					(end 149.411436 -38.372034)
				)
				(arc
					(start 149.369272 -38.570916)
					(mid 149.376422 -38.609065)
					(end 149.408388 -38.631114)
				)
				(xy 149.532594 -38.65753) (xy 150.079202 -38.773862)
				(arc
					(start 150.203408 -38.800278)
					(mid 150.241735 -38.79324)
					(end 150.26386 -38.761162)
				)
				(arc
					(start 150.306024 -38.56228)
					(mid 150.298874 -38.524131)
					(end 150.266908 -38.502082)
				)
				(xy 150.142702 -38.475666)
			)
		)
	)
	(zone
		(layer "In2.Cu")
		(hatch none 0.5)
		(connect_pads
			(clearance 0)
		)
		(min_thickness 0.25)
		(keepout
			(tracks not_allowed)
			(vias allowed)
			(pads allowed)
			(copperpour not_allowed)
			(footprints allowed)
		)
		(placement
			(enabled no)
			(sheetname "")
		)
		(fill
			(thermal_gap 0.5)
			(thermal_bridge_width 0.5)
			(island_removal_mode 0)
		)
		(polygon
			(pts
				(arc
					(start 132.677408 -45.814742)
					(mid 132.220208 -45.357542)
					(end 131.763008 -45.814742)
				)
				(arc
					(start 131.763008 -46.957488)
					(mid 132.220081 -47.414942)
					(end 132.677408 -46.957742)
				)
				(xy 132.677408 -46.602142)
				(arc
					(start 132.340858 -46.602142)
					(mid 132.326444 -46.604974)
					(end 132.314188 -46.613064)
				)
				(arc
					(start 132.304282 -46.623224)
					(mid 132.289118 -46.64583)
					(end 132.283708 -46.6725)
				)
				(arc
					(start 132.283708 -46.698662)
					(mid 132.220208 -47.22449)
					(end 132.156708 -46.698662)
				)
				(xy 132.156708 -46.646084)
				(arc
					(start 132.15874 -46.644052)
					(mid 132.171831 -46.597018)
					(end 132.196078 -46.554644)
				)
				(xy 132.196078 -46.551596) (xy 132.214366 -46.533562) (xy 132.21462 -46.533054) (xy 132.224018 -46.523656)
				(xy 132.224526 -46.523148) (xy 132.24256 -46.505114)
				(arc
					(start 132.246116 -46.505114)
					(mid 132.27751 -46.4878)
					(end 132.311902 -46.477682)
				)
				(xy 132.314442 -46.475142) (xy 132.677408 -46.475142) (xy 132.677408 -46.297342) (xy 132.32765 -46.297342)
				(arc
					(start 132.325618 -46.29531)
					(mid 132.265647 -46.276433)
					(end 132.21462 -46.239684)
				)
				(arc
					(start 132.21462 -46.239684)
					(mid 132.177649 -46.188453)
					(end 132.15874 -46.128178)
				)
				(xy 132.156708 -46.126146)
				(arc
					(start 132.156708 -46.073822)
					(mid 132.220208 -45.547994)
					(end 132.283708 -46.073822)
				)
				(arc
					(start 132.283708 -46.09973)
					(mid 132.289117 -46.126835)
					(end 132.304536 -46.149768)
				)
				(arc
					(start 132.304536 -46.149768)
					(mid 132.327246 -46.165006)
					(end 132.354066 -46.170342)
				)
				(xy 132.677408 -46.170342)
			)
		)
	)
	(zone
		(net "P3V3")
		(layer "In2.Cu")
		(hatch none 0.5)
		(connect_pads
			(clearance 0.5)
		)
		(min_thickness 0.25)
		(fill yes
			(thermal_gap 0.5)
			(thermal_bridge_width 0.5)
			(island_removal_mode 0)
		)
		(polygon
			(pts
				(xy 5.969 -67.7672) (xy 22.381972 -67.7672) (xy 23.9776 -66.171572) (xy 23.9776 -66.1416) (xy 24.4094 -65.7098)
				(xy 24.4094 -40.005) (xy 24.944324 -39.470076) (xy 28.4988 -35.9156) (xy 28.4988 -25.908) (xy 35.093148 -19.313652)
				(xy 56.971946 -19.313652) (xy 63.142622 -13.142976) (xy 72.703944 -13.142976) (xy 72.889872 -13.328904)
				(xy 72.889872 -17.05102) (xy 62.991492 -26.9494) (xy 53.721 -26.9494) (xy 50.673 -23.9014) (xy 41.047924 -23.9014)
				(xy 39.0525 -25.896824) (xy 39.0525 -29.442664) (xy 33.5788 -34.916364) (xy 33.5788 -39.2176) (xy 32.803846 -39.992554)
				(xy 28.9814 -43.815) (xy 28.9814 -47.9806) (xy 28.9814 -72.9742) (xy 37.7952 -81.788) (xy 44.9834 -88.9762)
				(xy 45.0342 -88.9762) (xy 45.4914 -89.4334) (xy 49.9364 -93.8784) (xy 49.9364 -121.666) (xy 50.6222 -122.3518)
				(xy 57.2516 -122.3518) (xy 57.6326 -122.7328) (xy 57.6326 -125.3744) (xy 57.6326 -126.1618) (xy 57.15 -126.6444)
				(xy 43.7134 -126.6444) (xy 43.053 -125.984) (xy 42.1386 -125.0696) (xy 42.1386 -107.1118) (xy 42.1386 -105.4354)
				(xy 40.5892 -103.886) (xy 38.9128 -103.886) (xy 5.08 -103.886) (xy 4.318 -103.124) (xy 4.318 -68.2244)
				(xy 4.7752 -67.7672) (xy 5.4102 -67.7672)
			)
		)
	)
	(zone
		(layer "In2.Cu")
		(hatch none 0.5)
		(connect_pads
			(clearance 0)
		)
		(min_thickness 0.25)
		(keepout
			(tracks not_allowed)
			(vias allowed)
			(pads allowed)
			(copperpour not_allowed)
			(footprints allowed)
		)
		(placement
			(enabled no)
			(sheetname "")
		)
		(fill
			(thermal_gap 0.5)
			(thermal_bridge_width 0.5)
			(island_removal_mode 0)
		)
		(polygon
			(pts
				(xy 165.897052 -36.416488)
				(arc
					(start 166.056056 -36.575492)
					(mid 166.388347 -36.988555)
					(end 165.975284 -36.656264)
				)
				(xy 165.776148 -36.457128) (xy 165.251384 -36.457128) (xy 165.156134 -36.552378)
				(arc
					(start 165.107112 -36.552378)
					(mid 165.05202 -36.6387)
					(end 165.021768 -36.736528)
				)
				(arc
					(start 165.140894 -36.736528)
					(mid 165.666722 -36.800028)
					(end 165.140894 -36.863528)
				)
				(arc
					(start 165.021768 -36.863528)
					(mid 165.152265 -37.092794)
					(end 165.399974 -37.183568)
				)
				(arc
					(start 166.19982 -37.183568)
					(mid 166.58336 -36.800028)
					(end 166.19982 -36.416488)
				)
			)
		)
	)
	(zone
		(layer "In2.Cu")
		(hatch none 0.5)
		(connect_pads
			(clearance 0)
		)
		(min_thickness 0.25)
		(keepout
			(tracks not_allowed)
			(vias allowed)
			(pads allowed)
			(copperpour not_allowed)
			(footprints allowed)
		)
		(placement
			(enabled no)
			(sheetname "")
		)
		(fill
			(thermal_gap 0.5)
			(thermal_bridge_width 0.5)
			(island_removal_mode 0)
		)
		(polygon
			(pts
				(xy 147.075652 -50.832004)
				(arc
					(start 146.951446 -50.805588)
					(mid 146.913119 -50.812626)
					(end 146.890994 -50.844704)
				)
				(arc
					(start 146.84883 -51.043586)
					(mid 146.85598 -51.081735)
					(end 146.887946 -51.103784)
				)
				(xy 147.012152 -51.1302) (xy 147.55876 -51.246532)
				(arc
					(start 147.682966 -51.272948)
					(mid 147.721293 -51.26591)
					(end 147.743418 -51.233832)
				)
				(arc
					(start 147.785582 -51.03495)
					(mid 147.778432 -50.996801)
					(end 147.746466 -50.974752)
				)
				(xy 147.62226 -50.948336)
			)
		)
	)
	(zone
		(layer "In2.Cu")
		(hatch none 0.5)
		(connect_pads
			(clearance 0)
		)
		(min_thickness 0.25)
		(keepout
			(tracks not_allowed)
			(vias allowed)
			(pads allowed)
			(copperpour not_allowed)
			(footprints allowed)
		)
		(placement
			(enabled no)
			(sheetname "")
		)
		(fill
			(thermal_gap 0.5)
			(thermal_bridge_width 0.5)
			(island_removal_mode 0)
		)
		(polygon
			(pts
				(xy 149.211284 -40.80256) (xy 148.8694 -40.729916)
				(arc
					(start 148.867622 -40.727376)
					(mid 148.81298 -40.696451)
					(end 148.770848 -40.649906)
				)
				(arc
					(start 148.770848 -40.649906)
					(mid 148.745355 -40.592127)
					(end 148.739352 -40.529256)
				)
				(xy 148.737828 -40.526716) (xy 148.743162 -40.501062)
				(arc
					(start 148.74875 -40.475662)
					(mid 148.919369 -39.97449)
					(end 148.872956 -40.501824)
				)
				(arc
					(start 148.867622 -40.527478)
					(mid 148.867261 -40.555133)
					(end 148.877528 -40.580818)
				)
				(arc
					(start 148.877528 -40.580818)
					(mid 148.896488 -40.600395)
					(end 148.92147 -40.611298)
				)
				(xy 149.2377 -40.678354)
				(arc
					(start 149.309328 -40.340788)
					(mid 148.964764 -39.789419)
					(end 148.41728 -40.140382)
				)
				(arc
					(start 148.179536 -41.25849)
					(mid 148.531834 -41.80078)
					(end 149.074124 -41.448482)
				)
				(xy 149.148038 -41.100756) (xy 148.831808 -41.0337) (xy 148.82495 -41.032176)
				(arc
					(start 148.81606 -41.030398)
					(mid 148.802614 -41.030895)
					(end 148.790152 -41.035986)
				)
				(arc
					(start 148.777452 -41.044368)
					(mid 148.758593 -41.063136)
					(end 148.747988 -41.087548)
				)
				(arc
					(start 148.742654 -41.113202)
					(mid 148.572035 -41.614374)
					(end 148.618448 -41.08704)
				)
				(xy 148.62937 -41.035478)
				(arc
					(start 148.63191 -41.0337)
					(mid 148.654387 -40.990527)
					(end 148.686774 -40.954198)
				)
				(xy 148.687282 -40.951658) (xy 148.707094 -40.938704) (xy 148.70938 -40.93718) (xy 148.7424 -40.915336)
				(arc
					(start 148.745956 -40.916098)
					(mid 148.78796 -40.904442)
					(end 148.831554 -40.90416)
				)
				(xy 148.832316 -40.903906) (xy 148.839428 -40.90543) (xy 148.84527 -40.9067) (xy 148.84654 -40.906954)
				(xy 148.851874 -40.90797) (xy 148.85797 -40.90924) (xy 149.174454 -40.97655) (xy 149.188678 -40.90924)
			)
		)
	)
	(zone
		(layer "In2.Cu")
		(hatch none 0.5)
		(connect_pads
			(clearance 0)
		)
		(min_thickness 0.25)
		(keepout
			(tracks not_allowed)
			(vias allowed)
			(pads allowed)
			(copperpour not_allowed)
			(footprints allowed)
		)
		(placement
			(enabled no)
			(sheetname "")
		)
		(fill
			(thermal_gap 0.5)
			(thermal_bridge_width 0.5)
			(island_removal_mode 0)
		)
		(polygon
			(pts
				(xy 145.128996 -32.20085)
				(arc
					(start 145.00479 -32.174434)
					(mid 144.966463 -32.181472)
					(end 144.944338 -32.21355)
				)
				(arc
					(start 144.902174 -32.412432)
					(mid 144.909324 -32.450581)
					(end 144.94129 -32.47263)
				)
				(xy 145.065496 -32.499046) (xy 145.612104 -32.615378)
				(arc
					(start 145.73631 -32.641794)
					(mid 145.774637 -32.634756)
					(end 145.796762 -32.602678)
				)
				(arc
					(start 145.838926 -32.403796)
					(mid 145.831776 -32.365647)
					(end 145.79981 -32.343598)
				)
				(xy 145.675604 -32.317182)
			)
		)
	)
	(zone
		(layer "In2.Cu")
		(hatch none 0.5)
		(connect_pads
			(clearance 0)
		)
		(min_thickness 0.25)
		(keepout
			(tracks not_allowed)
			(vias allowed)
			(pads allowed)
			(copperpour not_allowed)
			(footprints allowed)
		)
		(placement
			(enabled no)
			(sheetname "")
		)
		(fill
			(thermal_gap 0.5)
			(thermal_bridge_width 0.5)
			(island_removal_mode 0)
		)
		(polygon
			(pts
				(xy 149.717506 -37.788088)
				(arc
					(start 149.5933 -37.761672)
					(mid 149.554973 -37.76871)
					(end 149.532848 -37.800788)
				)
				(arc
					(start 149.490684 -37.99967)
					(mid 149.497834 -38.037819)
					(end 149.5298 -38.059868)
				)
				(xy 149.654006 -38.086284) (xy 150.200614 -38.202616)
				(arc
					(start 150.32482 -38.229032)
					(mid 150.363147 -38.221994)
					(end 150.385272 -38.189916)
				)
				(arc
					(start 150.427436 -37.991034)
					(mid 150.420286 -37.952885)
					(end 150.38832 -37.930836)
				)
				(xy 150.264114 -37.90442)
			)
		)
	)
	(zone
		(layer "In2.Cu")
		(hatch none 0.5)
		(connect_pads
			(clearance 0)
		)
		(min_thickness 0.25)
		(keepout
			(tracks not_allowed)
			(vias allowed)
			(pads allowed)
			(copperpour not_allowed)
			(footprints allowed)
		)
		(placement
			(enabled no)
			(sheetname "")
		)
		(fill
			(thermal_gap 0.5)
			(thermal_bridge_width 0.5)
			(island_removal_mode 0)
		)
		(polygon
			(pts
				(arc
					(start 166.58336 -37.600128)
					(mid 166.199947 -37.216334)
					(end 165.81628 -37.599874)
				)
				(xy 165.81628 -37.698426) (xy 165.90772 -37.789866)
				(arc
					(start 166.012622 -37.789866)
					(mid 166.288617 -37.348368)
					(end 166.226236 -37.865304)
				)
				(arc
					(start 166.226236 -37.865304)
					(mid 166.187739 -37.896764)
					(end 166.141146 -37.914072)
				)
				(xy 166.138352 -37.916866) (xy 165.90772 -37.916866) (xy 165.854888 -37.916866) (xy 165.817804 -37.879782)
				(xy 165.81628 -37.878258) (xy 165.81628 -38.094666) (xy 166.103808 -38.094666)
				(arc
					(start 166.10584 -38.096952)
					(mid 166.1507 -38.109852)
					(end 166.19093 -38.133528)
				)
				(arc
					(start 166.19093 -38.133528)
					(mid 166.311954 -38.641711)
					(end 166.001446 -38.221666)
				)
				(xy 165.81628 -38.221666)
				(arc
					(start 165.81628 -38.399974)
					(mid 166.19982 -38.783514)
					(end 166.58336 -38.399974)
				)
			)
		)
	)
	(zone
		(layer "In2.Cu")
		(hatch none 0.5)
		(connect_pads
			(clearance 0)
		)
		(min_thickness 0.25)
		(keepout
			(tracks not_allowed)
			(vias allowed)
			(pads allowed)
			(copperpour not_allowed)
			(footprints allowed)
		)
		(placement
			(enabled no)
			(sheetname "")
		)
		(fill
			(thermal_gap 0.5)
			(thermal_bridge_width 0.5)
			(island_removal_mode 0)
		)
		(polygon
			(pts
				(xy 145.007584 -32.77235)
				(arc
					(start 144.883378 -32.745934)
					(mid 144.845051 -32.752972)
					(end 144.822926 -32.78505)
				)
				(arc
					(start 144.780762 -32.983932)
					(mid 144.787912 -33.022081)
					(end 144.819878 -33.04413)
				)
				(xy 144.944084 -33.070546) (xy 145.490692 -33.186878)
				(arc
					(start 145.614898 -33.213294)
					(mid 145.653225 -33.206256)
					(end 145.67535 -33.174178)
				)
				(arc
					(start 145.717514 -32.975296)
					(mid 145.710364 -32.937147)
					(end 145.678398 -32.915098)
				)
				(xy 145.554192 -32.888682)
			)
		)
	)
	(zone
		(layer "In2.Cu")
		(hatch none 0.5)
		(connect_pads
			(clearance 0)
		)
		(min_thickness 0.25)
		(keepout
			(tracks not_allowed)
			(vias allowed)
			(pads allowed)
			(copperpour not_allowed)
			(footprints allowed)
		)
		(placement
			(enabled no)
			(sheetname "")
		)
		(fill
			(thermal_gap 0.5)
			(thermal_bridge_width 0.5)
			(island_removal_mode 0)
		)
		(polygon
			(pts
				(xy 166.696898 -29.216604)
				(arc
					(start 166.855902 -29.375608)
					(mid 167.188193 -29.788671)
					(end 166.77513 -29.45638)
				)
				(xy 166.57574 -29.25699)
				(arc
					(start 166.028116 -29.25699)
					(mid 165.972957 -29.290704)
					(end 165.92423 -29.33319)
				)
				(xy 166.013892 -29.33319)
				(arc
					(start 166.056056 -29.375354)
					(mid 166.388347 -29.788417)
					(end 165.975284 -29.456126)
				)
				(xy 165.966648 -29.44749)
				(arc
					(start 165.847776 -29.44749)
					(mid 165.879177 -29.810482)
					(end 166.19982 -29.98343)
				)
				(arc
					(start 166.999412 -29.983684)
					(mid 167.383206 -29.600271)
					(end 166.999666 -29.216604)
				)
			)
		)
	)
	(zone
		(layer "In2.Cu")
		(hatch none 0.5)
		(connect_pads
			(clearance 0)
		)
		(min_thickness 0.25)
		(keepout
			(tracks not_allowed)
			(vias allowed)
			(pads allowed)
			(copperpour not_allowed)
			(footprints allowed)
		)
		(placement
			(enabled no)
			(sheetname "")
		)
		(fill
			(thermal_gap 0.5)
			(thermal_bridge_width 0.5)
			(island_removal_mode 0)
		)
		(polygon
			(pts
				(arc
					(start 139.03071 -60.667392)
					(mid 138.57605 -61.122052)
					(end 139.03071 -61.576712)
				)
				(arc
					(start 140.173456 -61.576712)
					(mid 140.62837 -61.122179)
					(end 140.17371 -60.667392)
				)
				(xy 139.816078 -60.667392) (xy 139.817602 -60.689236) (xy 139.81811 -60.689744)
				(arc
					(start 139.81811 -60.954158)
					(mid 139.826106 -60.994176)
					(end 139.848844 -61.028072)
				)
				(arc
					(start 139.848844 -61.028072)
					(mid 139.879013 -61.049126)
					(end 139.91463 -61.058298)
				)
				(arc
					(start 139.91463 -61.058298)
					(mid 140.440519 -61.122175)
					(end 139.91463 -61.185552)
				)
				(xy 139.895834 -61.185552)
				(arc
					(start 139.89431 -61.183774)
					(mid 139.821094 -61.16224)
					(end 139.758928 -61.117988)
				)
				(arc
					(start 139.758928 -61.117988)
					(mid 139.714521 -61.055579)
					(end 139.692888 -60.982098)
				)
				(xy 139.69111 -60.980574)
				(arc
					(start 139.69111 -60.71616)
					(mid 139.690485 -60.691743)
					(end 139.68857 -60.667392)
				)
				(xy 139.508992 -60.667392) (xy 139.51204 -60.688474) (xy 139.51331 -60.689744) (xy 139.51331 -60.964318)
				(arc
					(start 139.511786 -60.965842)
					(mid 139.494551 -61.032467)
					(end 139.459716 -61.091826)
				)
				(xy 139.459716 -61.094366) (xy 139.422378 -61.131704)
				(arc
					(start 139.420092 -61.131704)
					(mid 139.360402 -61.166778)
					(end 139.293346 -61.184028)
				)
				(xy 139.291822 -61.185552)
				(arc
					(start 139.28979 -61.185552)
					(mid 138.763964 -61.123222)
					(end 139.289282 -61.056266)
				)
				(arc
					(start 139.289282 -61.056266)
					(mid 139.322607 -61.04435)
					(end 139.351004 -61.023246)
				)
				(arc
					(start 139.351258 -61.023246)
					(mid 139.377208 -60.984034)
					(end 139.38631 -60.937902)
				)
				(arc
					(start 139.38631 -60.71616)
					(mid 139.384343 -60.691459)
					(end 139.378436 -60.667392)
				)
			)
		)
	)
	(zone
		(layer "In2.Cu")
		(hatch none 0.5)
		(connect_pads
			(clearance 0)
		)
		(min_thickness 0.25)
		(keepout
			(tracks not_allowed)
			(vias allowed)
			(pads allowed)
			(copperpour not_allowed)
			(footprints allowed)
		)
		(placement
			(enabled no)
			(sheetname "")
		)
		(fill
			(thermal_gap 0.5)
			(thermal_bridge_width 0.5)
			(island_removal_mode 0)
		)
		(polygon
			(pts
				(arc
					(start 126.000256 -54.642004)
					(mid 125.641862 -55.000017)
					(end 126.000002 -55.358284)
				)
				(arc
					(start 127 -55.358284)
					(mid 127.355457 -55.043903)
					(end 127.086868 -54.652672)
				)
				(arc
					(start 126.730506 -54.652672)
					(mid 126.70054 -54.658597)
					(end 126.675134 -54.675532)
				)
				(arc
					(start 126.67488 -54.675786)
					(mid 126.658143 -54.701117)
					(end 126.652274 -54.730904)
				)
				(arc
					(start 126.652274 -54.911244)
					(mid 126.661573 -54.933695)
					(end 126.684024 -54.942994)
				)
				(arc
					(start 126.765558 -54.942994)
					(mid 127.241307 -55.000144)
					(end 126.765558 -55.057294)
				)
				(xy 126.660402 -55.057294)
				(arc
					(start 126.658116 -55.055008)
					(mid 126.58073 -55.014538)
					(end 126.54026 -54.937152)
				)
				(xy 126.537974 -54.934866) (xy 126.537974 -54.707282)
				(arc
					(start 126.539752 -54.705504)
					(mid 126.547015 -54.672878)
					(end 126.559818 -54.642004)
				)
				(arc
					(start 126.47676 -54.642004)
					(mid 126.465508 -54.685821)
					(end 126.461774 -54.730904)
				)
				(xy 126.461774 -54.934866)
				(arc
					(start 126.459488 -54.937152)
					(mid 126.419018 -55.014538)
					(end 126.341632 -55.055008)
				)
				(xy 126.339346 -55.057294)
				(arc
					(start 126.234444 -55.057294)
					(mid 125.758695 -55.000144)
					(end 126.234444 -54.942994)
				)
				(arc
					(start 126.315724 -54.942994)
					(mid 126.338175 -54.933695)
					(end 126.347474 -54.911244)
				)
				(xy 126.347474 -54.707282)
				(arc
					(start 126.348236 -54.70652)
					(mid 126.351698 -54.674058)
					(end 126.357888 -54.642004)
				)
			)
		)
	)
	(zone
		(layer "In2.Cu")
		(hatch none 0.5)
		(connect_pads
			(clearance 0)
		)
		(min_thickness 0.25)
		(keepout
			(tracks not_allowed)
			(vias allowed)
			(pads allowed)
			(copperpour not_allowed)
			(footprints allowed)
		)
		(placement
			(enabled no)
			(sheetname "")
		)
		(fill
			(thermal_gap 0.5)
			(thermal_bridge_width 0.5)
			(island_removal_mode 0)
		)
		(polygon
			(pts
				(xy 146.129756 -46.26229)
				(arc
					(start 146.00555 -46.235874)
					(mid 145.967223 -46.242912)
					(end 145.945098 -46.27499)
				)
				(arc
					(start 145.902934 -46.473872)
					(mid 145.910084 -46.512021)
					(end 145.94205 -46.53407)
				)
				(xy 146.066256 -46.560486) (xy 146.612864 -46.676818)
				(arc
					(start 146.73707 -46.703234)
					(mid 146.775397 -46.696196)
					(end 146.797522 -46.664118)
				)
				(arc
					(start 146.839686 -46.465236)
					(mid 146.832536 -46.427087)
					(end 146.80057 -46.405038)
				)
				(xy 146.676364 -46.378622)
			)
		)
	)
	(zone
		(layer "In2.Cu")
		(hatch none 0.5)
		(connect_pads
			(clearance 0)
		)
		(min_thickness 0.25)
		(keepout
			(tracks not_allowed)
			(vias allowed)
			(pads allowed)
			(copperpour not_allowed)
			(footprints allowed)
		)
		(placement
			(enabled no)
			(sheetname "")
		)
		(fill
			(thermal_gap 0.5)
			(thermal_bridge_width 0.5)
			(island_removal_mode 0)
		)
		(polygon
			(pts
				(arc
					(start 126.000256 -57.641998)
					(mid 125.641862 -58.000011)
					(end 126.000002 -58.358278)
				)
				(arc
					(start 127 -58.358278)
					(mid 127.354953 -58.047808)
					(end 127.094488 -57.654698)
				)
				(arc
					(start 126.73584 -57.654698)
					(mid 126.703958 -57.66104)
					(end 126.676912 -57.679082)
				)
				(arc
					(start 126.676912 -57.679082)
					(mid 126.658691 -57.706351)
					(end 126.652274 -57.738518)
				)
				(arc
					(start 126.652274 -57.911238)
					(mid 126.661573 -57.933689)
					(end 126.684024 -57.942988)
				)
				(arc
					(start 126.765558 -57.942988)
					(mid 127.241307 -58.000138)
					(end 126.765558 -58.057288)
				)
				(xy 126.660402 -58.057288)
				(arc
					(start 126.658116 -58.055002)
					(mid 126.58073 -58.014532)
					(end 126.54026 -57.937146)
				)
				(xy 126.537974 -57.93486) (xy 126.537974 -57.714896)
				(arc
					(start 126.539498 -57.713118)
					(mid 126.547934 -57.676439)
					(end 126.56312 -57.641998)
				)
				(arc
					(start 126.4793 -57.641998)
					(mid 126.466193 -57.689469)
					(end 126.461774 -57.738518)
				)
				(xy 126.461774 -57.93486)
				(arc
					(start 126.459488 -57.937146)
					(mid 126.419018 -58.014532)
					(end 126.341632 -58.055002)
				)
				(xy 126.339346 -58.057288)
				(arc
					(start 126.234444 -58.057288)
					(mid 125.758695 -58.000138)
					(end 126.234444 -57.942988)
				)
				(arc
					(start 126.315724 -57.942988)
					(mid 126.338175 -57.933689)
					(end 126.347474 -57.911238)
				)
				(xy 126.347474 -57.714896)
				(arc
					(start 126.348236 -57.714134)
					(mid 126.352264 -57.677799)
					(end 126.359666 -57.641998)
				)
			)
		)
	)
	(zone
		(layer "In2.Cu")
		(hatch none 0.5)
		(connect_pads
			(clearance 0)
		)
		(min_thickness 0.25)
		(keepout
			(tracks not_allowed)
			(vias allowed)
			(pads allowed)
			(copperpour not_allowed)
			(footprints allowed)
		)
		(placement
			(enabled no)
			(sheetname "")
		)
		(fill
			(thermal_gap 0.5)
			(thermal_bridge_width 0.5)
			(island_removal_mode 0)
		)
		(polygon
			(pts
				(xy 165.897052 -36.416488)
				(arc
					(start 166.056056 -36.575492)
					(mid 166.388347 -36.988555)
					(end 165.975284 -36.656264)
				)
				(xy 165.776148 -36.457128) (xy 165.251384 -36.457128) (xy 165.156134 -36.552378)
				(arc
					(start 165.107112 -36.552378)
					(mid 165.05202 -36.6387)
					(end 165.021768 -36.736528)
				)
				(arc
					(start 165.140894 -36.736528)
					(mid 165.666722 -36.800028)
					(end 165.140894 -36.863528)
				)
				(arc
					(start 165.021768 -36.863528)
					(mid 165.152265 -37.092794)
					(end 165.399974 -37.183568)
				)
				(arc
					(start 166.199566 -37.183568)
					(mid 166.58336 -36.800155)
					(end 166.19982 -36.416488)
				)
			)
		)
	)
	(zone
		(layer "In2.Cu")
		(hatch none 0.5)
		(connect_pads
			(clearance 0)
		)
		(min_thickness 0.25)
		(keepout
			(tracks not_allowed)
			(vias allowed)
			(pads allowed)
			(copperpour not_allowed)
			(footprints allowed)
		)
		(placement
			(enabled no)
			(sheetname "")
		)
		(fill
			(thermal_gap 0.5)
			(thermal_bridge_width 0.5)
			(island_removal_mode 0)
		)
		(polygon
			(pts
				(arc
					(start 126.000256 -58.641996)
					(mid 125.641862 -59.000009)
					(end 126.000002 -59.358276)
				)
				(arc
					(start 127 -59.358276)
					(mid 127.355457 -59.043895)
					(end 127.086868 -58.652664)
				)
				(arc
					(start 126.703582 -58.652664)
					(mid 126.683933 -58.656555)
					(end 126.66726 -58.66765)
				)
				(arc
					(start 126.66726 -58.66765)
					(mid 126.656179 -58.684329)
					(end 126.652274 -58.703972)
				)
				(arc
					(start 126.652274 -58.911236)
					(mid 126.661573 -58.933687)
					(end 126.684024 -58.942986)
				)
				(arc
					(start 126.765558 -58.942986)
					(mid 127.241307 -59.000136)
					(end 126.765558 -59.057286)
				)
				(xy 126.660402 -59.057286)
				(arc
					(start 126.658116 -59.055)
					(mid 126.58073 -59.01453)
					(end 126.54026 -58.937144)
				)
				(xy 126.537974 -58.934858) (xy 126.537974 -58.68035)
				(arc
					(start 126.540006 -58.678318)
					(mid 126.543922 -58.659874)
					(end 126.549912 -58.641996)
				)
				(arc
					(start 126.469648 -58.641996)
					(mid 126.463739 -58.672477)
					(end 126.461774 -58.703464)
				)
				(xy 126.461774 -58.934858)
				(arc
					(start 126.459488 -58.937144)
					(mid 126.419018 -59.01453)
					(end 126.341632 -59.055)
				)
				(xy 126.339346 -59.057286)
				(arc
					(start 126.234444 -59.057286)
					(mid 125.758695 -59.000136)
					(end 126.234444 -58.942986)
				)
				(arc
					(start 126.315724 -58.942986)
					(mid 126.338175 -58.933687)
					(end 126.347474 -58.911236)
				)
				(xy 126.347474 -58.68035)
				(arc
					(start 126.348236 -58.679588)
					(mid 126.35002 -58.660731)
					(end 126.352808 -58.641996)
				)
			)
		)
	)
	(zone
		(layer "In2.Cu")
		(hatch none 0.5)
		(connect_pads
			(clearance 0)
		)
		(min_thickness 0.25)
		(keepout
			(tracks not_allowed)
			(vias allowed)
			(pads allowed)
			(copperpour not_allowed)
			(footprints allowed)
		)
		(placement
			(enabled no)
			(sheetname "")
		)
		(fill
			(thermal_gap 0.5)
			(thermal_bridge_width 0.5)
			(island_removal_mode 0)
		)
		(polygon
			(pts
				(xy 148.389594 -44.04995)
				(arc
					(start 148.265388 -44.023534)
					(mid 148.227061 -44.030572)
					(end 148.204936 -44.06265)
				)
				(arc
					(start 148.162772 -44.261532)
					(mid 148.169922 -44.299681)
					(end 148.201888 -44.32173)
				)
				(xy 148.326094 -44.348146) (xy 148.872702 -44.464478)
				(arc
					(start 148.996908 -44.490894)
					(mid 149.035235 -44.483856)
					(end 149.05736 -44.451778)
				)
				(arc
					(start 149.099524 -44.252896)
					(mid 149.092374 -44.214747)
					(end 149.060408 -44.192698)
				)
				(xy 148.936202 -44.166282)
			)
		)
	)
	(zone
		(layer "In2.Cu")
		(hatch none 0.5)
		(connect_pads
			(clearance 0)
		)
		(min_thickness 0.25)
		(keepout
			(tracks not_allowed)
			(vias allowed)
			(pads allowed)
			(copperpour not_allowed)
			(footprints allowed)
		)
		(placement
			(enabled no)
			(sheetname "")
		)
		(fill
			(thermal_gap 0.5)
			(thermal_bridge_width 0.5)
			(island_removal_mode 0)
		)
		(polygon
			(pts
				(xy 165.897052 -34.016442)
				(arc
					(start 166.056056 -34.175446)
					(mid 166.388347 -34.588509)
					(end 165.975284 -34.256218)
				)
				(xy 165.776148 -34.057082)
				(arc
					(start 165.22827 -34.057082)
					(mid 165.170152 -34.092989)
					(end 165.119304 -34.138616)
				)
				(arc
					(start 165.202108 -34.221166)
					(mid 165.632801 -34.530653)
					(end 165.143942 -34.325052)
				)
				(arc
					(start 165.053772 -34.234628)
					(mid 165.075445 -34.604625)
					(end 165.399974 -34.783522)
				)
				(arc
					(start 166.199566 -34.783522)
					(mid 166.58336 -34.400109)
					(end 166.19982 -34.016442)
				)
			)
		)
	)
	(zone
		(net "GND")
		(layer "In2.Cu")
		(hatch none 0.5)
		(connect_pads
			(clearance 0.5)
		)
		(min_thickness 0.25)
		(fill yes
			(thermal_gap 0.5)
			(thermal_bridge_width 0.5)
			(island_removal_mode 0)
		)
		(polygon
			(pts
				(xy 86.614 -53.34) (xy 86.487 -53.467) (xy 86.487 -54.229) (xy 86.331298 -54.384702) (xy 84.721954 -54.384702)
				(xy 84.721954 -56.111394) (xy 84.813394 -56.111394) (xy 84.963 -56.261) (xy 84.963 -57.15) (xy 85.09 -57.277)
				(xy 85.471 -57.277) (xy 85.598 -57.15) (xy 85.598 -56.261) (xy 85.747606 -56.111394) (xy 87.352378 -56.111394)
				(xy 87.352378 -54.384702) (xy 87.277702 -54.384702) (xy 87.122 -54.229) (xy 87.122 -53.467) (xy 86.995 -53.34)
			)
		)
	)
	(zone
		(net "GB_VDDH")
		(layer "In2.Cu")
		(hatch none 0.5)
		(connect_pads
			(clearance 0.5)
		)
		(min_thickness 0.25)
		(fill yes
			(thermal_gap 0.5)
			(thermal_bridge_width 0.5)
			(island_removal_mode 0)
		)
		(polygon
			(pts
				(xy 126.290578 -72.616822) (xy 128.882902 -75.209146) (xy 139.691618 -75.209146) (xy 139.700508 -75.218036)
				(xy 140.736828 -75.218036) (xy 142.631922 -77.11313) (xy 146.385534 -77.11313) (xy 147.47367 -77.11313)
				(xy 147.6756 -76.9112) (xy 147.6756 -66.7512) (xy 147.205192 -66.280792) (xy 146.270726 -66.280792)
				(xy 135.04799 -66.280792) (xy 131.8514 -63.084202) (xy 131.8514 -61.8744) (xy 131.318 -61.341) (xy 130.093212 -61.341)
				(xy 109.7534 -61.341) (xy 109.397292 -61.697108) (xy 109.397292 -62.133988) (xy 109.397292 -69.577458)
				(xy 111.0742 -71.254366) (xy 111.3028 -71.254366) (xy 111.727234 -71.6788) (xy 124.968 -71.6788)
				(xy 125.906022 -72.616822)
			)
		)
	)
	(zone
		(layer "In2.Cu")
		(hatch none 0.5)
		(connect_pads
			(clearance 0)
		)
		(min_thickness 0.25)
		(keepout
			(tracks not_allowed)
			(vias allowed)
			(pads allowed)
			(copperpour not_allowed)
			(footprints allowed)
		)
		(placement
			(enabled no)
			(sheetname "")
		)
		(fill
			(thermal_gap 0.5)
			(thermal_bridge_width 0.5)
			(island_removal_mode 0)
		)
		(polygon
			(pts
				(arc
					(start 151.676862 -38.098476)
					(mid 151.332298 -37.547107)
					(end 150.784814 -37.89807)
				)
				(arc
					(start 150.54707 -39.016178)
					(mid 150.899368 -39.558468)
					(end 151.441658 -39.20617)
				)
				(xy 151.515572 -38.858444) (xy 151.199342 -38.791388) (xy 151.19223 -38.789864)
				(arc
					(start 151.183594 -38.788086)
					(mid 151.170148 -38.788583)
					(end 151.157686 -38.793674)
				)
				(arc
					(start 151.144986 -38.802056)
					(mid 151.126127 -38.820824)
					(end 151.115522 -38.845236)
				)
				(arc
					(start 151.110188 -38.87089)
					(mid 150.939569 -39.372062)
					(end 150.985982 -38.844728)
				)
				(xy 150.996904 -38.793166)
				(arc
					(start 150.999444 -38.791388)
					(mid 151.021921 -38.748215)
					(end 151.054308 -38.711886)
				)
				(xy 151.054816 -38.709346) (xy 151.074628 -38.696392) (xy 151.076914 -38.694868) (xy 151.109934 -38.673024)
				(arc
					(start 151.11349 -38.673786)
					(mid 151.155494 -38.66213)
					(end 151.199088 -38.661848)
				)
				(xy 151.19985 -38.661594) (xy 151.207216 -38.663118) (xy 151.212804 -38.664388) (xy 151.214074 -38.664642)
				(xy 151.219154 -38.665658) (xy 151.225504 -38.666928) (xy 151.541988 -38.734238) (xy 151.556212 -38.666928)
				(xy 151.578818 -38.560248) (xy 151.262588 -38.493192) (xy 151.236934 -38.487604)
				(arc
					(start 151.235156 -38.485064)
					(mid 151.180514 -38.454139)
					(end 151.138382 -38.407594)
				)
				(arc
					(start 151.138382 -38.407594)
					(mid 151.112889 -38.349815)
					(end 151.106886 -38.286944)
				)
				(xy 151.105362 -38.284404) (xy 151.110696 -38.25875)
				(arc
					(start 151.116284 -38.23335)
					(mid 151.286903 -37.732178)
					(end 151.24049 -38.259512)
				)
				(arc
					(start 151.235156 -38.285166)
					(mid 151.234795 -38.312821)
					(end 151.245062 -38.338506)
				)
				(arc
					(start 151.245062 -38.338506)
					(mid 151.264022 -38.358083)
					(end 151.289004 -38.368986)
				)
				(xy 151.605234 -38.436042)
			)
		)
	)
	(zone
		(layer "In2.Cu")
		(hatch none 0.5)
		(connect_pads
			(clearance 0)
		)
		(min_thickness 0.25)
		(keepout
			(tracks not_allowed)
			(vias allowed)
			(pads allowed)
			(copperpour not_allowed)
			(footprints allowed)
		)
		(placement
			(enabled no)
			(sheetname "")
		)
		(fill
			(thermal_gap 0.5)
			(thermal_bridge_width 0.5)
			(island_removal_mode 0)
		)
		(polygon
			(pts
				(arc
					(start 150.087584 -54.478174)
					(mid 149.735286 -53.935884)
					(end 149.192996 -54.288182)
				)
				(arc
					(start 148.957792 -55.395876)
					(mid 149.302356 -55.947245)
					(end 149.84984 -55.596282)
				)
				(xy 149.923754 -55.248302)
				(arc
					(start 149.594316 -55.178452)
					(mid 149.579581 -55.178352)
					(end 149.565868 -55.183786)
				)
				(arc
					(start 149.553168 -55.192168)
					(mid 149.534309 -55.210936)
					(end 149.523704 -55.235348)
				)
				(arc
					(start 149.51837 -55.261002)
					(mid 149.347751 -55.762174)
					(end 149.394164 -55.23484)
				)
				(xy 149.405086 -55.183278)
				(arc
					(start 149.407626 -55.1815)
					(mid 149.430103 -55.138327)
					(end 149.46249 -55.101998)
				)
				(xy 149.462998 -55.099458) (xy 149.48281 -55.086504) (xy 149.485096 -55.08498) (xy 149.518116 -55.063136)
				(arc
					(start 149.521672 -55.063898)
					(mid 149.556264 -55.053516)
					(end 149.592284 -55.050944)
				)
				(xy 149.595332 -55.048912) (xy 149.620732 -55.054246) (xy 149.620986 -55.054246) (xy 149.95017 -55.124096)
				(xy 149.987254 -54.950106) (xy 149.640544 -54.876446)
				(arc
					(start 149.638258 -54.873144)
					(mid 149.586747 -54.84259)
					(end 149.546818 -54.79796)
				)
				(arc
					(start 149.546564 -54.797706)
					(mid 149.521071 -54.739927)
					(end 149.515068 -54.677056)
				)
				(xy 149.513544 -54.674516) (xy 149.518878 -54.648862)
				(arc
					(start 149.524466 -54.623462)
					(mid 149.695085 -54.12229)
					(end 149.648672 -54.649624)
				)
				(arc
					(start 149.643338 -54.675278)
					(mid 149.64287 -54.702902)
					(end 149.65299 -54.728618)
				)
				(arc
					(start 149.65299 -54.728618)
					(mid 149.6707 -54.747147)
					(end 149.693884 -54.758082)
				)
				(xy 150.01367 -54.8259)
			)
		)
	)
	(zone
		(layer "In2.Cu")
		(hatch none 0.5)
		(connect_pads
			(clearance 0)
		)
		(min_thickness 0.25)
		(keepout
			(tracks not_allowed)
			(vias allowed)
			(pads allowed)
			(copperpour not_allowed)
			(footprints allowed)
		)
		(placement
			(enabled no)
			(sheetname "")
		)
		(fill
			(thermal_gap 0.5)
			(thermal_bridge_width 0.5)
			(island_removal_mode 0)
		)
		(polygon
			(pts
				(arc
					(start 147.989544 -46.551596)
					(mid 147.64498 -46.000227)
					(end 147.097496 -46.35119)
				)
				(arc
					(start 146.859752 -47.469298)
					(mid 147.21205 -48.011588)
					(end 147.75434 -47.65929)
				)
				(xy 147.828254 -47.311818) (xy 147.512024 -47.244508) (xy 147.504658 -47.242984)
				(arc
					(start 147.496276 -47.241206)
					(mid 147.48283 -47.241703)
					(end 147.470368 -47.246794)
				)
				(arc
					(start 147.457668 -47.255176)
					(mid 147.438809 -47.273944)
					(end 147.428204 -47.298356)
				)
				(arc
					(start 147.42287 -47.32401)
					(mid 147.252251 -47.825182)
					(end 147.298664 -47.297848)
				)
				(xy 147.309586 -47.246286)
				(arc
					(start 147.312126 -47.244508)
					(mid 147.334603 -47.201335)
					(end 147.36699 -47.165006)
				)
				(xy 147.367498 -47.162466) (xy 147.38731 -47.149512) (xy 147.389596 -47.147988) (xy 147.422616 -47.126144)
				(arc
					(start 147.426172 -47.126906)
					(mid 147.468301 -47.115232)
					(end 147.512024 -47.114968)
				)
				(xy 147.512532 -47.114714) (xy 147.520152 -47.116238) (xy 147.525486 -47.117508) (xy 147.526756 -47.117762)
				(xy 147.531582 -47.118778) (xy 147.538186 -47.120048) (xy 147.85467 -47.187358) (xy 147.868894 -47.120048)
				(xy 147.8915 -47.013368) (xy 147.549616 -46.940724)
				(arc
					(start 147.547838 -46.938184)
					(mid 147.493196 -46.907259)
					(end 147.451064 -46.860714)
				)
				(arc
					(start 147.451064 -46.860714)
					(mid 147.425571 -46.802935)
					(end 147.419568 -46.740064)
				)
				(xy 147.418044 -46.737524) (xy 147.423378 -46.71187)
				(arc
					(start 147.428966 -46.68647)
					(mid 147.599585 -46.185298)
					(end 147.553172 -46.712632)
				)
				(arc
					(start 147.547838 -46.738286)
					(mid 147.547477 -46.765941)
					(end 147.557744 -46.791626)
				)
				(arc
					(start 147.557744 -46.791626)
					(mid 147.576704 -46.811203)
					(end 147.601686 -46.822106)
				)
				(xy 147.917916 -46.889162)
			)
		)
	)
	(zone
		(layer "In2.Cu")
		(hatch none 0.5)
		(connect_pads
			(clearance 0)
		)
		(min_thickness 0.25)
		(keepout
			(tracks not_allowed)
			(vias allowed)
			(pads allowed)
			(copperpour not_allowed)
			(footprints allowed)
		)
		(placement
			(enabled no)
			(sheetname "")
		)
		(fill
			(thermal_gap 0.5)
			(thermal_bridge_width 0.5)
			(island_removal_mode 0)
		)
		(polygon
			(pts
				(arc
					(start 138.739118 -64.517524)
					(mid 138.284458 -64.972184)
					(end 138.739118 -65.426844)
				)
				(arc
					(start 139.881864 -65.426844)
					(mid 140.336778 -64.972311)
					(end 139.882118 -64.517524)
				)
				(xy 139.524486 -64.517524) (xy 139.52601 -64.539368) (xy 139.526518 -64.539876)
				(arc
					(start 139.526518 -64.80429)
					(mid 139.534514 -64.844308)
					(end 139.557252 -64.878204)
				)
				(arc
					(start 139.557252 -64.878204)
					(mid 139.587421 -64.899258)
					(end 139.623038 -64.90843)
				)
				(arc
					(start 139.623038 -64.90843)
					(mid 140.148927 -64.972307)
					(end 139.623038 -65.035684)
				)
				(xy 139.604242 -65.035684)
				(arc
					(start 139.602718 -65.033906)
					(mid 139.529502 -65.012372)
					(end 139.467336 -64.96812)
				)
				(arc
					(start 139.467336 -64.96812)
					(mid 139.422929 -64.905711)
					(end 139.401296 -64.83223)
				)
				(xy 139.399518 -64.830706)
				(arc
					(start 139.399518 -64.566292)
					(mid 139.398893 -64.541875)
					(end 139.396978 -64.517524)
				)
				(xy 139.2174 -64.517524) (xy 139.220448 -64.538606) (xy 139.221718 -64.539876) (xy 139.221718 -64.81445)
				(arc
					(start 139.220194 -64.815974)
					(mid 139.202959 -64.882599)
					(end 139.168124 -64.941958)
				)
				(xy 139.168124 -64.944498) (xy 139.130786 -64.981836)
				(arc
					(start 139.1285 -64.981836)
					(mid 139.06881 -65.01691)
					(end 139.001754 -65.03416)
				)
				(xy 139.00023 -65.035684)
				(arc
					(start 138.998198 -65.035684)
					(mid 138.472372 -64.973354)
					(end 138.99769 -64.906398)
				)
				(arc
					(start 138.99769 -64.906398)
					(mid 139.031015 -64.894482)
					(end 139.059412 -64.873378)
				)
				(arc
					(start 139.059666 -64.873378)
					(mid 139.085616 -64.834166)
					(end 139.094718 -64.788034)
				)
				(arc
					(start 139.094718 -64.566292)
					(mid 139.092751 -64.541591)
					(end 139.086844 -64.517524)
				)
			)
		)
	)
	(zone
		(layer "In2.Cu")
		(hatch none 0.5)
		(connect_pads
			(clearance 0)
		)
		(min_thickness 0.25)
		(keepout
			(tracks not_allowed)
			(vias allowed)
			(pads allowed)
			(copperpour not_allowed)
			(footprints allowed)
		)
		(placement
			(enabled no)
			(sheetname "")
		)
		(fill
			(thermal_gap 0.5)
			(thermal_bridge_width 0.5)
			(island_removal_mode 0)
		)
		(polygon
			(pts
				(xy 166.697152 -31.616396)
				(arc
					(start 166.856156 -31.7754)
					(mid 167.188447 -32.188463)
					(end 166.775384 -31.856172)
				)
				(xy 166.576248 -31.657036)
				(arc
					(start 166.02837 -31.657036)
					(mid 165.908772 -31.750525)
					(end 165.834822 -31.883096)
				)
				(arc
					(start 165.960298 -31.883096)
					(mid 166.459689 -32.061127)
					(end 165.933374 -31.997396)
				)
				(arc
					(start 165.816534 -31.997396)
					(mid 165.927968 -32.270246)
					(end 166.200074 -32.383476)
				)
				(arc
					(start 166.999666 -32.383476)
					(mid 167.38346 -32.000063)
					(end 166.99992 -31.616396)
				)
			)
		)
	)
	(zone
		(layer "In2.Cu")
		(hatch none 0.5)
		(connect_pads
			(clearance 0)
		)
		(min_thickness 0.25)
		(keepout
			(tracks not_allowed)
			(vias allowed)
			(pads allowed)
			(copperpour not_allowed)
			(footprints allowed)
		)
		(placement
			(enabled no)
			(sheetname "")
		)
		(fill
			(thermal_gap 0.5)
			(thermal_bridge_width 0.5)
			(island_removal_mode 0)
		)
		(polygon
			(pts
				(arc
					(start 126.000256 -56.642)
					(mid 125.641862 -57.000013)
					(end 126.000002 -57.35828)
				)
				(arc
					(start 127 -57.35828)
					(mid 127.355841 -57.040656)
					(end 127.080518 -56.651144)
				)
				(arc
					(start 126.695454 -56.651144)
					(mid 126.683373 -56.653512)
					(end 126.673102 -56.660288)
				)
				(xy 126.672594 -56.660796) (xy 126.66726 -56.66613)
				(arc
					(start 126.667006 -56.666384)
					(mid 126.656129 -56.682712)
					(end 126.652274 -56.701944)
				)
				(arc
					(start 126.652274 -56.91124)
					(mid 126.661573 -56.933691)
					(end 126.684024 -56.94299)
				)
				(arc
					(start 126.765558 -56.94299)
					(mid 127.241307 -57.00014)
					(end 126.765558 -57.05729)
				)
				(xy 126.660402 -57.05729)
				(arc
					(start 126.658116 -57.055004)
					(mid 126.58073 -57.014534)
					(end 126.54026 -56.937148)
				)
				(xy 126.537974 -56.934862) (xy 126.537974 -56.678322)
				(arc
					(start 126.540006 -56.67629)
					(mid 126.54377 -56.658888)
					(end 126.549404 -56.642)
				)
				(arc
					(start 126.469394 -56.642)
					(mid 126.463712 -56.671606)
					(end 126.461774 -56.70169)
				)
				(xy 126.461774 -56.934862)
				(arc
					(start 126.459488 -56.937148)
					(mid 126.419018 -57.014534)
					(end 126.341632 -57.055004)
				)
				(xy 126.339346 -57.05729)
				(arc
					(start 126.234444 -57.05729)
					(mid 125.758695 -57.00014)
					(end 126.234444 -56.94299)
				)
				(arc
					(start 126.315724 -56.94299)
					(mid 126.338175 -56.933691)
					(end 126.347474 -56.91124)
				)
				(xy 126.347474 -56.678068) (xy 126.348236 -56.677052) (xy 126.352554 -56.642)
			)
		)
	)
	(zone
		(layer "In2.Cu")
		(hatch none 0.5)
		(connect_pads
			(clearance 0)
		)
		(min_thickness 0.25)
		(keepout
			(tracks not_allowed)
			(vias allowed)
			(pads allowed)
			(copperpour not_allowed)
			(footprints allowed)
		)
		(placement
			(enabled no)
			(sheetname "")
		)
		(fill
			(thermal_gap 0.5)
			(thermal_bridge_width 0.5)
			(island_removal_mode 0)
		)
		(polygon
			(pts
				(xy 147.197064 -50.260758)
				(arc
					(start 147.072858 -50.234342)
					(mid 147.034531 -50.24138)
					(end 147.012406 -50.273458)
				)
				(arc
					(start 146.970242 -50.47234)
					(mid 146.977392 -50.510489)
					(end 147.009358 -50.532538)
				)
				(xy 147.133564 -50.558954) (xy 147.680172 -50.675286)
				(arc
					(start 147.804378 -50.701702)
					(mid 147.842705 -50.694664)
					(end 147.86483 -50.662586)
				)
				(arc
					(start 147.906994 -50.463704)
					(mid 147.899844 -50.425555)
					(end 147.867878 -50.403506)
				)
				(xy 147.743672 -50.37709)
			)
		)
	)
	(zone
		(layer "In2.Cu")
		(hatch none 0.5)
		(connect_pads
			(clearance 0)
		)
		(min_thickness 0.25)
		(keepout
			(tracks not_allowed)
			(vias allowed)
			(pads allowed)
			(copperpour not_allowed)
			(footprints allowed)
		)
		(placement
			(enabled no)
			(sheetname "")
		)
		(fill
			(thermal_gap 0.5)
			(thermal_bridge_width 0.5)
			(island_removal_mode 0)
		)
		(polygon
			(pts
				(arc
					(start 125.139958 -45.858938)
					(mid 124.682758 -45.401738)
					(end 124.225558 -45.858938)
				)
				(arc
					(start 124.225558 -47.001684)
					(mid 124.682631 -47.459138)
					(end 125.139958 -47.001938)
				)
				(xy 125.139958 -46.647608) (xy 125.11532 -46.646338)
				(arc
					(start 124.803408 -46.646338)
					(mid 124.788994 -46.64917)
					(end 124.776738 -46.65726)
				)
				(arc
					(start 124.766832 -46.66742)
					(mid 124.751668 -46.690026)
					(end 124.746258 -46.716696)
				)
				(arc
					(start 124.746258 -46.742858)
					(mid 124.682758 -47.268686)
					(end 124.619258 -46.742858)
				)
				(xy 124.619258 -46.69028)
				(arc
					(start 124.62129 -46.688248)
					(mid 124.634381 -46.641214)
					(end 124.658628 -46.59884)
				)
				(xy 124.658628 -46.595792) (xy 124.676916 -46.577758) (xy 124.67717 -46.57725) (xy 124.686568 -46.567852)
				(xy 124.687076 -46.567344) (xy 124.70511 -46.54931)
				(arc
					(start 124.708666 -46.54931)
					(mid 124.74006 -46.531996)
					(end 124.774452 -46.521878)
				)
				(xy 124.776992 -46.519338) (xy 125.139958 -46.519338) (xy 125.139958 -46.342046) (xy 125.11532 -46.341538)
				(xy 124.7902 -46.341538)
				(arc
					(start 124.788168 -46.339506)
					(mid 124.728197 -46.320629)
					(end 124.67717 -46.28388)
				)
				(arc
					(start 124.67717 -46.28388)
					(mid 124.640199 -46.232649)
					(end 124.62129 -46.172374)
				)
				(xy 124.619258 -46.170342)
				(arc
					(start 124.619258 -46.118018)
					(mid 124.682758 -45.59219)
					(end 124.746258 -46.118018)
				)
				(arc
					(start 124.746258 -46.143926)
					(mid 124.751667 -46.171031)
					(end 124.767086 -46.193964)
				)
				(arc
					(start 124.767086 -46.193964)
					(mid 124.789796 -46.209202)
					(end 124.816616 -46.214538)
				)
				(xy 125.139958 -46.214538)
			)
		)
	)
	(zone
		(layer "In2.Cu")
		(hatch none 0.5)
		(connect_pads
			(clearance 0)
		)
		(min_thickness 0.25)
		(keepout
			(tracks not_allowed)
			(vias allowed)
			(pads allowed)
			(copperpour not_allowed)
			(footprints allowed)
		)
		(placement
			(enabled no)
			(sheetname "")
		)
		(fill
			(thermal_gap 0.5)
			(thermal_bridge_width 0.5)
			(island_removal_mode 0)
		)
		(polygon
			(pts
				(xy 148.073618 -54.790086)
				(arc
					(start 147.949412 -54.76367)
					(mid 147.911085 -54.770708)
					(end 147.88896 -54.802786)
				)
				(arc
					(start 147.846796 -55.001668)
					(mid 147.853946 -55.039817)
					(end 147.885912 -55.061866)
				)
				(xy 148.010118 -55.088282) (xy 148.556726 -55.204614)
				(arc
					(start 148.680932 -55.23103)
					(mid 148.719259 -55.223992)
					(end 148.741384 -55.191914)
				)
				(arc
					(start 148.783548 -54.993032)
					(mid 148.776398 -54.954883)
					(end 148.744432 -54.932834)
				)
				(xy 148.620226 -54.906418)
			)
		)
	)
	(zone
		(layer "In2.Cu")
		(hatch none 0.5)
		(connect_pads
			(clearance 0)
		)
		(min_thickness 0.25)
		(keepout
			(tracks not_allowed)
			(vias allowed)
			(pads allowed)
			(copperpour not_allowed)
			(footprints allowed)
		)
		(placement
			(enabled no)
			(sheetname "")
		)
		(fill
			(thermal_gap 0.5)
			(thermal_bridge_width 0.5)
			(island_removal_mode 0)
		)
		(polygon
			(pts
				(arc
					(start 127.000254 -52.642008)
					(mid 126.64186 -53.000021)
					(end 127 -53.358288)
				)
				(arc
					(start 127.999998 -53.358288)
					(mid 128.358138 -53.000148)
					(end 127.999998 -52.642008)
				)
				(xy 127.652272 -52.642008)
				(arc
					(start 127.652272 -52.911248)
					(mid 127.661571 -52.933699)
					(end 127.684022 -52.942998)
				)
				(arc
					(start 127.765556 -52.942998)
					(mid 128.241305 -53.000148)
					(end 127.765556 -53.057298)
				)
				(xy 127.6604 -53.057298)
				(arc
					(start 127.658114 -53.055012)
					(mid 127.580728 -53.014542)
					(end 127.540258 -52.937156)
				)
				(xy 127.537972 -52.93487) (xy 127.537972 -52.642008) (xy 127.461772 -52.642008) (xy 127.461772 -52.93487)
				(arc
					(start 127.459486 -52.937156)
					(mid 127.419016 -53.014542)
					(end 127.34163 -53.055012)
				)
				(xy 127.339344 -53.057298)
				(arc
					(start 127.234442 -53.057298)
					(mid 126.758693 -53.000148)
					(end 127.234442 -52.942998)
				)
				(arc
					(start 127.315722 -52.942998)
					(mid 127.338173 -52.933699)
					(end 127.347472 -52.911248)
				)
				(xy 127.347472 -52.642008)
			)
		)
	)
	(zone
		(layer "In2.Cu")
		(hatch none 0.5)
		(connect_pads
			(clearance 0)
		)
		(min_thickness 0.25)
		(keepout
			(tracks not_allowed)
			(vias allowed)
			(pads allowed)
			(copperpour not_allowed)
			(footprints allowed)
		)
		(placement
			(enabled no)
			(sheetname "")
		)
		(fill
			(thermal_gap 0.5)
			(thermal_bridge_width 0.5)
			(island_removal_mode 0)
		)
		(polygon
			(pts
				(arc
					(start 166.58336 -35.200082)
					(mid 166.199947 -34.816288)
					(end 165.81628 -35.199828)
				)
				(xy 165.81628 -35.29711) (xy 165.90899 -35.38982)
				(arc
					(start 166.012622 -35.38982)
					(mid 166.288617 -34.948322)
					(end 166.226236 -35.465258)
				)
				(arc
					(start 166.226236 -35.465258)
					(mid 166.187739 -35.496718)
					(end 166.141146 -35.514026)
				)
				(xy 166.138352 -35.51682) (xy 165.90899 -35.51682) (xy 165.856158 -35.51682) (xy 165.819074 -35.479736)
				(xy 165.81628 -35.476942) (xy 165.81628 -35.69462) (xy 166.103808 -35.69462)
				(arc
					(start 166.10584 -35.696906)
					(mid 166.1507 -35.709806)
					(end 166.19093 -35.733482)
				)
				(arc
					(start 166.19093 -35.733482)
					(mid 166.311954 -36.241665)
					(end 166.001446 -35.82162)
				)
				(xy 165.81628 -35.82162)
				(arc
					(start 165.81628 -35.999928)
					(mid 166.19982 -36.383468)
					(end 166.58336 -35.999928)
				)
			)
		)
	)
	(zone
		(layer "In2.Cu")
		(hatch none 0.5)
		(connect_pads
			(clearance 0)
		)
		(min_thickness 0.25)
		(keepout
			(tracks not_allowed)
			(vias allowed)
			(pads allowed)
			(copperpour not_allowed)
			(footprints allowed)
		)
		(placement
			(enabled no)
			(sheetname "")
		)
		(fill
			(thermal_gap 0.5)
			(thermal_bridge_width 0.5)
			(island_removal_mode 0)
		)
		(polygon
			(pts
				(xy 146.871182 -32.921956) (xy 146.554952 -32.8549) (xy 146.529298 -32.849312)
				(arc
					(start 146.52752 -32.846772)
					(mid 146.472878 -32.815847)
					(end 146.430746 -32.769302)
				)
				(arc
					(start 146.430746 -32.769302)
					(mid 146.405253 -32.711523)
					(end 146.39925 -32.648652)
				)
				(xy 146.397726 -32.646112) (xy 146.40306 -32.620458)
				(arc
					(start 146.408648 -32.595058)
					(mid 146.579267 -32.093886)
					(end 146.532854 -32.62122)
				)
				(arc
					(start 146.52752 -32.646874)
					(mid 146.527159 -32.674529)
					(end 146.537426 -32.700214)
				)
				(arc
					(start 146.537426 -32.700214)
					(mid 146.556386 -32.719791)
					(end 146.581368 -32.730694)
				)
				(xy 146.897598 -32.79775)
				(arc
					(start 146.969226 -32.460184)
					(mid 146.624662 -31.908815)
					(end 146.077178 -32.259778)
				)
				(arc
					(start 145.839434 -33.377886)
					(mid 146.191732 -33.920176)
					(end 146.734022 -33.567878)
				)
				(xy 146.807936 -33.220152)
				(arc
					(start 146.478498 -33.150048)
					(mid 146.463763 -33.149948)
					(end 146.45005 -33.155382)
				)
				(arc
					(start 146.43735 -33.163764)
					(mid 146.418491 -33.182532)
					(end 146.407886 -33.206944)
				)
				(arc
					(start 146.402552 -33.232598)
					(mid 146.231933 -33.73377)
					(end 146.278346 -33.206436)
				)
				(xy 146.289268 -33.154874)
				(arc
					(start 146.291808 -33.153096)
					(mid 146.314285 -33.109923)
					(end 146.346672 -33.073594)
				)
				(xy 146.34718 -33.071054) (xy 146.366992 -33.0581) (xy 146.369278 -33.056576) (xy 146.402298 -33.034732)
				(arc
					(start 146.405854 -33.035494)
					(mid 146.440446 -33.025112)
					(end 146.476466 -33.02254)
				)
				(xy 146.479514 -33.020508) (xy 146.504914 -33.025842) (xy 146.505168 -33.025842) (xy 146.834352 -33.095946)
			)
		)
	)
	(zone
		(layer "In2.Cu")
		(hatch none 0.5)
		(connect_pads
			(clearance 0)
		)
		(min_thickness 0.25)
		(keepout
			(tracks allowed)
			(vias allowed)
			(pads allowed)
			(copperpour allowed)
			(footprints allowed)
		)
		(placement
			(enabled no)
			(sheetname "")
		)
		(fill
			(thermal_gap 0.5)
			(thermal_bridge_width 0.5)
			(island_removal_mode 0)
		)
		(polygon
			(pts
				(xy 108.980732 -8.76173) (xy 108.00715 -8.76173) (xy 108.00715 -13.204444) (xy 108.980732 -13.204444)
			)
		)
	)
	(zone
		(net "GND")
		(layer "In2.Cu")
		(hatch none 0.5)
		(connect_pads
			(clearance 0.5)
		)
		(min_thickness 0.25)
		(fill yes
			(thermal_gap 0.5)
			(thermal_bridge_width 0.5)
			(island_removal_mode 0)
		)
		(polygon
			(pts
				(xy 158.017464 -43.508422) (xy 158.017464 -43.658536) (xy 157.988 -43.688) (xy 156.845 -43.688)
				(xy 156.718 -43.815) (xy 156.718 -44.196) (xy 156.845 -44.323) (xy 157.988 -44.323) (xy 158.017464 -44.352464)
				(xy 158.017464 -46.138846) (xy 158.914846 -46.138846) (xy 159.004 -46.228) (xy 159.004 -47.244)
				(xy 159.131 -47.371) (xy 159.512 -47.371) (xy 159.639 -47.244) (xy 159.639 -46.2026) (xy 159.702754 -46.138846)
				(xy 159.744156 -46.138846) (xy 159.744156 -43.508422)
			)
		)
	)
	(zone
		(net "P3V3")
		(layer "In2.Cu")
		(hatch none 0.5)
		(connect_pads
			(clearance 0.5)
		)
		(min_thickness 0.25)
		(fill yes
			(thermal_gap 0.5)
			(thermal_bridge_width 0.5)
			(island_removal_mode 0)
		)
		(polygon
			(pts
				(xy 158.008574 -80.5434) (xy 160.401 -80.5434) (xy 172.8724 -68.072) (xy 172.8724 -63.7794) (xy 170.3832 -61.2902)
				(xy 166.4208 -61.2902) (xy 164.2618 -63.4492) (xy 157.8356 -69.8754) (xy 157.8356 -74.8284) (xy 157.8356 -80.370426)
			)
		)
	)
	(zone
		(layer "In2.Cu")
		(hatch none 0.5)
		(connect_pads
			(clearance 0)
		)
		(min_thickness 0.25)
		(keepout
			(tracks not_allowed)
			(vias allowed)
			(pads allowed)
			(copperpour not_allowed)
			(footprints allowed)
		)
		(placement
			(enabled no)
			(sheetname "")
		)
		(fill
			(thermal_gap 0.5)
			(thermal_bridge_width 0.5)
			(island_removal_mode 0)
		)
		(polygon
			(pts
				(arc
					(start 126.000256 -59.641994)
					(mid 125.641862 -60.000007)
					(end 126.000002 -60.358274)
				)
				(arc
					(start 127 -60.358274)
					(mid 127.355457 -60.043893)
					(end 127.086868 -59.652662)
				)
				(arc
					(start 126.685294 -59.652662)
					(mid 126.672658 -59.655175)
					(end 126.661926 -59.662314)
				)
				(arc
					(start 126.661926 -59.662314)
					(mid 126.654762 -59.673035)
					(end 126.652274 -59.685682)
				)
				(arc
					(start 126.652274 -59.911234)
					(mid 126.661573 -59.933685)
					(end 126.684024 -59.942984)
				)
				(arc
					(start 126.765558 -59.942984)
					(mid 127.241307 -60.000134)
					(end 126.765558 -60.057284)
				)
				(xy 126.660402 -60.057284)
				(arc
					(start 126.658116 -60.054998)
					(mid 126.58073 -60.014528)
					(end 126.54026 -59.937142)
				)
				(xy 126.537974 -59.934856) (xy 126.537974 -59.66206) (xy 126.54026 -59.659774) (xy 126.544578 -59.641994)
				(arc
					(start 126.466092 -59.641994)
					(mid 126.462886 -59.663479)
					(end 126.461774 -59.685174)
				)
				(xy 126.461774 -59.934856)
				(arc
					(start 126.459488 -59.937142)
					(mid 126.419018 -60.014528)
					(end 126.341632 -60.054998)
				)
				(xy 126.339346 -60.057284)
				(arc
					(start 126.234444 -60.057284)
					(mid 125.758695 -60.000134)
					(end 126.234444 -59.942984)
				)
				(arc
					(start 126.315724 -59.942984)
					(mid 126.338175 -59.933685)
					(end 126.347474 -59.911234)
				)
				(xy 126.347474 -59.66206) (xy 126.348236 -59.661044) (xy 126.350268 -59.641994)
			)
		)
	)
	(zone
		(layer "In2.Cu")
		(hatch none 0.5)
		(connect_pads
			(clearance 0)
		)
		(min_thickness 0.25)
		(keepout
			(tracks not_allowed)
			(vias allowed)
			(pads allowed)
			(copperpour not_allowed)
			(footprints allowed)
		)
		(placement
			(enabled no)
			(sheetname "")
		)
		(fill
			(thermal_gap 0.5)
			(thermal_bridge_width 0.5)
			(island_removal_mode 0)
		)
		(polygon
			(pts
				(arc
					(start 150.230078 -44.309284)
					(mid 149.885514 -43.757915)
					(end 149.33803 -44.108878)
				)
				(arc
					(start 149.100286 -45.226986)
					(mid 149.452584 -45.769276)
					(end 149.994874 -45.416978)
				)
				(xy 150.068788 -45.069252) (xy 149.752558 -45.002196) (xy 149.745446 -45.000672)
				(arc
					(start 149.73681 -44.998894)
					(mid 149.723364 -44.999391)
					(end 149.710902 -45.004482)
				)
				(arc
					(start 149.698202 -45.012864)
					(mid 149.679343 -45.031632)
					(end 149.668738 -45.056044)
				)
				(arc
					(start 149.663404 -45.081698)
					(mid 149.492785 -45.58287)
					(end 149.539198 -45.055536)
				)
				(xy 149.55012 -45.003974)
				(arc
					(start 149.55266 -45.002196)
					(mid 149.575137 -44.959023)
					(end 149.607524 -44.922694)
				)
				(xy 149.608032 -44.920154) (xy 149.627844 -44.9072) (xy 149.63013 -44.905676) (xy 149.66315 -44.883832)
				(arc
					(start 149.666706 -44.884594)
					(mid 149.70871 -44.872938)
					(end 149.752304 -44.872656)
				)
				(xy 149.753066 -44.872402) (xy 149.760432 -44.873926) (xy 149.76602 -44.875196) (xy 149.76729 -44.87545)
				(xy 149.77237 -44.876466) (xy 149.77872 -44.877736) (xy 150.095204 -44.945046) (xy 150.109428 -44.877736)
				(xy 150.132034 -44.771056) (xy 149.815804 -44.704) (xy 149.79015 -44.698412)
				(arc
					(start 149.788372 -44.695872)
					(mid 149.73373 -44.664947)
					(end 149.691598 -44.618402)
				)
				(arc
					(start 149.691598 -44.618402)
					(mid 149.666105 -44.560623)
					(end 149.660102 -44.497752)
				)
				(xy 149.658578 -44.495212) (xy 149.663912 -44.469558)
				(arc
					(start 149.6695 -44.444158)
					(mid 149.840119 -43.942986)
					(end 149.793706 -44.47032)
				)
				(arc
					(start 149.788372 -44.495974)
					(mid 149.788011 -44.523629)
					(end 149.798278 -44.549314)
				)
				(arc
					(start 149.798278 -44.549314)
					(mid 149.817238 -44.568891)
					(end 149.84222 -44.579794)
				)
				(xy 150.15845 -44.64685)
			)
		)
	)
	(zone
		(layer "In2.Cu")
		(hatch none 0.5)
		(connect_pads
			(clearance 0)
		)
		(min_thickness 0.25)
		(keepout
			(tracks not_allowed)
			(vias allowed)
			(pads allowed)
			(copperpour not_allowed)
			(footprints allowed)
		)
		(placement
			(enabled no)
			(sheetname "")
		)
		(fill
			(thermal_gap 0.5)
			(thermal_bridge_width 0.5)
			(island_removal_mode 0)
		)
		(polygon
			(pts
				(arc
					(start 166.58336 -32.80029)
					(mid 166.199947 -32.416496)
					(end 165.81628 -32.800036)
				)
				(xy 165.81628 -33.047432)
				(arc
					(start 165.952932 -33.047432)
					(mid 166.003244 -33.04064)
					(end 166.04996 -33.020762)
				)
				(arc
					(start 166.04996 -33.020762)
					(mid 166.289516 -32.548539)
					(end 166.174928 -33.065466)
				)
				(arc
					(start 166.174928 -33.065466)
					(mid 166.085134 -33.131508)
					(end 165.97757 -33.160716)
				)
				(xy 165.976554 -33.161732) (xy 165.81628 -33.161732) (xy 165.81628 -33.237932) (xy 165.976554 -33.237932)
				(arc
					(start 165.97757 -33.238948)
					(mid 166.085149 -33.268303)
					(end 166.174928 -33.334452)
				)
				(arc
					(start 166.174928 -33.334452)
					(mid 166.289877 -33.850805)
					(end 166.050214 -33.379156)
				)
				(arc
					(start 166.050214 -33.379156)
					(mid 166.0034 -33.359079)
					(end 165.952932 -33.352232)
				)
				(xy 165.81628 -33.352232)
				(arc
					(start 165.81628 -33.599882)
					(mid 166.19982 -33.983422)
					(end 166.58336 -33.599882)
				)
			)
		)
	)
	(zone
		(net "PCE_VDDH")
		(layer "In2.Cu")
		(hatch none 0.5)
		(connect_pads
			(clearance 0.5)
		)
		(min_thickness 0.25)
		(fill yes
			(thermal_gap 0.5)
			(thermal_bridge_width 0.5)
			(island_removal_mode 0)
		)
		(polygon
			(pts
				(xy 167.899842 -31.41599) (xy 167.66159 -31.654242) (xy 167.66159 -34.271458) (xy 168.220136 -34.830004)
				(xy 175.367188 -34.830004) (xy 177.013616 -33.183576) (xy 177.013616 -29.271214) (xy 177.26279 -29.02204)
				(xy 194.841368 -29.02204) (xy 195.356226 -28.507182) (xy 195.5038 -28.359608) (xy 195.5038 -26.030936)
				(xy 195.356226 -25.883362) (xy 194.873372 -25.400508) (xy 175.945292 -25.400508) (xy 169.92219 -25.400508)
				(xy 167.899842 -27.422856)
			)
		)
	)
	(zone
		(layer "In2.Cu")
		(hatch none 0.5)
		(connect_pads
			(clearance 0)
		)
		(min_thickness 0.25)
		(keepout
			(tracks not_allowed)
			(vias allowed)
			(pads allowed)
			(copperpour not_allowed)
			(footprints allowed)
		)
		(placement
			(enabled no)
			(sheetname "")
		)
		(fill
			(thermal_gap 0.5)
			(thermal_bridge_width 0.5)
			(island_removal_mode 0)
		)
		(polygon
			(pts
				(xy 165.897052 -34.016442)
				(arc
					(start 166.056056 -34.175446)
					(mid 166.388347 -34.588509)
					(end 165.975284 -34.256218)
				)
				(xy 165.776148 -34.057082)
				(arc
					(start 165.22827 -34.057082)
					(mid 165.170152 -34.092989)
					(end 165.119304 -34.138616)
				)
				(arc
					(start 165.202108 -34.221166)
					(mid 165.632801 -34.530653)
					(end 165.143942 -34.325052)
				)
				(arc
					(start 165.053772 -34.234628)
					(mid 165.075445 -34.604625)
					(end 165.399974 -34.783522)
				)
				(arc
					(start 166.19982 -34.783522)
					(mid 166.58336 -34.399982)
					(end 166.19982 -34.016442)
				)
			)
		)
	)
	(zone
		(layer "In2.Cu")
		(hatch none 0.5)
		(connect_pads
			(clearance 0)
		)
		(min_thickness 0.25)
		(keepout
			(tracks not_allowed)
			(vias allowed)
			(pads allowed)
			(copperpour not_allowed)
			(footprints allowed)
		)
		(placement
			(enabled no)
			(sheetname "")
		)
		(fill
			(thermal_gap 0.5)
			(thermal_bridge_width 0.5)
			(island_removal_mode 0)
		)
		(polygon
			(pts
				(xy 147.949412 -34.948876)
				(arc
					(start 147.825206 -34.92246)
					(mid 147.786879 -34.929498)
					(end 147.764754 -34.961576)
				)
				(arc
					(start 147.72259 -35.160458)
					(mid 147.72974 -35.198607)
					(end 147.761706 -35.220656)
				)
				(xy 147.885912 -35.247072) (xy 148.43252 -35.363404)
				(arc
					(start 148.556726 -35.38982)
					(mid 148.595053 -35.382782)
					(end 148.617178 -35.350704)
				)
				(arc
					(start 148.659342 -35.151822)
					(mid 148.652192 -35.113673)
					(end 148.620226 -35.091624)
				)
				(xy 148.49602 -35.065208)
			)
		)
	)
	(zone
		(layer "In2.Cu")
		(hatch none 0.5)
		(connect_pads
			(clearance 0)
		)
		(min_thickness 0.25)
		(keepout
			(tracks not_allowed)
			(vias allowed)
			(pads allowed)
			(copperpour not_allowed)
			(footprints allowed)
		)
		(placement
			(enabled no)
			(sheetname "")
		)
		(fill
			(thermal_gap 0.5)
			(thermal_bridge_width 0.5)
			(island_removal_mode 0)
		)
		(polygon
			(pts
				(arc
					(start 149.814534 -35.21329)
					(mid 149.46997 -34.661921)
					(end 148.922486 -35.012884)
				)
				(arc
					(start 148.684742 -36.130992)
					(mid 149.03704 -36.673282)
					(end 149.57933 -36.320984)
				)
				(xy 149.655022 -35.964368) (xy 149.335998 -35.905948) (xy 149.333712 -35.90544) (xy 149.285198 -35.915346)
				(arc
					(start 149.282658 -35.91687)
					(mid 149.263799 -35.935638)
					(end 149.253194 -35.96005)
				)
				(arc
					(start 149.24786 -35.985704)
					(mid 149.077241 -36.486876)
					(end 149.123654 -35.959542)
				)
				(xy 149.134576 -35.90798)
				(arc
					(start 149.137116 -35.906202)
					(mid 149.159593 -35.863029)
					(end 149.19198 -35.8267)
				)
				(xy 149.192488 -35.82416) (xy 149.2123 -35.811206) (xy 149.214586 -35.809682) (xy 149.21484 -35.809428)
				(xy 149.222206 -35.798252) (xy 149.235922 -35.795458) (xy 149.247606 -35.787838) (xy 149.260814 -35.790632)
				(xy 149.30247 -35.78225) (xy 149.307804 -35.776916) (xy 149.32914 -35.776916) (xy 149.347682 -35.77336)
				(xy 149.353016 -35.776916) (xy 149.360636 -35.776916) (xy 149.36597 -35.78225) (xy 149.681438 -35.840162)
				(xy 149.718522 -35.665918) (xy 149.371812 -35.602418)
				(arc
					(start 149.369018 -35.598354)
					(mid 149.31663 -35.567615)
					(end 149.276054 -35.522408)
				)
				(arc
					(start 149.276054 -35.522408)
					(mid 149.250561 -35.464629)
					(end 149.244558 -35.401758)
				)
				(xy 149.243034 -35.399218) (xy 149.248368 -35.373564)
				(arc
					(start 149.253956 -35.348164)
					(mid 149.424575 -34.846992)
					(end 149.378162 -35.374326)
				)
				(arc
					(start 149.372828 -35.39998)
					(mid 149.372467 -35.427635)
					(end 149.382734 -35.45332)
				)
				(arc
					(start 149.382734 -35.45332)
					(mid 149.400089 -35.471751)
					(end 149.422866 -35.482784)
				)
				(xy 149.744938 -35.541712)
			)
		)
	)
	(zone
		(layer "In2.Cu")
		(hatch none 0.5)
		(connect_pads
			(clearance 0)
		)
		(min_thickness 0.25)
		(keepout
			(tracks not_allowed)
			(vias allowed)
			(pads allowed)
			(copperpour not_allowed)
			(footprints allowed)
		)
		(placement
			(enabled no)
			(sheetname "")
		)
		(fill
			(thermal_gap 0.5)
			(thermal_bridge_width 0.5)
			(island_removal_mode 0)
		)
		(polygon
			(pts
				(xy 147.828 -35.520122)
				(arc
					(start 147.703794 -35.493706)
					(mid 147.665467 -35.500744)
					(end 147.643342 -35.532822)
				)
				(arc
					(start 147.601178 -35.731704)
					(mid 147.608328 -35.769853)
					(end 147.640294 -35.791902)
				)
				(xy 147.7645 -35.818318) (xy 148.311108 -35.93465)
				(arc
					(start 148.435314 -35.961066)
					(mid 148.473641 -35.954028)
					(end 148.495766 -35.92195)
				)
				(arc
					(start 148.53793 -35.723068)
					(mid 148.53078 -35.684919)
					(end 148.498814 -35.66287)
				)
				(xy 148.374608 -35.636454)
			)
		)
	)
	(zone
		(layer "In2.Cu")
		(hatch none 0.5)
		(connect_pads
			(clearance 0)
		)
		(min_thickness 0.25)
		(keepout
			(tracks not_allowed)
			(vias allowed)
			(pads allowed)
			(copperpour not_allowed)
			(footprints allowed)
		)
		(placement
			(enabled no)
			(sheetname "")
		)
		(fill
			(thermal_gap 0.5)
			(thermal_bridge_width 0.5)
			(island_removal_mode 0)
		)
		(polygon
			(pts
				(arc
					(start 139.446 -58.44794)
					(mid 138.99134 -58.9026)
					(end 139.446 -59.35726)
				)
				(arc
					(start 140.588746 -59.35726)
					(mid 141.04366 -58.902727)
					(end 140.589 -58.44794)
				)
				(xy 140.231368 -58.44794) (xy 140.232892 -58.469784) (xy 140.2334 -58.470292)
				(arc
					(start 140.2334 -58.734706)
					(mid 140.241396 -58.774724)
					(end 140.264134 -58.80862)
				)
				(arc
					(start 140.264134 -58.80862)
					(mid 140.294303 -58.829674)
					(end 140.32992 -58.838846)
				)
				(arc
					(start 140.32992 -58.838846)
					(mid 140.855809 -58.902723)
					(end 140.32992 -58.9661)
				)
				(xy 140.311124 -58.9661)
				(arc
					(start 140.3096 -58.964322)
					(mid 140.236384 -58.942788)
					(end 140.174218 -58.898536)
				)
				(arc
					(start 140.174218 -58.898536)
					(mid 140.129811 -58.836127)
					(end 140.108178 -58.762646)
				)
				(xy 140.1064 -58.761122)
				(arc
					(start 140.1064 -58.496708)
					(mid 140.105775 -58.472291)
					(end 140.10386 -58.44794)
				)
				(xy 139.924282 -58.44794) (xy 139.92733 -58.469022) (xy 139.9286 -58.470292) (xy 139.9286 -58.744866)
				(arc
					(start 139.927076 -58.74639)
					(mid 139.909841 -58.813015)
					(end 139.875006 -58.872374)
				)
				(xy 139.875006 -58.874914) (xy 139.837668 -58.912252)
				(arc
					(start 139.835382 -58.912252)
					(mid 139.775692 -58.947326)
					(end 139.708636 -58.964576)
				)
				(xy 139.707112 -58.9661)
				(arc
					(start 139.70508 -58.9661)
					(mid 139.179254 -58.90377)
					(end 139.704572 -58.836814)
				)
				(arc
					(start 139.704572 -58.836814)
					(mid 139.737897 -58.824898)
					(end 139.766294 -58.803794)
				)
				(arc
					(start 139.766548 -58.803794)
					(mid 139.792498 -58.764582)
					(end 139.8016 -58.71845)
				)
				(arc
					(start 139.8016 -58.496708)
					(mid 139.799633 -58.472007)
					(end 139.793726 -58.44794)
				)
			)
		)
	)
	(zone
		(layer "In2.Cu")
		(hatch none 0.5)
		(connect_pads
			(clearance 0)
		)
		(min_thickness 0.25)
		(keepout
			(tracks not_allowed)
			(vias allowed)
			(pads allowed)
			(copperpour not_allowed)
			(footprints allowed)
		)
		(placement
			(enabled no)
			(sheetname "")
		)
		(fill
			(thermal_gap 0.5)
			(thermal_bridge_width 0.5)
			(island_removal_mode 0)
		)
		(polygon
			(pts
				(xy 166.696898 -29.216604)
				(arc
					(start 166.855902 -29.375608)
					(mid 167.188193 -29.788671)
					(end 166.77513 -29.45638)
				)
				(xy 166.57574 -29.25699)
				(arc
					(start 166.028116 -29.25699)
					(mid 165.972812 -29.29081)
					(end 165.923976 -29.333444)
				)
				(xy 166.014146 -29.333444)
				(arc
					(start 166.056056 -29.375354)
					(mid 166.388347 -29.788417)
					(end 165.975284 -29.456126)
				)
				(xy 165.966902 -29.447744)
				(arc
					(start 165.847776 -29.447744)
					(mid 165.879325 -29.810524)
					(end 166.19982 -29.98343)
				)
				(arc
					(start 166.999412 -29.983684)
					(mid 167.383206 -29.600271)
					(end 166.999666 -29.216604)
				)
			)
		)
	)
	(zone
		(layers "In2.Cu" "In3.Cu" "In4.Cu" "In5.Cu")
		(hatch none 0.5)
		(connect_pads
			(clearance 0)
		)
		(min_thickness 0.25)
		(keepout
			(tracks not_allowed)
			(vias allowed)
			(pads allowed)
			(copperpour not_allowed)
			(footprints allowed)
		)
		(placement
			(enabled no)
			(sheetname "")
		)
		(fill yes
			(thermal_gap 0.5)
			(thermal_bridge_width 0.5)
			(island_removal_mode 0)
		)
		(polygon
			(pts
				(arc
					(start 4.99999 -139.224258)
					(mid 18.499799 -131.430014)
					(end 4.99999 -123.63577)
				)
			)
		)
	)
	(zone
		(layers "In2.Cu" "In5.Cu")
		(hatch none 0.5)
		(connect_pads
			(clearance 0)
		)
		(min_thickness 0.25)
		(keepout
			(tracks not_allowed)
			(vias allowed)
			(pads allowed)
			(copperpour not_allowed)
			(footprints allowed)
		)
		(placement
			(enabled no)
			(sheetname "")
		)
		(fill yes
			(thermal_gap 0.5)
			(thermal_bridge_width 0.5)
			(island_removal_mode 0)
		)
		(polygon
			(pts
				(arc
					(start 104.358186 -55.000144)
					(mid 104.000046 -54.642004)
					(end 103.641906 -55.000144)
				)
				(arc
					(start 103.641906 -55.999888)
					(mid 103.998649 -56.358279)
					(end 104.358186 -56.002682)
				)
				(arc
					(start 104.241346 -56.002682)
					(mid 104.000046 -56.241455)
					(end 103.758746 -56.002682)
				)
				(arc
					(start 103.758746 -56.000142)
					(mid 104.000046 -55.758842)
					(end 104.241346 -56.000142)
				)
				(xy 104.358186 -56.000142) (xy 104.358186 -55.002684)
				(arc
					(start 104.241346 -55.002684)
					(mid 104.000046 -55.241457)
					(end 103.758746 -55.002684)
				)
				(arc
					(start 103.758746 -55.000144)
					(mid 104.000046 -54.758844)
					(end 104.241346 -55.000144)
				)
			)
		)
	)
	(zone
		(layers "In2.Cu" "In5.Cu")
		(hatch none 0.5)
		(connect_pads
			(clearance 0)
		)
		(min_thickness 0.25)
		(keepout
			(tracks not_allowed)
			(vias allowed)
			(pads allowed)
			(copperpour not_allowed)
			(footprints allowed)
		)
		(placement
			(enabled no)
			(sheetname "")
		)
		(fill yes
			(thermal_gap 0.5)
			(thermal_bridge_width 0.5)
			(island_removal_mode 0)
		)
		(polygon
			(pts
				(arc
					(start 126.000256 -72.641968)
					(mid 125.641862 -72.999981)
					(end 126.000002 -73.358248)
				)
				(arc
					(start 127 -73.358248)
					(mid 127.252344 -73.254248)
					(end 127.35814 -73.002648)
				)
				(arc
					(start 127.2413 -73.002648)
					(mid 127 -73.241421)
					(end 126.7587 -73.002648)
				)
				(arc
					(start 126.241302 -73.002648)
					(mid 126.000002 -73.241421)
					(end 125.758702 -73.002648)
				)
				(arc
					(start 125.758702 -73.000108)
					(mid 126.000002 -72.758808)
					(end 126.241302 -73.000108)
				)
				(arc
					(start 126.7587 -73.000108)
					(mid 127 -72.758808)
					(end 127.2413 -73.000108)
				)
				(arc
					(start 127.35814 -73.000108)
					(mid 127.253243 -72.746865)
					(end 127 -72.641968)
				)
			)
		)
	)
	(zone
		(layers "In2.Cu" "In5.Cu")
		(hatch none 0.5)
		(connect_pads
			(clearance 0)
		)
		(min_thickness 0.25)
		(keepout
			(tracks not_allowed)
			(vias allowed)
			(pads allowed)
			(copperpour not_allowed)
			(footprints allowed)
		)
		(placement
			(enabled no)
			(sheetname "")
		)
		(fill yes
			(thermal_gap 0.5)
			(thermal_bridge_width 0.5)
			(island_removal_mode 0)
		)
		(polygon
			(pts
				(arc
					(start 176.158144 -30.400244)
					(mid 175.800004 -30.042104)
					(end 175.441864 -30.400244)
				)
				(arc
					(start 175.441864 -31.199836)
					(mid 175.798607 -31.558227)
					(end 176.158144 -31.20263)
				)
				(arc
					(start 176.041304 -31.20263)
					(mid 175.800004 -31.441403)
					(end 175.558704 -31.20263)
				)
				(arc
					(start 175.558704 -31.20009)
					(mid 175.800004 -30.95879)
					(end 176.041304 -31.20009)
				)
				(xy 176.158144 -31.20009) (xy 176.158144 -30.402784)
				(arc
					(start 176.041304 -30.402784)
					(mid 175.800004 -30.641557)
					(end 175.558704 -30.402784)
				)
				(arc
					(start 175.558704 -30.400244)
					(mid 175.800004 -30.158944)
					(end 176.041304 -30.400244)
				)
			)
		)
	)
	(zone
		(layers "In2.Cu" "In5.Cu")
		(hatch none 0.5)
		(connect_pads
			(clearance 0)
		)
		(min_thickness 0.25)
		(keepout
			(tracks not_allowed)
			(vias allowed)
			(pads allowed)
			(copperpour not_allowed)
			(footprints allowed)
		)
		(placement
			(enabled no)
			(sheetname "")
		)
		(fill yes
			(thermal_gap 0.5)
			(thermal_bridge_width 0.5)
			(island_removal_mode 0)
		)
		(polygon
			(pts
				(arc
					(start 126.000256 -74.641964)
					(mid 125.641862 -74.999977)
					(end 126.000002 -75.358244)
				)
				(arc
					(start 127 -75.358244)
					(mid 127.252344 -75.254244)
					(end 127.35814 -75.002644)
				)
				(arc
					(start 127.2413 -75.002644)
					(mid 127 -75.241417)
					(end 126.7587 -75.002644)
				)
				(arc
					(start 126.241302 -75.002644)
					(mid 126.000002 -75.241417)
					(end 125.758702 -75.002644)
				)
				(arc
					(start 125.758702 -75.000104)
					(mid 126.000002 -74.758804)
					(end 126.241302 -75.000104)
				)
				(arc
					(start 126.7587 -75.000104)
					(mid 127 -74.758804)
					(end 127.2413 -75.000104)
				)
				(arc
					(start 127.35814 -75.000104)
					(mid 127.253243 -74.746861)
					(end 127 -74.641964)
				)
			)
		)
	)
	(zone
		(layers "In2.Cu" "In5.Cu")
		(hatch none 0.5)
		(connect_pads
			(clearance 0)
		)
		(min_thickness 0.25)
		(keepout
			(tracks not_allowed)
			(vias allowed)
			(pads allowed)
			(copperpour not_allowed)
			(footprints allowed)
		)
		(placement
			(enabled no)
			(sheetname "")
		)
		(fill yes
			(thermal_gap 0.5)
			(thermal_bridge_width 0.5)
			(island_removal_mode 0)
		)
		(polygon
			(pts
				(arc
					(start 170.557952 -30.39999)
					(mid 170.199685 -30.04185)
					(end 169.841672 -30.400244)
				)
				(arc
					(start 169.841926 -31.199836)
					(mid 170.198669 -31.558227)
					(end 170.558206 -31.20263)
				)
				(arc
					(start 170.441366 -31.20263)
					(mid 170.200066 -31.441403)
					(end 169.958766 -31.20263)
				)
				(arc
					(start 169.958766 -31.20009)
					(mid 170.200066 -30.95879)
					(end 170.441366 -31.20009)
				)
				(xy 170.558206 -31.20009) (xy 170.558206 -31.199836) (xy 170.557952 -30.64129) (xy 170.557952 -30.40253)
				(arc
					(start 170.441112 -30.40253)
					(mid 170.199812 -30.641303)
					(end 169.958512 -30.40253)
				)
				(arc
					(start 169.958512 -30.39999)
					(mid 170.199812 -30.15869)
					(end 170.441112 -30.39999)
				)
			)
		)
	)
	(zone
		(layers "In2.Cu" "In5.Cu")
		(hatch none 0.5)
		(connect_pads
			(clearance 0)
		)
		(min_thickness 0.25)
		(keepout
			(tracks not_allowed)
			(vias allowed)
			(pads allowed)
			(copperpour not_allowed)
			(footprints allowed)
		)
		(placement
			(enabled no)
			(sheetname "")
		)
		(fill yes
			(thermal_gap 0.5)
			(thermal_bridge_width 0.5)
			(island_removal_mode 0)
		)
		(polygon
			(pts
				(arc
					(start 108.358178 -55.000144)
					(mid 108.000038 -54.642004)
					(end 107.641898 -55.000144)
				)
				(arc
					(start 107.641898 -55.999888)
					(mid 107.998641 -56.358279)
					(end 108.358178 -56.002682)
				)
				(arc
					(start 108.241338 -56.002682)
					(mid 108.000038 -56.241455)
					(end 107.758738 -56.002682)
				)
				(arc
					(start 107.758738 -56.000142)
					(mid 108.000038 -55.758842)
					(end 108.241338 -56.000142)
				)
				(xy 108.358178 -56.000142) (xy 108.358178 -55.002684)
				(arc
					(start 108.241338 -55.002684)
					(mid 108.000038 -55.241457)
					(end 107.758738 -55.002684)
				)
				(arc
					(start 107.758738 -55.000144)
					(mid 108.000038 -54.758844)
					(end 108.241338 -55.000144)
				)
			)
		)
	)
	(zone
		(layers "In2.Cu" "In5.Cu")
		(hatch none 0.5)
		(connect_pads
			(clearance 0)
		)
		(min_thickness 0.25)
		(keepout
			(tracks not_allowed)
			(vias allowed)
			(pads allowed)
			(copperpour not_allowed)
			(footprints allowed)
		)
		(placement
			(enabled no)
			(sheetname "")
		)
		(fill yes
			(thermal_gap 0.5)
			(thermal_bridge_width 0.5)
			(island_removal_mode 0)
		)
		(polygon
			(pts
				(arc
					(start 168.958006 -30.39999)
					(mid 168.599866 -30.04185)
					(end 168.241726 -30.39999)
				)
				(arc
					(start 168.241726 -31.199582)
					(mid 168.598469 -31.557973)
					(end 168.958006 -31.202376)
				)
				(arc
					(start 168.841166 -31.202376)
					(mid 168.599866 -31.441149)
					(end 168.358566 -31.202376)
				)
				(arc
					(start 168.358566 -31.199836)
					(mid 168.599866 -30.958536)
					(end 168.841166 -31.199836)
				)
				(xy 168.958006 -31.199836) (xy 168.958006 -30.40253)
				(arc
					(start 168.841166 -30.40253)
					(mid 168.599866 -30.641303)
					(end 168.358566 -30.40253)
				)
				(arc
					(start 168.358566 -30.39999)
					(mid 168.599866 -30.15869)
					(end 168.841166 -30.39999)
				)
			)
		)
	)
	(zone
		(layers "In2.Cu" "In5.Cu")
		(hatch none 0.5)
		(connect_pads
			(clearance 0)
		)
		(min_thickness 0.25)
		(keepout
			(tracks not_allowed)
			(vias allowed)
			(pads allowed)
			(copperpour not_allowed)
			(footprints allowed)
		)
		(placement
			(enabled no)
			(sheetname "")
		)
		(fill yes
			(thermal_gap 0.5)
			(thermal_bridge_width 0.5)
			(island_removal_mode 0)
		)
		(polygon
			(pts
				(arc
					(start 123.358148 -55.000144)
					(mid 123.000008 -54.642004)
					(end 122.641868 -55.000144)
				)
				(arc
					(start 122.641868 -55.999888)
					(mid 122.998611 -56.358279)
					(end 123.358148 -56.002682)
				)
				(arc
					(start 123.241308 -56.002682)
					(mid 123.000008 -56.241455)
					(end 122.758708 -56.002682)
				)
				(arc
					(start 122.758708 -56.000142)
					(mid 123.000008 -55.758842)
					(end 123.241308 -56.000142)
				)
				(xy 123.358148 -56.000142) (xy 123.358148 -55.002684)
				(arc
					(start 123.241308 -55.002684)
					(mid 123.000008 -55.241457)
					(end 122.758708 -55.002684)
				)
				(arc
					(start 122.758708 -55.000144)
					(mid 123.000008 -54.758844)
					(end 123.241308 -55.000144)
				)
			)
		)
	)
	(zone
		(layers "In2.Cu" "In5.Cu")
		(hatch none 0.5)
		(connect_pads
			(clearance 0)
		)
		(min_thickness 0.25)
		(keepout
			(tracks not_allowed)
			(vias allowed)
			(pads allowed)
			(copperpour not_allowed)
			(footprints allowed)
		)
		(placement
			(enabled no)
			(sheetname "")
		)
		(fill yes
			(thermal_gap 0.5)
			(thermal_bridge_width 0.5)
			(island_removal_mode 0)
		)
		(polygon
			(pts
				(arc
					(start 107.35818 -55.000144)
					(mid 107.00004 -54.642004)
					(end 106.6419 -55.000144)
				)
				(arc
					(start 106.6419 -55.999888)
					(mid 106.998643 -56.358279)
					(end 107.35818 -56.002682)
				)
				(arc
					(start 107.24134 -56.002682)
					(mid 107.00004 -56.241455)
					(end 106.75874 -56.002682)
				)
				(arc
					(start 106.75874 -56.000142)
					(mid 107.00004 -55.758842)
					(end 107.24134 -56.000142)
				)
				(xy 107.35818 -56.000142) (xy 107.35818 -55.002684)
				(arc
					(start 107.24134 -55.002684)
					(mid 107.00004 -55.241457)
					(end 106.75874 -55.002684)
				)
				(arc
					(start 106.75874 -55.000144)
					(mid 107.00004 -54.758844)
					(end 107.24134 -55.000144)
				)
			)
		)
	)
	(zone
		(layers "In2.Cu" "In5.Cu")
		(hatch none 0.5)
		(connect_pads
			(clearance 0)
		)
		(min_thickness 0.25)
		(keepout
			(tracks not_allowed)
			(vias allowed)
			(pads allowed)
			(copperpour not_allowed)
			(footprints allowed)
		)
		(placement
			(enabled no)
			(sheetname "")
		)
		(fill yes
			(thermal_gap 0.5)
			(thermal_bridge_width 0.5)
			(island_removal_mode 0)
		)
		(polygon
			(pts
				(arc
					(start 102.35819 -55.000144)
					(mid 102.00005 -54.642004)
					(end 101.64191 -55.000144)
				)
				(arc
					(start 101.64191 -55.999888)
					(mid 101.998653 -56.358279)
					(end 102.35819 -56.002682)
				)
				(arc
					(start 102.24135 -56.002682)
					(mid 102.00005 -56.241455)
					(end 101.75875 -56.002682)
				)
				(arc
					(start 101.75875 -56.000142)
					(mid 102.00005 -55.758842)
					(end 102.24135 -56.000142)
				)
				(xy 102.35819 -56.000142) (xy 102.35819 -55.002684)
				(arc
					(start 102.24135 -55.002684)
					(mid 102.00005 -55.241457)
					(end 101.75875 -55.002684)
				)
				(arc
					(start 101.75875 -55.000144)
					(mid 102.00005 -54.758844)
					(end 102.24135 -55.000144)
				)
			)
		)
	)
	(zone
		(layers "In2.Cu" "In5.Cu")
		(hatch none 0.5)
		(connect_pads
			(clearance 0)
		)
		(min_thickness 0.25)
		(keepout
			(tracks not_allowed)
			(vias allowed)
			(pads allowed)
			(copperpour not_allowed)
			(footprints allowed)
		)
		(placement
			(enabled no)
			(sheetname "")
		)
		(fill yes
			(thermal_gap 0.5)
			(thermal_bridge_width 0.5)
			(island_removal_mode 0)
		)
		(polygon
			(pts
				(arc
					(start 109.358176 -55.000144)
					(mid 109.000036 -54.642004)
					(end 108.641896 -55.000144)
				)
				(arc
					(start 108.641896 -55.999888)
					(mid 108.998639 -56.358279)
					(end 109.358176 -56.002682)
				)
				(arc
					(start 109.241336 -56.002682)
					(mid 109.000036 -56.241455)
					(end 108.758736 -56.002682)
				)
				(arc
					(start 108.758736 -56.000142)
					(mid 109.000036 -55.758842)
					(end 109.241336 -56.000142)
				)
				(xy 109.358176 -56.000142) (xy 109.358176 -55.002684)
				(arc
					(start 109.241336 -55.002684)
					(mid 109.000036 -55.241457)
					(end 108.758736 -55.002684)
				)
				(arc
					(start 108.758736 -55.000144)
					(mid 109.000036 -54.758844)
					(end 109.241336 -55.000144)
				)
			)
		)
	)
	(zone
		(layers "In2.Cu" "In5.Cu")
		(hatch none 0.5)
		(connect_pads
			(clearance 0)
		)
		(min_thickness 0.25)
		(keepout
			(tracks not_allowed)
			(vias allowed)
			(pads allowed)
			(copperpour not_allowed)
			(footprints allowed)
		)
		(placement
			(enabled no)
			(sheetname "")
		)
		(fill yes
			(thermal_gap 0.5)
			(thermal_bridge_width 0.5)
			(island_removal_mode 0)
		)
		(polygon
			(pts
				(arc
					(start 122.35815 -55.000144)
					(mid 122.00001 -54.642004)
					(end 121.64187 -55.000144)
				)
				(arc
					(start 121.64187 -55.999888)
					(mid 121.998613 -56.358279)
					(end 122.35815 -56.002682)
				)
				(arc
					(start 122.24131 -56.002682)
					(mid 122.00001 -56.241455)
					(end 121.75871 -56.002682)
				)
				(arc
					(start 121.75871 -56.000142)
					(mid 122.00001 -55.758842)
					(end 122.24131 -56.000142)
				)
				(xy 122.35815 -56.000142) (xy 122.35815 -55.002684)
				(arc
					(start 122.24131 -55.002684)
					(mid 122.00001 -55.241457)
					(end 121.75871 -55.002684)
				)
				(arc
					(start 121.75871 -55.000144)
					(mid 122.00001 -54.758844)
					(end 122.24131 -55.000144)
				)
			)
		)
	)
	(zone
		(layers "In2.Cu" "In5.Cu")
		(hatch none 0.5)
		(connect_pads
			(clearance 0)
		)
		(min_thickness 0.25)
		(keepout
			(tracks not_allowed)
			(vias allowed)
			(pads allowed)
			(copperpour not_allowed)
			(footprints allowed)
		)
		(placement
			(enabled no)
			(sheetname "")
		)
		(fill yes
			(thermal_gap 0.5)
			(thermal_bridge_width 0.5)
			(island_removal_mode 0)
		)
		(polygon
			(pts
				(arc
					(start 126.000256 -63.641986)
					(mid 125.641862 -63.999999)
					(end 126.000002 -64.358266)
				)
				(arc
					(start 127 -64.358266)
					(mid 127.252344 -64.254266)
					(end 127.35814 -64.002666)
				)
				(arc
					(start 127.2413 -64.002666)
					(mid 127 -64.241439)
					(end 126.7587 -64.002666)
				)
				(arc
					(start 126.241302 -64.002666)
					(mid 126.000002 -64.241439)
					(end 125.758702 -64.002666)
				)
				(arc
					(start 125.758702 -64.000126)
					(mid 126.000002 -63.758826)
					(end 126.241302 -64.000126)
				)
				(arc
					(start 126.7587 -64.000126)
					(mid 127 -63.758826)
					(end 127.2413 -64.000126)
				)
				(arc
					(start 127.35814 -64.000126)
					(mid 127.253243 -63.746883)
					(end 127 -63.641986)
				)
			)
		)
	)
	(zone
		(layers "In2.Cu" "In5.Cu")
		(hatch none 0.5)
		(connect_pads
			(clearance 0)
		)
		(min_thickness 0.25)
		(keepout
			(tracks not_allowed)
			(vias allowed)
			(pads allowed)
			(copperpour not_allowed)
			(footprints allowed)
		)
		(placement
			(enabled no)
			(sheetname "")
		)
		(fill yes
			(thermal_gap 0.5)
			(thermal_bridge_width 0.5)
			(island_removal_mode 0)
		)
		(polygon
			(pts
				(arc
					(start 119.358156 -55.000144)
					(mid 119.000016 -54.642004)
					(end 118.641876 -55.000144)
				)
				(arc
					(start 118.641876 -55.999888)
					(mid 118.998619 -56.358279)
					(end 119.358156 -56.002682)
				)
				(arc
					(start 119.241316 -56.002682)
					(mid 119.000016 -56.241455)
					(end 118.758716 -56.002682)
				)
				(arc
					(start 118.758716 -56.000142)
					(mid 119.000016 -55.758842)
					(end 119.241316 -56.000142)
				)
				(xy 119.358156 -56.000142) (xy 119.358156 -55.002684)
				(arc
					(start 119.241316 -55.002684)
					(mid 119.000016 -55.241457)
					(end 118.758716 -55.002684)
				)
				(arc
					(start 118.758716 -55.000144)
					(mid 119.000016 -54.758844)
					(end 119.241316 -55.000144)
				)
			)
		)
	)
	(zone
		(layers "In2.Cu" "In5.Cu")
		(hatch none 0.5)
		(connect_pads
			(clearance 0)
		)
		(min_thickness 0.25)
		(keepout
			(tracks not_allowed)
			(vias allowed)
			(pads allowed)
			(copperpour not_allowed)
			(footprints allowed)
		)
		(placement
			(enabled no)
			(sheetname "")
		)
		(fill yes
			(thermal_gap 0.5)
			(thermal_bridge_width 0.5)
			(island_removal_mode 0)
		)
		(polygon
			(pts
				(arc
					(start 126.000256 -62.641988)
					(mid 125.641862 -63.000001)
					(end 126.000002 -63.358268)
				)
				(arc
					(start 127 -63.358268)
					(mid 127.252344 -63.254268)
					(end 127.35814 -63.002668)
				)
				(arc
					(start 127.2413 -63.002668)
					(mid 127 -63.241441)
					(end 126.7587 -63.002668)
				)
				(arc
					(start 126.241302 -63.002668)
					(mid 126.000002 -63.241441)
					(end 125.758702 -63.002668)
				)
				(arc
					(start 125.758702 -63.000128)
					(mid 126.000002 -62.758828)
					(end 126.241302 -63.000128)
				)
				(arc
					(start 126.7587 -63.000128)
					(mid 127 -62.758828)
					(end 127.2413 -63.000128)
				)
				(arc
					(start 127.35814 -63.000128)
					(mid 127.253243 -62.746885)
					(end 127 -62.641988)
				)
			)
		)
	)
	(zone
		(layers "In2.Cu" "In5.Cu")
		(hatch none 0.5)
		(connect_pads
			(clearance 0)
		)
		(min_thickness 0.25)
		(keepout
			(tracks not_allowed)
			(vias allowed)
			(pads allowed)
			(copperpour not_allowed)
			(footprints allowed)
		)
		(placement
			(enabled no)
			(sheetname "")
		)
		(fill yes
			(thermal_gap 0.5)
			(thermal_bridge_width 0.5)
			(island_removal_mode 0)
		)
		(polygon
			(pts
				(arc
					(start 173.758098 -30.39999)
					(mid 173.399831 -30.04185)
					(end 173.041818 -30.400244)
				)
				(arc
					(start 173.042072 -31.199836)
					(mid 173.398815 -31.558227)
					(end 173.758352 -31.20263)
				)
				(arc
					(start 173.641512 -31.20263)
					(mid 173.400212 -31.441403)
					(end 173.158912 -31.20263)
				)
				(arc
					(start 173.158912 -31.20009)
					(mid 173.400212 -30.95879)
					(end 173.641512 -31.20009)
				)
				(xy 173.758352 -31.20009) (xy 173.758352 -31.199836) (xy 173.758098 -30.64129) (xy 173.758098 -30.40253)
				(arc
					(start 173.641258 -30.40253)
					(mid 173.399958 -30.641303)
					(end 173.158658 -30.40253)
				)
				(arc
					(start 173.158658 -30.39999)
					(mid 173.399958 -30.15869)
					(end 173.641258 -30.39999)
				)
			)
		)
	)
	(zone
		(layers "In2.Cu" "In5.Cu")
		(hatch none 0.5)
		(connect_pads
			(clearance 0)
		)
		(min_thickness 0.25)
		(keepout
			(tracks not_allowed)
			(vias allowed)
			(pads allowed)
			(copperpour not_allowed)
			(footprints allowed)
		)
		(placement
			(enabled no)
			(sheetname "")
		)
		(fill yes
			(thermal_gap 0.5)
			(thermal_bridge_width 0.5)
			(island_removal_mode 0)
		)
		(polygon
			(pts
				(arc
					(start 175.358044 -30.39999)
					(mid 174.999777 -30.04185)
					(end 174.641764 -30.400244)
				)
				(arc
					(start 174.642018 -31.199836)
					(mid 174.998761 -31.558227)
					(end 175.358298 -31.20263)
				)
				(arc
					(start 175.241458 -31.20263)
					(mid 175.000158 -31.441403)
					(end 174.758858 -31.20263)
				)
				(arc
					(start 174.758858 -31.20009)
					(mid 175.000158 -30.95879)
					(end 175.241458 -31.20009)
				)
				(xy 175.358298 -31.20009) (xy 175.358298 -31.199836) (xy 175.358044 -30.64129) (xy 175.358044 -30.40253)
				(arc
					(start 175.241204 -30.40253)
					(mid 174.999904 -30.641303)
					(end 174.758604 -30.40253)
				)
				(arc
					(start 174.758604 -30.39999)
					(mid 174.999904 -30.15869)
					(end 175.241204 -30.39999)
				)
			)
		)
	)
	(zone
		(layers "In2.Cu" "In5.Cu")
		(hatch none 0.5)
		(connect_pads
			(clearance 0)
		)
		(min_thickness 0.25)
		(keepout
			(tracks not_allowed)
			(vias allowed)
			(pads allowed)
			(copperpour not_allowed)
			(footprints allowed)
		)
		(placement
			(enabled no)
			(sheetname "")
		)
		(fill yes
			(thermal_gap 0.5)
			(thermal_bridge_width 0.5)
			(island_removal_mode 0)
		)
		(polygon
			(pts
				(arc
					(start 105.358184 -55.000144)
					(mid 105.000044 -54.642004)
					(end 104.641904 -55.000144)
				)
				(arc
					(start 104.641904 -55.999888)
					(mid 104.998647 -56.358279)
					(end 105.358184 -56.002682)
				)
				(arc
					(start 105.241344 -56.002682)
					(mid 105.000044 -56.241455)
					(end 104.758744 -56.002682)
				)
				(arc
					(start 104.758744 -56.000142)
					(mid 105.000044 -55.758842)
					(end 105.241344 -56.000142)
				)
				(xy 105.358184 -56.000142) (xy 105.358184 -55.002684)
				(arc
					(start 105.241344 -55.002684)
					(mid 105.000044 -55.241457)
					(end 104.758744 -55.002684)
				)
				(arc
					(start 104.758744 -55.000144)
					(mid 105.000044 -54.758844)
					(end 105.241344 -55.000144)
				)
			)
		)
	)
	(zone
		(layers "In2.Cu" "In5.Cu")
		(hatch none 0.5)
		(connect_pads
			(clearance 0)
		)
		(min_thickness 0.25)
		(keepout
			(tracks not_allowed)
			(vias allowed)
			(pads allowed)
			(copperpour not_allowed)
			(footprints allowed)
		)
		(placement
			(enabled no)
			(sheetname "")
		)
		(fill yes
			(thermal_gap 0.5)
			(thermal_bridge_width 0.5)
			(island_removal_mode 0)
		)
		(polygon
			(pts
				(arc
					(start 126.000256 -71.64197)
					(mid 125.641862 -71.999983)
					(end 126.000002 -72.35825)
				)
				(arc
					(start 127 -72.35825)
					(mid 127.252344 -72.25425)
					(end 127.35814 -72.00265)
				)
				(arc
					(start 127.2413 -72.00265)
					(mid 127 -72.241423)
					(end 126.7587 -72.00265)
				)
				(arc
					(start 126.241302 -72.00265)
					(mid 126.000002 -72.241423)
					(end 125.758702 -72.00265)
				)
				(arc
					(start 125.758702 -72.00011)
					(mid 126.000002 -71.75881)
					(end 126.241302 -72.00011)
				)
				(arc
					(start 126.7587 -72.00011)
					(mid 127 -71.75881)
					(end 127.2413 -72.00011)
				)
				(arc
					(start 127.35814 -72.00011)
					(mid 127.253243 -71.746867)
					(end 127 -71.64197)
				)
			)
		)
	)
	(zone
		(layers "In2.Cu" "In5.Cu")
		(hatch none 0.5)
		(connect_pads
			(clearance 0)
		)
		(min_thickness 0.25)
		(keepout
			(tracks not_allowed)
			(vias allowed)
			(pads allowed)
			(copperpour not_allowed)
			(footprints allowed)
		)
		(placement
			(enabled no)
			(sheetname "")
		)
		(fill yes
			(thermal_gap 0.5)
			(thermal_bridge_width 0.5)
			(island_removal_mode 0)
		)
		(polygon
			(pts
				(arc
					(start 126.000256 -65.641982)
					(mid 125.641862 -65.999995)
					(end 126.000002 -66.358262)
				)
				(arc
					(start 127 -66.358262)
					(mid 127.252344 -66.254262)
					(end 127.35814 -66.002662)
				)
				(arc
					(start 127.2413 -66.002662)
					(mid 127 -66.241435)
					(end 126.7587 -66.002662)
				)
				(arc
					(start 126.241302 -66.002662)
					(mid 126.000002 -66.241435)
					(end 125.758702 -66.002662)
				)
				(arc
					(start 125.758702 -66.000122)
					(mid 126.000002 -65.758822)
					(end 126.241302 -66.000122)
				)
				(arc
					(start 126.7587 -66.000122)
					(mid 127 -65.758822)
					(end 127.2413 -66.000122)
				)
				(arc
					(start 127.35814 -66.000122)
					(mid 127.253243 -65.746879)
					(end 127 -65.641982)
				)
			)
		)
	)
	(zone
		(layers "In2.Cu" "In5.Cu")
		(hatch none 0.5)
		(connect_pads
			(clearance 0)
		)
		(min_thickness 0.25)
		(keepout
			(tracks not_allowed)
			(vias allowed)
			(pads allowed)
			(copperpour not_allowed)
			(footprints allowed)
		)
		(placement
			(enabled no)
			(sheetname "")
		)
		(fill yes
			(thermal_gap 0.5)
			(thermal_bridge_width 0.5)
			(island_removal_mode 0)
		)
		(polygon
			(pts
				(arc
					(start 113.358168 -55.000144)
					(mid 113.000028 -54.642004)
					(end 112.641888 -55.000144)
				)
				(arc
					(start 112.641888 -55.999888)
					(mid 112.998631 -56.358279)
					(end 113.358168 -56.002682)
				)
				(arc
					(start 113.241328 -56.002682)
					(mid 113.000028 -56.241455)
					(end 112.758728 -56.002682)
				)
				(arc
					(start 112.758728 -56.000142)
					(mid 113.000028 -55.758842)
					(end 113.241328 -56.000142)
				)
				(xy 113.358168 -56.000142) (xy 113.358168 -55.002684)
				(arc
					(start 113.241328 -55.002684)
					(mid 113.000028 -55.241457)
					(end 112.758728 -55.002684)
				)
				(arc
					(start 112.758728 -55.000144)
					(mid 113.000028 -54.758844)
					(end 113.241328 -55.000144)
				)
			)
		)
	)
	(zone
		(layers "In2.Cu" "In5.Cu")
		(hatch none 0.5)
		(connect_pads
			(clearance 0)
		)
		(min_thickness 0.25)
		(keepout
			(tracks not_allowed)
			(vias allowed)
			(pads allowed)
			(copperpour not_allowed)
			(footprints allowed)
		)
		(placement
			(enabled no)
			(sheetname "")
		)
		(fill yes
			(thermal_gap 0.5)
			(thermal_bridge_width 0.5)
			(island_removal_mode 0)
		)
		(polygon
			(pts
				(arc
					(start 126.000256 -69.641974)
					(mid 125.641862 -69.999987)
					(end 126.000002 -70.358254)
				)
				(arc
					(start 127 -70.358254)
					(mid 127.252344 -70.254254)
					(end 127.35814 -70.002654)
				)
				(arc
					(start 127.2413 -70.002654)
					(mid 127 -70.241427)
					(end 126.7587 -70.002654)
				)
				(arc
					(start 126.241302 -70.002654)
					(mid 126.000002 -70.241427)
					(end 125.758702 -70.002654)
				)
				(arc
					(start 125.758702 -70.000114)
					(mid 126.000002 -69.758814)
					(end 126.241302 -70.000114)
				)
				(arc
					(start 126.7587 -70.000114)
					(mid 127 -69.758814)
					(end 127.2413 -70.000114)
				)
				(arc
					(start 127.35814 -70.000114)
					(mid 127.253243 -69.746871)
					(end 127 -69.641974)
				)
			)
		)
	)
	(zone
		(layers "In2.Cu" "In5.Cu")
		(hatch none 0.5)
		(connect_pads
			(clearance 0)
		)
		(min_thickness 0.25)
		(keepout
			(tracks not_allowed)
			(vias allowed)
			(pads allowed)
			(copperpour not_allowed)
			(footprints allowed)
		)
		(placement
			(enabled no)
			(sheetname "")
		)
		(fill yes
			(thermal_gap 0.5)
			(thermal_bridge_width 0.5)
			(island_removal_mode 0)
		)
		(polygon
			(pts
				(arc
					(start 126.000256 -61.64199)
					(mid 125.641862 -62.000003)
					(end 126.000002 -62.35827)
				)
				(arc
					(start 127 -62.35827)
					(mid 127.252344 -62.25427)
					(end 127.35814 -62.00267)
				)
				(arc
					(start 127.2413 -62.00267)
					(mid 127 -62.241443)
					(end 126.7587 -62.00267)
				)
				(arc
					(start 126.241302 -62.00267)
					(mid 126.000002 -62.241443)
					(end 125.758702 -62.00267)
				)
				(arc
					(start 125.758702 -62.00013)
					(mid 126.000002 -61.75883)
					(end 126.241302 -62.00013)
				)
				(arc
					(start 126.7587 -62.00013)
					(mid 127 -61.75883)
					(end 127.2413 -62.00013)
				)
				(arc
					(start 127.35814 -62.00013)
					(mid 127.253243 -61.746887)
					(end 127 -61.64199)
				)
			)
		)
	)
	(zone
		(layers "In2.Cu" "In5.Cu")
		(hatch none 0.5)
		(connect_pads
			(clearance 0)
		)
		(min_thickness 0.25)
		(keepout
			(tracks not_allowed)
			(vias allowed)
			(pads allowed)
			(copperpour not_allowed)
			(footprints allowed)
		)
		(placement
			(enabled no)
			(sheetname "")
		)
		(fill yes
			(thermal_gap 0.5)
			(thermal_bridge_width 0.5)
			(island_removal_mode 0)
		)
		(polygon
			(pts
				(arc
					(start 120.358154 -55.000144)
					(mid 120.000014 -54.642004)
					(end 119.641874 -55.000144)
				)
				(arc
					(start 119.641874 -55.999888)
					(mid 119.998617 -56.358279)
					(end 120.358154 -56.002682)
				)
				(arc
					(start 120.241314 -56.002682)
					(mid 120.000014 -56.241455)
					(end 119.758714 -56.002682)
				)
				(arc
					(start 119.758714 -56.000142)
					(mid 120.000014 -55.758842)
					(end 120.241314 -56.000142)
				)
				(xy 120.358154 -56.000142) (xy 120.358154 -55.002684)
				(arc
					(start 120.241314 -55.002684)
					(mid 120.000014 -55.241457)
					(end 119.758714 -55.002684)
				)
				(arc
					(start 119.758714 -55.000144)
					(mid 120.000014 -54.758844)
					(end 120.241314 -55.000144)
				)
			)
		)
	)
	(zone
		(layers "In2.Cu" "In5.Cu")
		(hatch none 0.5)
		(connect_pads
			(clearance 0)
		)
		(min_thickness 0.25)
		(keepout
			(tracks not_allowed)
			(vias allowed)
			(pads allowed)
			(copperpour not_allowed)
			(footprints allowed)
		)
		(placement
			(enabled no)
			(sheetname "")
		)
		(fill yes
			(thermal_gap 0.5)
			(thermal_bridge_width 0.5)
			(island_removal_mode 0)
		)
		(polygon
			(pts
				(arc
					(start 110.358174 -55.000144)
					(mid 110.000034 -54.642004)
					(end 109.641894 -55.000144)
				)
				(arc
					(start 109.641894 -55.999888)
					(mid 109.998637 -56.358279)
					(end 110.358174 -56.002682)
				)
				(arc
					(start 110.241334 -56.002682)
					(mid 110.000034 -56.241455)
					(end 109.758734 -56.002682)
				)
				(arc
					(start 109.758734 -56.000142)
					(mid 110.000034 -55.758842)
					(end 110.241334 -56.000142)
				)
				(xy 110.358174 -56.000142) (xy 110.358174 -55.002684)
				(arc
					(start 110.241334 -55.002684)
					(mid 110.000034 -55.241457)
					(end 109.758734 -55.002684)
				)
				(arc
					(start 109.758734 -55.000144)
					(mid 110.000034 -54.758844)
					(end 110.241334 -55.000144)
				)
			)
		)
	)
	(zone
		(layers "In2.Cu" "In5.Cu")
		(hatch none 0.5)
		(connect_pads
			(clearance 0)
		)
		(min_thickness 0.25)
		(keepout
			(tracks not_allowed)
			(vias allowed)
			(pads allowed)
			(copperpour not_allowed)
			(footprints allowed)
		)
		(placement
			(enabled no)
			(sheetname "")
		)
		(fill yes
			(thermal_gap 0.5)
			(thermal_bridge_width 0.5)
			(island_removal_mode 0)
		)
		(polygon
			(pts
				(arc
					(start 126.000256 -64.641984)
					(mid 125.641862 -64.999997)
					(end 126.000002 -65.358264)
				)
				(arc
					(start 127 -65.358264)
					(mid 127.252344 -65.254264)
					(end 127.35814 -65.002664)
				)
				(arc
					(start 127.2413 -65.002664)
					(mid 127 -65.241437)
					(end 126.7587 -65.002664)
				)
				(arc
					(start 126.241302 -65.002664)
					(mid 126.000002 -65.241437)
					(end 125.758702 -65.002664)
				)
				(arc
					(start 125.758702 -65.000124)
					(mid 126.000002 -64.758824)
					(end 126.241302 -65.000124)
				)
				(arc
					(start 126.7587 -65.000124)
					(mid 127 -64.758824)
					(end 127.2413 -65.000124)
				)
				(arc
					(start 127.35814 -65.000124)
					(mid 127.253243 -64.746881)
					(end 127 -64.641984)
				)
			)
		)
	)
	(zone
		(layers "In2.Cu" "In5.Cu")
		(hatch none 0.5)
		(connect_pads
			(clearance 0)
		)
		(min_thickness 0.25)
		(keepout
			(tracks not_allowed)
			(vias allowed)
			(pads allowed)
			(copperpour not_allowed)
			(footprints allowed)
		)
		(placement
			(enabled no)
			(sheetname "")
		)
		(fill yes
			(thermal_gap 0.5)
			(thermal_bridge_width 0.5)
			(island_removal_mode 0)
		)
		(polygon
			(pts
				(arc
					(start 126.000256 -60.641992)
					(mid 125.641862 -61.000005)
					(end 126.000002 -61.358272)
				)
				(arc
					(start 127 -61.358272)
					(mid 127.252344 -61.254272)
					(end 127.35814 -61.002672)
				)
				(arc
					(start 127.2413 -61.002672)
					(mid 127 -61.241445)
					(end 126.7587 -61.002672)
				)
				(arc
					(start 126.241302 -61.002672)
					(mid 126.000002 -61.241445)
					(end 125.758702 -61.002672)
				)
				(arc
					(start 125.758702 -61.000132)
					(mid 126.000002 -60.758832)
					(end 126.241302 -61.000132)
				)
				(arc
					(start 126.7587 -61.000132)
					(mid 127 -60.758832)
					(end 127.2413 -61.000132)
				)
				(arc
					(start 127.35814 -61.000132)
					(mid 127.253243 -60.746889)
					(end 127 -60.641992)
				)
			)
		)
	)
	(zone
		(layers "In2.Cu" "In5.Cu")
		(hatch none 0.5)
		(connect_pads
			(clearance 0)
		)
		(min_thickness 0.25)
		(keepout
			(tracks not_allowed)
			(vias allowed)
			(pads allowed)
			(copperpour not_allowed)
			(footprints allowed)
		)
		(placement
			(enabled no)
			(sheetname "")
		)
		(fill yes
			(thermal_gap 0.5)
			(thermal_bridge_width 0.5)
			(island_removal_mode 0)
		)
		(polygon
			(pts
				(arc
					(start 126.000256 -70.641972)
					(mid 125.641862 -70.999985)
					(end 126.000002 -71.358252)
				)
				(arc
					(start 127 -71.358252)
					(mid 127.252344 -71.254252)
					(end 127.35814 -71.002652)
				)
				(arc
					(start 127.2413 -71.002652)
					(mid 127 -71.241425)
					(end 126.7587 -71.002652)
				)
				(arc
					(start 126.241302 -71.002652)
					(mid 126.000002 -71.241425)
					(end 125.758702 -71.002652)
				)
				(arc
					(start 125.758702 -71.000112)
					(mid 126.000002 -70.758812)
					(end 126.241302 -71.000112)
				)
				(arc
					(start 126.7587 -71.000112)
					(mid 127 -70.758812)
					(end 127.2413 -71.000112)
				)
				(arc
					(start 127.35814 -71.000112)
					(mid 127.253243 -70.746869)
					(end 127 -70.641972)
				)
			)
		)
	)
	(zone
		(layers "In2.Cu" "In5.Cu")
		(hatch none 0.5)
		(connect_pads
			(clearance 0)
		)
		(min_thickness 0.25)
		(keepout
			(tracks not_allowed)
			(vias allowed)
			(pads allowed)
			(copperpour not_allowed)
			(footprints allowed)
		)
		(placement
			(enabled no)
			(sheetname "")
		)
		(fill yes
			(thermal_gap 0.5)
			(thermal_bridge_width 0.5)
			(island_removal_mode 0)
		)
		(polygon
			(pts
				(arc
					(start 111.358172 -55.000144)
					(mid 111.000032 -54.642004)
					(end 110.641892 -55.000144)
				)
				(arc
					(start 110.641892 -55.999888)
					(mid 110.998635 -56.358279)
					(end 111.358172 -56.002682)
				)
				(arc
					(start 111.241332 -56.002682)
					(mid 111.000032 -56.241455)
					(end 110.758732 -56.002682)
				)
				(arc
					(start 110.758732 -56.000142)
					(mid 111.000032 -55.758842)
					(end 111.241332 -56.000142)
				)
				(xy 111.358172 -56.000142) (xy 111.358172 -55.002684)
				(arc
					(start 111.241332 -55.002684)
					(mid 111.000032 -55.241457)
					(end 110.758732 -55.002684)
				)
				(arc
					(start 110.758732 -55.000144)
					(mid 111.000032 -54.758844)
					(end 111.241332 -55.000144)
				)
			)
		)
	)
	(zone
		(layers "In2.Cu" "In5.Cu")
		(hatch none 0.5)
		(connect_pads
			(clearance 0)
		)
		(min_thickness 0.25)
		(keepout
			(tracks not_allowed)
			(vias allowed)
			(pads allowed)
			(copperpour not_allowed)
			(footprints allowed)
		)
		(placement
			(enabled no)
			(sheetname "")
		)
		(fill yes
			(thermal_gap 0.5)
			(thermal_bridge_width 0.5)
			(island_removal_mode 0)
		)
		(polygon
			(pts
				(arc
					(start 106.358182 -55.000144)
					(mid 106.000042 -54.642004)
					(end 105.641902 -55.000144)
				)
				(arc
					(start 105.641902 -55.999888)
					(mid 105.998645 -56.358279)
					(end 106.358182 -56.002682)
				)
				(arc
					(start 106.241342 -56.002682)
					(mid 106.000042 -56.241455)
					(end 105.758742 -56.002682)
				)
				(arc
					(start 105.758742 -56.000142)
					(mid 106.000042 -55.758842)
					(end 106.241342 -56.000142)
				)
				(xy 106.358182 -56.000142) (xy 106.358182 -55.002684)
				(arc
					(start 106.241342 -55.002684)
					(mid 106.000042 -55.241457)
					(end 105.758742 -55.002684)
				)
				(arc
					(start 105.758742 -55.000144)
					(mid 106.000042 -54.758844)
					(end 106.241342 -55.000144)
				)
			)
		)
	)
	(zone
		(layers "In2.Cu" "In5.Cu")
		(hatch none 0.5)
		(connect_pads
			(clearance 0)
		)
		(min_thickness 0.25)
		(keepout
			(tracks not_allowed)
			(vias allowed)
			(pads allowed)
			(copperpour not_allowed)
			(footprints allowed)
		)
		(placement
			(enabled no)
			(sheetname "")
		)
		(fill yes
			(thermal_gap 0.5)
			(thermal_bridge_width 0.5)
			(island_removal_mode 0)
		)
		(polygon
			(pts
				(arc
					(start 168.157906 -30.39999)
					(mid 167.799639 -30.04185)
					(end 167.441626 -30.400244)
				)
				(arc
					(start 167.44188 -31.199582)
					(mid 167.798623 -31.557973)
					(end 168.15816 -31.202376)
				)
				(arc
					(start 168.04132 -31.202376)
					(mid 167.80002 -31.441149)
					(end 167.55872 -31.202376)
				)
				(arc
					(start 167.55872 -31.199836)
					(mid 167.80002 -30.958536)
					(end 168.04132 -31.199836)
				)
				(xy 168.15816 -31.199836) (xy 168.15816 -31.199582) (xy 168.157906 -30.64129) (xy 168.157906 -30.40253)
				(arc
					(start 168.041066 -30.40253)
					(mid 167.799766 -30.641303)
					(end 167.558466 -30.40253)
				)
				(arc
					(start 167.558466 -30.39999)
					(mid 167.799766 -30.15869)
					(end 168.041066 -30.39999)
				)
			)
		)
	)
	(zone
		(layers "In2.Cu" "In5.Cu")
		(hatch none 0.5)
		(connect_pads
			(clearance 0)
		)
		(min_thickness 0.25)
		(keepout
			(tracks not_allowed)
			(vias allowed)
			(pads allowed)
			(copperpour not_allowed)
			(footprints allowed)
		)
		(placement
			(enabled no)
			(sheetname "")
		)
		(fill yes
			(thermal_gap 0.5)
			(thermal_bridge_width 0.5)
			(island_removal_mode 0)
		)
		(polygon
			(pts
				(arc
					(start 99.358196 -54.000146)
					(mid 99.000056 -53.642006)
					(end 98.641916 -54.000146)
				)
				(arc
					(start 98.641916 -54.99989)
					(mid 98.998659 -55.358281)
					(end 99.358196 -55.002684)
				)
				(arc
					(start 99.241356 -55.002684)
					(mid 99.000056 -55.241457)
					(end 98.758756 -55.002684)
				)
				(arc
					(start 98.758756 -55.000144)
					(mid 99.000056 -54.758844)
					(end 99.241356 -55.000144)
				)
				(xy 99.358196 -55.000144) (xy 99.358196 -54.002686)
				(arc
					(start 99.241356 -54.002686)
					(mid 99.000056 -54.241459)
					(end 98.758756 -54.002686)
				)
				(arc
					(start 98.758756 -54.000146)
					(mid 99.000056 -53.758846)
					(end 99.241356 -54.000146)
				)
			)
		)
	)
	(zone
		(layers "In2.Cu" "In5.Cu")
		(hatch none 0.5)
		(connect_pads
			(clearance 0)
		)
		(min_thickness 0.25)
		(keepout
			(tracks not_allowed)
			(vias allowed)
			(pads allowed)
			(copperpour not_allowed)
			(footprints allowed)
		)
		(placement
			(enabled no)
			(sheetname "")
		)
		(fill yes
			(thermal_gap 0.5)
			(thermal_bridge_width 0.5)
			(island_removal_mode 0)
		)
		(polygon
			(pts
				(arc
					(start 126.000256 -76.64196)
					(mid 125.641862 -76.999973)
					(end 126.000002 -77.35824)
				)
				(arc
					(start 127 -77.35824)
					(mid 127.252344 -77.25424)
					(end 127.35814 -77.00264)
				)
				(arc
					(start 127.2413 -77.00264)
					(mid 127 -77.241413)
					(end 126.7587 -77.00264)
				)
				(arc
					(start 126.241302 -77.00264)
					(mid 126.000002 -77.241413)
					(end 125.758702 -77.00264)
				)
				(arc
					(start 125.758702 -77.0001)
					(mid 126.000002 -76.7588)
					(end 126.241302 -77.0001)
				)
				(arc
					(start 126.7587 -77.0001)
					(mid 127 -76.7588)
					(end 127.2413 -77.0001)
				)
				(arc
					(start 127.35814 -77.0001)
					(mid 127.253243 -76.746857)
					(end 127 -76.64196)
				)
			)
		)
	)
	(zone
		(layers "In2.Cu" "In5.Cu")
		(hatch none 0.5)
		(connect_pads
			(clearance 0)
		)
		(min_thickness 0.25)
		(keepout
			(tracks not_allowed)
			(vias allowed)
			(pads allowed)
			(copperpour not_allowed)
			(footprints allowed)
		)
		(placement
			(enabled no)
			(sheetname "")
		)
		(fill yes
			(thermal_gap 0.5)
			(thermal_bridge_width 0.5)
			(island_removal_mode 0)
		)
		(polygon
			(pts
				(arc
					(start 116.358162 -55.000144)
					(mid 116.000022 -54.642004)
					(end 115.641882 -55.000144)
				)
				(arc
					(start 115.641882 -55.999888)
					(mid 115.998625 -56.358279)
					(end 116.358162 -56.002682)
				)
				(arc
					(start 116.241322 -56.002682)
					(mid 116.000022 -56.241455)
					(end 115.758722 -56.002682)
				)
				(arc
					(start 115.758722 -56.000142)
					(mid 116.000022 -55.758842)
					(end 116.241322 -56.000142)
				)
				(xy 116.358162 -56.000142) (xy 116.358162 -55.002684)
				(arc
					(start 116.241322 -55.002684)
					(mid 116.000022 -55.241457)
					(end 115.758722 -55.002684)
				)
				(arc
					(start 115.758722 -55.000144)
					(mid 116.000022 -54.758844)
					(end 116.241322 -55.000144)
				)
			)
		)
	)
	(zone
		(layers "In2.Cu" "In5.Cu")
		(hatch none 0.5)
		(connect_pads
			(clearance 0)
		)
		(min_thickness 0.25)
		(keepout
			(tracks not_allowed)
			(vias allowed)
			(pads allowed)
			(copperpour not_allowed)
			(footprints allowed)
		)
		(placement
			(enabled no)
			(sheetname "")
		)
		(fill yes
			(thermal_gap 0.5)
			(thermal_bridge_width 0.5)
			(island_removal_mode 0)
		)
		(polygon
			(pts
				(arc
					(start 171.358052 -30.39999)
					(mid 170.999785 -30.04185)
					(end 170.641772 -30.400244)
				)
				(arc
					(start 170.642026 -31.199836)
					(mid 170.998769 -31.558227)
					(end 171.358306 -31.20263)
				)
				(arc
					(start 171.241466 -31.20263)
					(mid 171.000166 -31.441403)
					(end 170.758866 -31.20263)
				)
				(arc
					(start 170.758866 -31.20009)
					(mid 171.000166 -30.95879)
					(end 171.241466 -31.20009)
				)
				(xy 171.358306 -31.20009) (xy 171.358306 -31.199836) (xy 171.358052 -30.64129) (xy 171.358052 -30.40253)
				(arc
					(start 171.241212 -30.40253)
					(mid 170.999912 -30.641303)
					(end 170.758612 -30.40253)
				)
				(arc
					(start 170.758612 -30.39999)
					(mid 170.999912 -30.15869)
					(end 171.241212 -30.39999)
				)
			)
		)
	)
	(zone
		(layers "In2.Cu" "In5.Cu")
		(hatch none 0.5)
		(connect_pads
			(clearance 0)
		)
		(min_thickness 0.25)
		(keepout
			(tracks not_allowed)
			(vias allowed)
			(pads allowed)
			(copperpour not_allowed)
			(footprints allowed)
		)
		(placement
			(enabled no)
			(sheetname "")
		)
		(fill yes
			(thermal_gap 0.5)
			(thermal_bridge_width 0.5)
			(island_removal_mode 0)
		)
		(polygon
			(pts
				(arc
					(start 112.35817 -55.000144)
					(mid 112.00003 -54.642004)
					(end 111.64189 -55.000144)
				)
				(arc
					(start 111.64189 -55.999888)
					(mid 111.998633 -56.358279)
					(end 112.35817 -56.002682)
				)
				(arc
					(start 112.24133 -56.002682)
					(mid 112.00003 -56.241455)
					(end 111.75873 -56.002682)
				)
				(arc
					(start 111.75873 -56.000142)
					(mid 112.00003 -55.758842)
					(end 112.24133 -56.000142)
				)
				(xy 112.35817 -56.000142) (xy 112.35817 -55.002684)
				(arc
					(start 112.24133 -55.002684)
					(mid 112.00003 -55.241457)
					(end 111.75873 -55.002684)
				)
				(arc
					(start 111.75873 -55.000144)
					(mid 112.00003 -54.758844)
					(end 112.24133 -55.000144)
				)
			)
		)
	)
	(zone
		(layers "In2.Cu" "In5.Cu")
		(hatch none 0.5)
		(connect_pads
			(clearance 0)
		)
		(min_thickness 0.25)
		(keepout
			(tracks not_allowed)
			(vias allowed)
			(pads allowed)
			(copperpour not_allowed)
			(footprints allowed)
		)
		(placement
			(enabled no)
			(sheetname "")
		)
		(fill yes
			(thermal_gap 0.5)
			(thermal_bridge_width 0.5)
			(island_removal_mode 0)
		)
		(polygon
			(pts
				(arc
					(start 103.358188 -55.000144)
					(mid 103.000048 -54.642004)
					(end 102.641908 -55.000144)
				)
				(arc
					(start 102.641908 -55.999888)
					(mid 102.998651 -56.358279)
					(end 103.358188 -56.002682)
				)
				(arc
					(start 103.241348 -56.002682)
					(mid 103.000048 -56.241455)
					(end 102.758748 -56.002682)
				)
				(arc
					(start 102.758748 -56.000142)
					(mid 103.000048 -55.758842)
					(end 103.241348 -56.000142)
				)
				(xy 103.358188 -56.000142) (xy 103.358188 -55.002684)
				(arc
					(start 103.241348 -55.002684)
					(mid 103.000048 -55.241457)
					(end 102.758748 -55.002684)
				)
				(arc
					(start 102.758748 -55.000144)
					(mid 103.000048 -54.758844)
					(end 103.241348 -55.000144)
				)
			)
		)
	)
	(zone
		(layers "In2.Cu" "In5.Cu")
		(hatch none 0.5)
		(connect_pads
			(clearance 0)
		)
		(min_thickness 0.25)
		(keepout
			(tracks not_allowed)
			(vias allowed)
			(pads allowed)
			(copperpour not_allowed)
			(footprints allowed)
		)
		(placement
			(enabled no)
			(sheetname "")
		)
		(fill yes
			(thermal_gap 0.5)
			(thermal_bridge_width 0.5)
			(island_removal_mode 0)
		)
		(polygon
			(pts
				(arc
					(start 126.000256 -68.641976)
					(mid 125.641862 -68.999989)
					(end 126.000002 -69.358256)
				)
				(arc
					(start 127 -69.358256)
					(mid 127.252344 -69.254256)
					(end 127.35814 -69.002656)
				)
				(arc
					(start 127.2413 -69.002656)
					(mid 127 -69.241429)
					(end 126.7587 -69.002656)
				)
				(arc
					(start 126.241302 -69.002656)
					(mid 126.000002 -69.241429)
					(end 125.758702 -69.002656)
				)
				(arc
					(start 125.758702 -69.000116)
					(mid 126.000002 -68.758816)
					(end 126.241302 -69.000116)
				)
				(arc
					(start 126.7587 -69.000116)
					(mid 127 -68.758816)
					(end 127.2413 -69.000116)
				)
				(arc
					(start 127.35814 -69.000116)
					(mid 127.253243 -68.746873)
					(end 127 -68.641976)
				)
			)
		)
	)
	(zone
		(layers "In2.Cu" "In5.Cu")
		(hatch none 0.5)
		(connect_pads
			(clearance 0)
		)
		(min_thickness 0.25)
		(keepout
			(tracks not_allowed)
			(vias allowed)
			(pads allowed)
			(copperpour not_allowed)
			(footprints allowed)
		)
		(placement
			(enabled no)
			(sheetname "")
		)
		(fill yes
			(thermal_gap 0.5)
			(thermal_bridge_width 0.5)
			(island_removal_mode 0)
		)
		(polygon
			(pts
				(arc
					(start 126.000256 -75.641962)
					(mid 125.641862 -75.999975)
					(end 126.000002 -76.358242)
				)
				(arc
					(start 127 -76.358242)
					(mid 127.252344 -76.254242)
					(end 127.35814 -76.002642)
				)
				(arc
					(start 127.2413 -76.002642)
					(mid 127 -76.241415)
					(end 126.7587 -76.002642)
				)
				(arc
					(start 126.241302 -76.002642)
					(mid 126.000002 -76.241415)
					(end 125.758702 -76.002642)
				)
				(arc
					(start 125.758702 -76.000102)
					(mid 126.000002 -75.758802)
					(end 126.241302 -76.000102)
				)
				(arc
					(start 126.7587 -76.000102)
					(mid 127 -75.758802)
					(end 127.2413 -76.000102)
				)
				(arc
					(start 127.35814 -76.000102)
					(mid 127.253243 -75.746859)
					(end 127 -75.641962)
				)
			)
		)
	)
	(zone
		(layers "In2.Cu" "In5.Cu")
		(hatch none 0.5)
		(connect_pads
			(clearance 0)
		)
		(min_thickness 0.25)
		(keepout
			(tracks not_allowed)
			(vias allowed)
			(pads allowed)
			(copperpour not_allowed)
			(footprints allowed)
		)
		(placement
			(enabled no)
			(sheetname "")
		)
		(fill yes
			(thermal_gap 0.5)
			(thermal_bridge_width 0.5)
			(island_removal_mode 0)
		)
		(polygon
			(pts
				(arc
					(start 117.35816 -55.000144)
					(mid 117.00002 -54.642004)
					(end 116.64188 -55.000144)
				)
				(arc
					(start 116.64188 -55.999888)
					(mid 116.998623 -56.358279)
					(end 117.35816 -56.002682)
				)
				(arc
					(start 117.24132 -56.002682)
					(mid 117.00002 -56.241455)
					(end 116.75872 -56.002682)
				)
				(arc
					(start 116.75872 -56.000142)
					(mid 117.00002 -55.758842)
					(end 117.24132 -56.000142)
				)
				(xy 117.35816 -56.000142) (xy 117.35816 -55.002684)
				(arc
					(start 117.24132 -55.002684)
					(mid 117.00002 -55.241457)
					(end 116.75872 -55.002684)
				)
				(arc
					(start 116.75872 -55.000144)
					(mid 117.00002 -54.758844)
					(end 117.24132 -55.000144)
				)
			)
		)
	)
	(zone
		(layers "In2.Cu" "In5.Cu")
		(hatch none 0.5)
		(connect_pads
			(clearance 0)
		)
		(min_thickness 0.25)
		(keepout
			(tracks not_allowed)
			(vias allowed)
			(pads allowed)
			(copperpour not_allowed)
			(footprints allowed)
		)
		(placement
			(enabled no)
			(sheetname "")
		)
		(fill yes
			(thermal_gap 0.5)
			(thermal_bridge_width 0.5)
			(island_removal_mode 0)
		)
		(polygon
			(pts
				(arc
					(start 126.000256 -67.641978)
					(mid 125.641862 -67.999991)
					(end 126.000002 -68.358258)
				)
				(arc
					(start 127 -68.358258)
					(mid 127.252344 -68.254258)
					(end 127.35814 -68.002658)
				)
				(arc
					(start 127.2413 -68.002658)
					(mid 127 -68.241431)
					(end 126.7587 -68.002658)
				)
				(arc
					(start 126.241302 -68.002658)
					(mid 126.000002 -68.241431)
					(end 125.758702 -68.002658)
				)
				(arc
					(start 125.758702 -68.000118)
					(mid 126.000002 -67.758818)
					(end 126.241302 -68.000118)
				)
				(arc
					(start 126.7587 -68.000118)
					(mid 127 -67.758818)
					(end 127.2413 -68.000118)
				)
				(arc
					(start 127.35814 -68.000118)
					(mid 127.253243 -67.746875)
					(end 127 -67.641978)
				)
			)
		)
	)
	(zone
		(layers "In2.Cu" "In5.Cu")
		(hatch none 0.5)
		(connect_pads
			(clearance 0)
		)
		(min_thickness 0.25)
		(keepout
			(tracks not_allowed)
			(vias allowed)
			(pads allowed)
			(copperpour not_allowed)
			(footprints allowed)
		)
		(placement
			(enabled no)
			(sheetname "")
		)
		(fill yes
			(thermal_gap 0.5)
			(thermal_bridge_width 0.5)
			(island_removal_mode 0)
		)
		(polygon
			(pts
				(arc
					(start 172.957998 -30.39999)
					(mid 172.599731 -30.04185)
					(end 172.241718 -30.400244)
				)
				(arc
					(start 172.241972 -31.199836)
					(mid 172.598715 -31.558227)
					(end 172.958252 -31.20263)
				)
				(arc
					(start 172.841412 -31.20263)
					(mid 172.600112 -31.441403)
					(end 172.358812 -31.20263)
				)
				(arc
					(start 172.358812 -31.20009)
					(mid 172.600112 -30.95879)
					(end 172.841412 -31.20009)
				)
				(xy 172.958252 -31.20009) (xy 172.958252 -31.199836) (xy 172.957998 -30.64129) (xy 172.957998 -30.40253)
				(arc
					(start 172.841158 -30.40253)
					(mid 172.599858 -30.641303)
					(end 172.358558 -30.40253)
				)
				(arc
					(start 172.358558 -30.39999)
					(mid 172.599858 -30.15869)
					(end 172.841158 -30.39999)
				)
			)
		)
	)
	(zone
		(layers "In2.Cu" "In5.Cu")
		(hatch none 0.5)
		(connect_pads
			(clearance 0)
		)
		(min_thickness 0.25)
		(keepout
			(tracks not_allowed)
			(vias allowed)
			(pads allowed)
			(copperpour not_allowed)
			(footprints allowed)
		)
		(placement
			(enabled no)
			(sheetname "")
		)
		(fill yes
			(thermal_gap 0.5)
			(thermal_bridge_width 0.5)
			(island_removal_mode 0)
		)
		(polygon
			(pts
				(arc
					(start 118.358158 -55.000144)
					(mid 118.000018 -54.642004)
					(end 117.641878 -55.000144)
				)
				(arc
					(start 117.641878 -55.999888)
					(mid 117.998621 -56.358279)
					(end 118.358158 -56.002682)
				)
				(arc
					(start 118.241318 -56.002682)
					(mid 118.000018 -56.241455)
					(end 117.758718 -56.002682)
				)
				(arc
					(start 117.758718 -56.000142)
					(mid 118.000018 -55.758842)
					(end 118.241318 -56.000142)
				)
				(xy 118.358158 -56.000142) (xy 118.358158 -55.002684)
				(arc
					(start 118.241318 -55.002684)
					(mid 118.000018 -55.241457)
					(end 117.758718 -55.002684)
				)
				(arc
					(start 117.758718 -55.000144)
					(mid 118.000018 -54.758844)
					(end 118.241318 -55.000144)
				)
			)
		)
	)
	(zone
		(layers "In2.Cu" "In5.Cu")
		(hatch none 0.5)
		(connect_pads
			(clearance 0)
		)
		(min_thickness 0.25)
		(keepout
			(tracks not_allowed)
			(vias allowed)
			(pads allowed)
			(copperpour not_allowed)
			(footprints allowed)
		)
		(placement
			(enabled no)
			(sheetname "")
		)
		(fill yes
			(thermal_gap 0.5)
			(thermal_bridge_width 0.5)
			(island_removal_mode 0)
		)
		(polygon
			(pts
				(arc
					(start 124.358146 -55.000144)
					(mid 124.000006 -54.642004)
					(end 123.641866 -55.000144)
				)
				(arc
					(start 123.641866 -55.999888)
					(mid 123.998609 -56.358279)
					(end 124.358146 -56.002682)
				)
				(arc
					(start 124.241306 -56.002682)
					(mid 124.000006 -56.241455)
					(end 123.758706 -56.002682)
				)
				(arc
					(start 123.758706 -56.000142)
					(mid 124.000006 -55.758842)
					(end 124.241306 -56.000142)
				)
				(xy 124.358146 -56.000142) (xy 124.358146 -55.002684)
				(arc
					(start 124.241306 -55.002684)
					(mid 124.000006 -55.241457)
					(end 123.758706 -55.002684)
				)
				(arc
					(start 123.758706 -55.000144)
					(mid 124.000006 -54.758844)
					(end 124.241306 -55.000144)
				)
			)
		)
	)
	(zone
		(layers "In2.Cu" "In5.Cu")
		(hatch none 0.5)
		(connect_pads
			(clearance 0)
		)
		(min_thickness 0.25)
		(keepout
			(tracks not_allowed)
			(vias allowed)
			(pads allowed)
			(copperpour not_allowed)
			(footprints allowed)
		)
		(placement
			(enabled no)
			(sheetname "")
		)
		(fill yes
			(thermal_gap 0.5)
			(thermal_bridge_width 0.5)
			(island_removal_mode 0)
		)
		(polygon
			(pts
				(arc
					(start 121.358152 -55.000144)
					(mid 121.000012 -54.642004)
					(end 120.641872 -55.000144)
				)
				(arc
					(start 120.641872 -55.999888)
					(mid 120.998615 -56.358279)
					(end 121.358152 -56.002682)
				)
				(arc
					(start 121.241312 -56.002682)
					(mid 121.000012 -56.241455)
					(end 120.758712 -56.002682)
				)
				(arc
					(start 120.758712 -56.000142)
					(mid 121.000012 -55.758842)
					(end 121.241312 -56.000142)
				)
				(xy 121.358152 -56.000142) (xy 121.358152 -55.002684)
				(arc
					(start 121.241312 -55.002684)
					(mid 121.000012 -55.241457)
					(end 120.758712 -55.002684)
				)
				(arc
					(start 120.758712 -55.000144)
					(mid 121.000012 -54.758844)
					(end 121.241312 -55.000144)
				)
			)
		)
	)
	(zone
		(layers "In2.Cu" "In5.Cu")
		(hatch none 0.5)
		(connect_pads
			(clearance 0)
		)
		(min_thickness 0.25)
		(keepout
			(tracks not_allowed)
			(vias allowed)
			(pads allowed)
			(copperpour not_allowed)
			(footprints allowed)
		)
		(placement
			(enabled no)
			(sheetname "")
		)
		(fill yes
			(thermal_gap 0.5)
			(thermal_bridge_width 0.5)
			(island_removal_mode 0)
		)
		(polygon
			(pts
				(arc
					(start 126.000256 -73.641966)
					(mid 125.641862 -73.999979)
					(end 126.000002 -74.358246)
				)
				(arc
					(start 127 -74.358246)
					(mid 127.252344 -74.254246)
					(end 127.35814 -74.002646)
				)
				(arc
					(start 127.2413 -74.002646)
					(mid 127 -74.241419)
					(end 126.7587 -74.002646)
				)
				(arc
					(start 126.241302 -74.002646)
					(mid 126.000002 -74.241419)
					(end 125.758702 -74.002646)
				)
				(arc
					(start 125.758702 -74.000106)
					(mid 126.000002 -73.758806)
					(end 126.241302 -74.000106)
				)
				(arc
					(start 126.7587 -74.000106)
					(mid 127 -73.758806)
					(end 127.2413 -74.000106)
				)
				(arc
					(start 127.35814 -74.000106)
					(mid 127.253243 -73.746863)
					(end 127 -73.641966)
				)
			)
		)
	)
	(zone
		(layers "In2.Cu" "In5.Cu")
		(hatch none 0.5)
		(connect_pads
			(clearance 0)
		)
		(min_thickness 0.25)
		(keepout
			(tracks not_allowed)
			(vias allowed)
			(pads allowed)
			(copperpour not_allowed)
			(footprints allowed)
		)
		(placement
			(enabled no)
			(sheetname "")
		)
		(fill yes
			(thermal_gap 0.5)
			(thermal_bridge_width 0.5)
			(island_removal_mode 0)
		)
		(polygon
			(pts
				(arc
					(start 101.358192 -55.000144)
					(mid 101.000052 -54.642004)
					(end 100.641912 -55.000144)
				)
				(arc
					(start 100.641912 -55.999888)
					(mid 100.998655 -56.358279)
					(end 101.358192 -56.002682)
				)
				(arc
					(start 101.241352 -56.002682)
					(mid 101.000052 -56.241455)
					(end 100.758752 -56.002682)
				)
				(arc
					(start 100.758752 -56.000142)
					(mid 101.000052 -55.758842)
					(end 101.241352 -56.000142)
				)
				(xy 101.358192 -56.000142) (xy 101.358192 -55.002684)
				(arc
					(start 101.241352 -55.002684)
					(mid 101.000052 -55.241457)
					(end 100.758752 -55.002684)
				)
				(arc
					(start 100.758752 -55.000144)
					(mid 101.000052 -54.758844)
					(end 101.241352 -55.000144)
				)
			)
		)
	)
	(zone
		(layers "In2.Cu" "In5.Cu")
		(hatch none 0.5)
		(connect_pads
			(clearance 0)
		)
		(min_thickness 0.25)
		(keepout
			(tracks not_allowed)
			(vias allowed)
			(pads allowed)
			(copperpour not_allowed)
			(footprints allowed)
		)
		(placement
			(enabled no)
			(sheetname "")
		)
		(fill yes
			(thermal_gap 0.5)
			(thermal_bridge_width 0.5)
			(island_removal_mode 0)
		)
		(polygon
			(pts
				(arc
					(start 114.358166 -55.000144)
					(mid 114.000026 -54.642004)
					(end 113.641886 -55.000144)
				)
				(arc
					(start 113.641886 -55.999888)
					(mid 113.998629 -56.358279)
					(end 114.358166 -56.002682)
				)
				(arc
					(start 114.241326 -56.002682)
					(mid 114.000026 -56.241455)
					(end 113.758726 -56.002682)
				)
				(arc
					(start 113.758726 -56.000142)
					(mid 114.000026 -55.758842)
					(end 114.241326 -56.000142)
				)
				(xy 114.358166 -56.000142) (xy 114.358166 -55.002684)
				(arc
					(start 114.241326 -55.002684)
					(mid 114.000026 -55.241457)
					(end 113.758726 -55.002684)
				)
				(arc
					(start 113.758726 -55.000144)
					(mid 114.000026 -54.758844)
					(end 114.241326 -55.000144)
				)
			)
		)
	)
	(zone
		(net "GND")
		(layer "In3.Cu")
		(hatch none 0.5)
		(connect_pads
			(clearance 0.5)
		)
		(min_thickness 0.25)
		(fill yes
			(thermal_gap 0.5)
			(thermal_bridge_width 0.5)
			(island_removal_mode 0)
		)
		(polygon
			(pts
				(xy 39.194994 -1.27) (xy 38.719252 -1.745742) (xy 38.719252 -23.445724) (xy 33.986978 -28.177998)
				(xy 33.986978 -36.973002) (xy 33.987232 -36.973256) (xy 33.987232 -37.131244) (xy 33.986978 -37.131498)
				(xy 33.986978 -60.339224) (xy 31.735776 -62.590426) (xy 31.735776 -83.588606) (xy 35.84067 -87.6935)
				(xy 50.492406 -87.6935) (xy 50.6095 -87.576406)
				(arc
					(start 50.6095 -55.15356)
					(mid 50.625894 -55.071544)
					(end 50.672238 -55.001922)
				)
				(xy 50.672746 -55.001414) (xy 59.1693 -46.504606) (xy 59.1693 -34.084006) (xy 59.763406 -33.4899)
				(xy 85.061806 -33.4899) (xy 88.516206 -30.0355) (xy 142.618968 -30.0355) (xy 143.261334 -30.677866)
				(xy 143.261334 -46.45152) (xy 142.282672 -47.430182) (xy 142.282672 -76.298298) (xy 140.86967 -77.7113)
				(xy 121.998994 -77.7113) (xy 121.700544 -78.00975) (xy 121.700544 -95.09125) (xy 121.882154 -95.27286)
				(xy 132.118354 -95.27286) (xy 133.926834 -97.08134) (xy 136.120886 -97.08134) (xy 138.302746 -94.89948)
				(xy 157.035246 -94.89948) (xy 157.3149 -94.619826) (xy 157.3149 -76.189586) (xy 154.506422 -73.381108)
				(xy 154.506422 -27.874976) (xy 156.028898 -26.3525) (xy 177.263806 -26.3525) (xy 177.746406 -25.8699)
				(xy 208.407508 -25.8699) (xy 208.730088 -25.54732)
				(arc
					(start 208.730088 -1.999996)
					(mid 208.516277 -1.483811)
					(end 208.000092 -1.27)
				)
			)
		)
		(polygon
			(pts
				(xy 139.986258 -81.924906) (xy 138.843512 -81.924906) (xy 138.843258 -81.92516)
				(arc
					(start 138.843258 -81.925668)
					(mid 138.46048 -82.308446)
					(end 138.843258 -82.691224)
				)
				(xy 138.843258 -82.691986) (xy 139.986258 -82.691986)
				(arc
					(start 139.986258 -82.691224)
					(mid 140.369036 -82.308446)
					(end 139.986258 -81.925668)
				)
			)
		)
		(polygon
			(pts
				(xy 139.643612 -79.813912) (xy 138.500866 -79.813912) (xy 138.500612 -79.814166)
				(arc
					(start 138.500612 -79.814674)
					(mid 138.117834 -80.197452)
					(end 138.500612 -80.58023)
				)
				(xy 138.500612 -80.580992) (xy 139.643612 -80.580992)
				(arc
					(start 139.643612 -80.58023)
					(mid 140.02639 -80.197452)
					(end 139.643612 -79.814674)
				)
			)
		)
		(polygon
			(pts
				(xy 139.629134 -78.044294) (xy 138.486134 -78.044294)
				(arc
					(start 138.486134 -78.045056)
					(mid 138.103356 -78.427834)
					(end 138.486134 -78.810612)
				)
				(xy 138.486134 -78.811374) (xy 139.62888 -78.811374) (xy 139.629134 -78.81112)
				(arc
					(start 139.629134 -78.810612)
					(mid 140.011912 -78.427834)
					(end 139.629134 -78.045056)
				)
			)
		)
		(polygon
			(pts
				(arc
					(start 150.087584 -54.478174)
					(mid 149.735286 -53.935884)
					(end 149.192996 -54.288182)
				)
				(arc
					(start 148.957792 -55.395876)
					(mid 149.302356 -55.947245)
					(end 149.84984 -55.596282)
				)
			)
		)
		(polygon
			(pts
				(arc
					(start 149.037294 -50.520092)
					(mid 148.69273 -49.968723)
					(end 148.145246 -50.319686)
				)
				(arc
					(start 147.907502 -51.437794)
					(mid 148.2598 -51.980084)
					(end 148.80209 -51.627786)
				)
			)
		)
		(polygon
			(pts
				(arc
					(start 147.989544 -46.551596)
					(mid 147.64498 -46.000227)
					(end 147.097496 -46.35119)
				)
				(arc
					(start 146.859752 -47.469298)
					(mid 147.21205 -48.011588)
					(end 147.75434 -47.65929)
				)
			)
		)
		(polygon
			(pts
				(arc
					(start 150.230078 -44.309284)
					(mid 149.885514 -43.757915)
					(end 149.33803 -44.108878)
				)
				(arc
					(start 149.100286 -45.226986)
					(mid 149.452584 -45.769276)
					(end 149.994874 -45.416978)
				)
			)
		)
		(polygon
			(pts
				(arc
					(start 149.309328 -40.340788)
					(mid 148.964764 -39.789419)
					(end 148.41728 -40.140382)
				)
				(arc
					(start 148.179536 -41.25849)
					(mid 148.531834 -41.80078)
					(end 149.074124 -41.448482)
				)
			)
		)
		(polygon
			(pts
				(arc
					(start 151.676862 -38.098476)
					(mid 151.332298 -37.547107)
					(end 150.784814 -37.89807)
				)
				(arc
					(start 150.54707 -39.016178)
					(mid 150.899368 -39.558468)
					(end 151.441658 -39.20617)
				)
			)
		)
		(polygon
			(pts
				(arc
					(start 149.814534 -35.21329)
					(mid 149.46997 -34.661921)
					(end 148.922486 -35.012884)
				)
				(arc
					(start 148.684742 -36.130992)
					(mid 149.03704 -36.673282)
					(end 149.57933 -36.320984)
				)
			)
		)
		(polygon
			(pts
				(arc
					(start 146.969226 -32.460184)
					(mid 146.624662 -31.908815)
					(end 146.077178 -32.259778)
				)
				(arc
					(start 145.839434 -33.377886)
					(mid 146.191732 -33.920176)
					(end 146.734022 -33.567878)
				)
			)
		)
		(polygon
			(pts
				(arc
					(start 180.819552 -23.596346)
					(mid 180.436012 -23.212806)
					(end 180.052472 -23.596346)
				)
				(arc
					(start 180.052472 -24.4856)
					(mid 180.436139 -24.868886)
					(end 180.819552 -24.485346)
				)
			)
		)
		(polygon
			(pts
				(arc
					(start 166.508938 -23.166832)
					(mid 166.125398 -22.783292)
					(end 165.741858 -23.166832)
				)
				(arc
					(start 165.741858 -24.056086)
					(mid 166.125525 -24.439372)
					(end 166.508938 -24.055832)
				)
			)
		)
		(polygon
			(pts
				(arc
					(start 168.543478 -23.123906)
					(mid 168.159938 -22.740366)
					(end 167.776398 -23.123906)
				)
				(arc
					(start 167.776398 -24.01316)
					(mid 168.160065 -24.396446)
					(end 168.543478 -24.012906)
				)
			)
		)
		(polygon
			(pts
				(arc
					(start 178.790854 -23.11654)
					(mid 178.407314 -22.733)
					(end 178.023774 -23.11654)
				)
				(arc
					(start 178.023774 -24.005794)
					(mid 178.407441 -24.38908)
					(end 178.790854 -24.00554)
				)
			)
		)
		(polygon
			(pts
				(arc
					(start 170.600624 -23.11527)
					(mid 170.217084 -22.73173)
					(end 169.833544 -23.11527)
				)
				(arc
					(start 169.833544 -24.004524)
					(mid 170.217211 -24.38781)
					(end 170.600624 -24.00427)
				)
			)
		)
		(polygon
			(pts
				(arc
					(start 172.65269 -23.112984)
					(mid 172.26915 -22.729444)
					(end 171.88561 -23.112984)
				)
				(arc
					(start 171.88561 -24.002238)
					(mid 172.269277 -24.385524)
					(end 172.65269 -24.001984)
				)
			)
		)
		(polygon
			(pts
				(arc
					(start 174.698406 -23.112476)
					(mid 174.314866 -22.728936)
					(end 173.931326 -23.112476)
				)
				(arc
					(start 173.931326 -24.00173)
					(mid 174.314993 -24.385016)
					(end 174.698406 -24.001476)
				)
			)
		)
		(polygon
			(pts
				(arc
					(start 176.75225 -23.103332)
					(mid 176.36871 -22.719792)
					(end 175.98517 -23.103332)
				)
				(arc
					(start 175.98517 -23.992586)
					(mid 176.368837 -24.375872)
					(end 176.75225 -23.992332)
				)
			)
		)
		(polygon
			(pts
				(arc
					(start 191.361314 -10.999978)
					(mid 190.799974 -10.438638)
					(end 190.238634 -10.999978)
				)
				(arc
					(start 190.238634 -12.40028)
					(mid 190.800101 -12.961366)
					(end 191.361314 -12.400026)
				)
			)
		)
		(polygon
			(pts
				(arc
					(start 187.761118 -10.999978)
					(mid 187.199778 -10.438638)
					(end 186.638438 -10.999978)
				)
				(arc
					(start 186.638438 -12.40028)
					(mid 187.199905 -12.961366)
					(end 187.761118 -12.400026)
				)
			)
		)
		(polygon
			(pts
				(arc
					(start 184.161176 -10.999978)
					(mid 183.599836 -10.438638)
					(end 183.038496 -10.999978)
				)
				(arc
					(start 183.038496 -12.40028)
					(mid 183.599963 -12.961366)
					(end 184.161176 -12.400026)
				)
			)
		)
		(polygon
			(pts
				(arc
					(start 180.561234 -10.999978)
					(mid 179.999894 -10.438638)
					(end 179.438554 -10.999978)
				)
				(arc
					(start 179.438554 -12.40028)
					(mid 180.000021 -12.961366)
					(end 180.561234 -12.400026)
				)
			)
		)
		(polygon
			(pts
				(arc
					(start 147.761452 -10.999978)
					(mid 147.200112 -10.438638)
					(end 146.638772 -10.999978)
				)
				(arc
					(start 146.638772 -12.40028)
					(mid 147.200239 -12.961366)
					(end 147.761452 -12.400026)
				)
			)
		)
		(polygon
			(pts
				(arc
					(start 144.16151 -10.999978)
					(mid 143.60017 -10.438638)
					(end 143.03883 -10.999978)
				)
				(arc
					(start 143.03883 -12.40028)
					(mid 143.600297 -12.961366)
					(end 144.16151 -12.400026)
				)
			)
		)
		(polygon
			(pts
				(arc
					(start 140.561314 -10.999978)
					(mid 139.999974 -10.438638)
					(end 139.438634 -10.999978)
				)
				(arc
					(start 139.438634 -12.40028)
					(mid 140.000101 -12.961366)
					(end 140.561314 -12.400026)
				)
			)
		)
		(polygon
			(pts
				(arc
					(start 136.961372 -10.999978)
					(mid 136.400032 -10.438638)
					(end 135.838692 -10.999978)
				)
				(arc
					(start 135.838692 -12.40028)
					(mid 136.400159 -12.961366)
					(end 136.961372 -12.400026)
				)
			)
		)
		(polygon
			(pts
				(arc
					(start 133.36143 -10.999978)
					(mid 132.80009 -10.438638)
					(end 132.23875 -10.999978)
				)
				(arc
					(start 132.23875 -12.40028)
					(mid 132.800217 -12.961366)
					(end 133.36143 -12.400026)
				)
			)
		)
		(polygon
			(pts
				(arc
					(start 129.761488 -10.999978)
					(mid 129.200148 -10.438638)
					(end 128.638808 -10.999978)
				)
				(arc
					(start 128.638808 -12.40028)
					(mid 129.200275 -12.961366)
					(end 129.761488 -12.400026)
				)
			)
		)
		(polygon
			(pts
				(arc
					(start 126.161546 -10.999978)
					(mid 125.600206 -10.438638)
					(end 125.038866 -10.999978)
				)
				(arc
					(start 125.038866 -12.40028)
					(mid 125.600333 -12.961366)
					(end 126.161546 -12.400026)
				)
			)
		)
		(polygon
			(pts
				(arc
					(start 122.56135 -10.999978)
					(mid 122.00001 -10.438638)
					(end 121.43867 -10.999978)
				)
				(arc
					(start 121.43867 -12.40028)
					(mid 122.000137 -12.961366)
					(end 122.56135 -12.400026)
				)
			)
		)
		(polygon
			(pts
				(arc
					(start 118.961408 -10.999978)
					(mid 118.400068 -10.438638)
					(end 117.838728 -10.999978)
				)
				(arc
					(start 117.838728 -12.40028)
					(mid 118.400195 -12.961366)
					(end 118.961408 -12.400026)
				)
			)
		)
		(polygon
			(pts
				(arc
					(start 115.361466 -10.999978)
					(mid 114.800126 -10.438638)
					(end 114.238786 -10.999978)
				)
				(arc
					(start 114.238786 -12.40028)
					(mid 114.800253 -12.961366)
					(end 115.361466 -12.400026)
				)
			)
		)
		(polygon
			(pts
				(arc
					(start 111.761524 -10.999978)
					(mid 111.200184 -10.438638)
					(end 110.638844 -10.999978)
				)
				(arc
					(start 110.638844 -12.40028)
					(mid 111.200311 -12.961366)
					(end 111.761524 -12.400026)
				)
			)
		)
		(polygon
			(pts
				(arc
					(start 108.161328 -10.999978)
					(mid 107.599988 -10.438638)
					(end 107.038648 -10.999978)
				)
				(arc
					(start 107.038648 -12.40028)
					(mid 107.600115 -12.961366)
					(end 108.161328 -12.400026)
				)
			)
		)
		(polygon
			(pts
				(arc
					(start 104.561386 -10.999978)
					(mid 104.000046 -10.438638)
					(end 103.438706 -10.999978)
				)
				(arc
					(start 103.438706 -12.40028)
					(mid 104.000173 -12.961366)
					(end 104.561386 -12.400026)
				)
			)
		)
		(polygon
			(pts
				(arc
					(start 100.961444 -10.999978)
					(mid 100.400104 -10.438638)
					(end 99.838764 -10.999978)
				)
				(arc
					(start 99.838764 -12.40028)
					(mid 100.400231 -12.961366)
					(end 100.961444 -12.400026)
				)
			)
		)
		(polygon
			(pts
				(arc
					(start 97.361502 -10.999978)
					(mid 96.800162 -10.438638)
					(end 96.238822 -10.999978)
				)
				(arc
					(start 96.238822 -12.40028)
					(mid 96.800289 -12.961366)
					(end 97.361502 -12.400026)
				)
			)
		)
		(polygon
			(pts
				(arc
					(start 93.761306 -10.999978)
					(mid 93.199966 -10.438638)
					(end 92.638626 -10.999978)
				)
				(arc
					(start 92.638626 -12.40028)
					(mid 93.200093 -12.961366)
					(end 93.761306 -12.400026)
				)
			)
		)
		(polygon
			(pts
				(arc
					(start 90.161364 -10.999978)
					(mid 89.600024 -10.438638)
					(end 89.038684 -10.999978)
				)
				(arc
					(start 89.038684 -12.40028)
					(mid 89.600151 -12.961366)
					(end 90.161364 -12.400026)
				)
			)
		)
		(polygon
			(pts
				(arc
					(start 86.561422 -10.999978)
					(mid 86.000082 -10.438638)
					(end 85.438742 -10.999978)
				)
				(arc
					(start 85.438742 -12.40028)
					(mid 86.000209 -12.961366)
					(end 86.561422 -12.400026)
				)
			)
		)
		(polygon
			(pts
				(arc
					(start 193.161158 -9.800082)
					(mid 192.599818 -9.238742)
					(end 192.038478 -9.800082)
				)
				(arc
					(start 192.038478 -11.200384)
					(mid 192.599945 -11.76147)
					(end 193.161158 -11.20013)
				)
			)
		)
		(polygon
			(pts
				(arc
					(start 189.561216 -9.800082)
					(mid 188.999876 -9.238742)
					(end 188.438536 -9.800082)
				)
				(arc
					(start 188.438536 -11.200384)
					(mid 189.000003 -11.76147)
					(end 189.561216 -11.20013)
				)
			)
		)
		(polygon
			(pts
				(arc
					(start 185.961274 -9.800082)
					(mid 185.399934 -9.238742)
					(end 184.838594 -9.800082)
				)
				(arc
					(start 184.838594 -11.200384)
					(mid 185.400061 -11.76147)
					(end 185.961274 -11.20013)
				)
			)
		)
		(polygon
			(pts
				(arc
					(start 182.361332 -9.800082)
					(mid 181.799992 -9.238742)
					(end 181.238652 -9.800082)
				)
				(arc
					(start 181.238652 -11.200384)
					(mid 181.800119 -11.76147)
					(end 182.361332 -11.20013)
				)
			)
		)
		(polygon
			(pts
				(arc
					(start 149.561296 -9.800082)
					(mid 148.999956 -9.238742)
					(end 148.438616 -9.800082)
				)
				(arc
					(start 148.438616 -11.200384)
					(mid 149.000083 -11.76147)
					(end 149.561296 -11.20013)
				)
			)
		)
		(polygon
			(pts
				(arc
					(start 145.961354 -9.800082)
					(mid 145.400014 -9.238742)
					(end 144.838674 -9.800082)
				)
				(arc
					(start 144.838674 -11.200384)
					(mid 145.400141 -11.76147)
					(end 145.961354 -11.20013)
				)
			)
		)
		(polygon
			(pts
				(arc
					(start 142.361412 -9.800082)
					(mid 141.800072 -9.238742)
					(end 141.238732 -9.800082)
				)
				(arc
					(start 141.238732 -11.200384)
					(mid 141.800199 -11.76147)
					(end 142.361412 -11.20013)
				)
			)
		)
		(polygon
			(pts
				(arc
					(start 138.76147 -9.800082)
					(mid 138.20013 -9.238742)
					(end 137.63879 -9.800082)
				)
				(arc
					(start 137.63879 -11.200384)
					(mid 138.200257 -11.76147)
					(end 138.76147 -11.20013)
				)
			)
		)
		(polygon
			(pts
				(arc
					(start 135.161528 -9.800082)
					(mid 134.600188 -9.238742)
					(end 134.038848 -9.800082)
				)
				(arc
					(start 134.038848 -11.200384)
					(mid 134.600315 -11.76147)
					(end 135.161528 -11.20013)
				)
			)
		)
		(polygon
			(pts
				(arc
					(start 131.561332 -9.800082)
					(mid 130.999992 -9.238742)
					(end 130.438652 -9.800082)
				)
				(arc
					(start 130.438652 -11.200384)
					(mid 131.000119 -11.76147)
					(end 131.561332 -11.20013)
				)
			)
		)
		(polygon
			(pts
				(arc
					(start 127.96139 -9.800082)
					(mid 127.40005 -9.238742)
					(end 126.83871 -9.800082)
				)
				(arc
					(start 126.83871 -11.200384)
					(mid 127.400177 -11.76147)
					(end 127.96139 -11.20013)
				)
			)
		)
		(polygon
			(pts
				(arc
					(start 124.361448 -9.800082)
					(mid 123.800108 -9.238742)
					(end 123.238768 -9.800082)
				)
				(arc
					(start 123.238768 -11.200384)
					(mid 123.800235 -11.76147)
					(end 124.361448 -11.20013)
				)
			)
		)
		(polygon
			(pts
				(arc
					(start 120.761506 -9.800082)
					(mid 120.200166 -9.238742)
					(end 119.638826 -9.800082)
				)
				(arc
					(start 119.638826 -11.200384)
					(mid 120.200293 -11.76147)
					(end 120.761506 -11.20013)
				)
			)
		)
		(polygon
			(pts
				(arc
					(start 117.16131 -9.800082)
					(mid 116.59997 -9.238742)
					(end 116.03863 -9.800082)
				)
				(arc
					(start 116.03863 -11.200384)
					(mid 116.600097 -11.76147)
					(end 117.16131 -11.20013)
				)
			)
		)
		(polygon
			(pts
				(arc
					(start 113.561368 -9.800082)
					(mid 113.000028 -9.238742)
					(end 112.438688 -9.800082)
				)
				(arc
					(start 112.438688 -11.200384)
					(mid 113.000155 -11.76147)
					(end 113.561368 -11.20013)
				)
			)
		)
		(polygon
			(pts
				(arc
					(start 109.961426 -9.800082)
					(mid 109.400086 -9.238742)
					(end 108.838746 -9.800082)
				)
				(arc
					(start 108.838746 -11.200384)
					(mid 109.400213 -11.76147)
					(end 109.961426 -11.20013)
				)
			)
		)
		(polygon
			(pts
				(arc
					(start 106.361484 -9.800082)
					(mid 105.800144 -9.238742)
					(end 105.238804 -9.800082)
				)
				(arc
					(start 105.238804 -11.200384)
					(mid 105.800271 -11.76147)
					(end 106.361484 -11.20013)
				)
			)
		)
		(polygon
			(pts
				(arc
					(start 102.761542 -9.800082)
					(mid 102.200202 -9.238742)
					(end 101.638862 -9.800082)
				)
				(arc
					(start 101.638862 -11.200384)
					(mid 102.200329 -11.76147)
					(end 102.761542 -11.20013)
				)
			)
		)
		(polygon
			(pts
				(arc
					(start 99.161346 -9.800082)
					(mid 98.600006 -9.238742)
					(end 98.038666 -9.800082)
				)
				(arc
					(start 98.038666 -11.200384)
					(mid 98.600133 -11.76147)
					(end 99.161346 -11.20013)
				)
			)
		)
		(polygon
			(pts
				(arc
					(start 95.561404 -9.800082)
					(mid 95.000064 -9.238742)
					(end 94.438724 -9.800082)
				)
				(arc
					(start 94.438724 -11.200384)
					(mid 95.000191 -11.76147)
					(end 95.561404 -11.20013)
				)
			)
		)
		(polygon
			(pts
				(arc
					(start 91.961462 -9.800082)
					(mid 91.400122 -9.238742)
					(end 90.838782 -9.800082)
				)
				(arc
					(start 90.838782 -11.200384)
					(mid 91.400249 -11.76147)
					(end 91.961462 -11.20013)
				)
			)
		)
		(polygon
			(pts
				(arc
					(start 88.36152 -9.800082)
					(mid 87.80018 -9.238742)
					(end 87.23884 -9.800082)
				)
				(arc
					(start 87.23884 -11.200384)
					(mid 87.800307 -11.76147)
					(end 88.36152 -11.20013)
				)
			)
		)
		(polygon
			(pts
				(arc
					(start 180.561234 -7.400036)
					(mid 179.999894 -6.838696)
					(end 179.438554 -7.400036)
				)
				(arc
					(start 179.438554 -8.800338)
					(mid 180.000021 -9.361424)
					(end 180.561234 -8.800084)
				)
			)
		)
		(polygon
			(pts
				(arc
					(start 191.361314 -3.800094)
					(mid 190.799974 -3.238754)
					(end 190.238634 -3.800094)
				)
				(arc
					(start 190.238634 -5.200396)
					(mid 190.800101 -5.761482)
					(end 191.361314 -5.200142)
				)
			)
		)
		(polygon
			(pts
				(arc
					(start 187.761118 -3.800094)
					(mid 187.199778 -3.238754)
					(end 186.638438 -3.800094)
				)
				(arc
					(start 186.638438 -5.200396)
					(mid 187.199905 -5.761482)
					(end 187.761118 -5.200142)
				)
			)
		)
		(polygon
			(pts
				(arc
					(start 184.161176 -3.800094)
					(mid 183.599836 -3.238754)
					(end 183.038496 -3.800094)
				)
				(arc
					(start 183.038496 -5.200396)
					(mid 183.599963 -5.761482)
					(end 184.161176 -5.200142)
				)
			)
		)
		(polygon
			(pts
				(arc
					(start 180.561234 -3.800094)
					(mid 179.999894 -3.238754)
					(end 179.438554 -3.800094)
				)
				(arc
					(start 179.438554 -5.200396)
					(mid 180.000021 -5.761482)
					(end 180.561234 -5.200142)
				)
			)
		)
		(polygon
			(pts
				(arc
					(start 147.761452 -3.800094)
					(mid 147.200112 -3.238754)
					(end 146.638772 -3.800094)
				)
				(arc
					(start 146.638772 -5.200396)
					(mid 147.200239 -5.761482)
					(end 147.761452 -5.200142)
				)
			)
		)
		(polygon
			(pts
				(arc
					(start 144.16151 -3.800094)
					(mid 143.60017 -3.238754)
					(end 143.03883 -3.800094)
				)
				(arc
					(start 143.03883 -5.200396)
					(mid 143.600297 -5.761482)
					(end 144.16151 -5.200142)
				)
			)
		)
		(polygon
			(pts
				(arc
					(start 140.561314 -3.800094)
					(mid 139.999974 -3.238754)
					(end 139.438634 -3.800094)
				)
				(arc
					(start 139.438634 -5.200396)
					(mid 140.000101 -5.761482)
					(end 140.561314 -5.200142)
				)
			)
		)
		(polygon
			(pts
				(arc
					(start 136.961372 -3.800094)
					(mid 136.400032 -3.238754)
					(end 135.838692 -3.800094)
				)
				(arc
					(start 135.838692 -5.200396)
					(mid 136.400159 -5.761482)
					(end 136.961372 -5.200142)
				)
			)
		)
		(polygon
			(pts
				(arc
					(start 133.36143 -3.800094)
					(mid 132.80009 -3.238754)
					(end 132.23875 -3.800094)
				)
				(arc
					(start 132.23875 -5.200396)
					(mid 132.800217 -5.761482)
					(end 133.36143 -5.200142)
				)
			)
		)
		(polygon
			(pts
				(arc
					(start 129.761488 -3.800094)
					(mid 129.200148 -3.238754)
					(end 128.638808 -3.800094)
				)
				(arc
					(start 128.638808 -5.200396)
					(mid 129.200275 -5.761482)
					(end 129.761488 -5.200142)
				)
			)
		)
		(polygon
			(pts
				(arc
					(start 126.161546 -3.800094)
					(mid 125.600206 -3.238754)
					(end 125.038866 -3.800094)
				)
				(arc
					(start 125.038866 -5.200396)
					(mid 125.600333 -5.761482)
					(end 126.161546 -5.200142)
				)
			)
		)
		(polygon
			(pts
				(arc
					(start 122.56135 -3.800094)
					(mid 122.00001 -3.238754)
					(end 121.43867 -3.800094)
				)
				(arc
					(start 121.43867 -5.200396)
					(mid 122.000137 -5.761482)
					(end 122.56135 -5.200142)
				)
			)
		)
		(polygon
			(pts
				(arc
					(start 118.961408 -3.800094)
					(mid 118.400068 -3.238754)
					(end 117.838728 -3.800094)
				)
				(arc
					(start 117.838728 -5.200396)
					(mid 118.400195 -5.761482)
					(end 118.961408 -5.200142)
				)
			)
		)
		(polygon
			(pts
				(arc
					(start 115.361466 -3.800094)
					(mid 114.800126 -3.238754)
					(end 114.238786 -3.800094)
				)
				(arc
					(start 114.238786 -5.200396)
					(mid 114.800253 -5.761482)
					(end 115.361466 -5.200142)
				)
			)
		)
		(polygon
			(pts
				(arc
					(start 111.761524 -3.800094)
					(mid 111.200184 -3.238754)
					(end 110.638844 -3.800094)
				)
				(arc
					(start 110.638844 -5.200396)
					(mid 111.200311 -5.761482)
					(end 111.761524 -5.200142)
				)
			)
		)
		(polygon
			(pts
				(arc
					(start 108.161328 -3.800094)
					(mid 107.599988 -3.238754)
					(end 107.038648 -3.800094)
				)
				(arc
					(start 107.038648 -5.200396)
					(mid 107.600115 -5.761482)
					(end 108.161328 -5.200142)
				)
			)
		)
		(polygon
			(pts
				(arc
					(start 104.561386 -3.800094)
					(mid 104.000046 -3.238754)
					(end 103.438706 -3.800094)
				)
				(arc
					(start 103.438706 -5.200396)
					(mid 104.000173 -5.761482)
					(end 104.561386 -5.200142)
				)
			)
		)
		(polygon
			(pts
				(arc
					(start 100.961444 -3.800094)
					(mid 100.400104 -3.238754)
					(end 99.838764 -3.800094)
				)
				(arc
					(start 99.838764 -5.200396)
					(mid 100.400231 -5.761482)
					(end 100.961444 -5.200142)
				)
			)
		)
		(polygon
			(pts
				(arc
					(start 97.361502 -3.800094)
					(mid 96.800162 -3.238754)
					(end 96.238822 -3.800094)
				)
				(arc
					(start 96.238822 -5.200396)
					(mid 96.800289 -5.761482)
					(end 97.361502 -5.200142)
				)
			)
		)
		(polygon
			(pts
				(arc
					(start 93.761306 -3.800094)
					(mid 93.199966 -3.238754)
					(end 92.638626 -3.800094)
				)
				(arc
					(start 92.638626 -5.200396)
					(mid 93.200093 -5.761482)
					(end 93.761306 -5.200142)
				)
			)
		)
		(polygon
			(pts
				(arc
					(start 90.161364 -3.800094)
					(mid 89.600024 -3.238754)
					(end 89.038684 -3.800094)
				)
				(arc
					(start 89.038684 -5.200396)
					(mid 89.600151 -5.761482)
					(end 90.161364 -5.200142)
				)
			)
		)
		(polygon
			(pts
				(arc
					(start 86.561422 -3.800094)
					(mid 86.000082 -3.238754)
					(end 85.438742 -3.800094)
				)
				(arc
					(start 85.438742 -5.200396)
					(mid 86.000209 -5.761482)
					(end 86.561422 -5.200142)
				)
			)
		)
		(polygon
			(pts
				(arc
					(start 193.161158 -2.600198)
					(mid 192.599818 -2.038858)
					(end 192.038478 -2.600198)
				)
				(arc
					(start 192.038478 -4.000246)
					(mid 192.599945 -4.561332)
					(end 193.161158 -3.999992)
				)
			)
		)
		(polygon
			(pts
				(arc
					(start 189.561216 -2.600198)
					(mid 188.999876 -2.038858)
					(end 188.438536 -2.600198)
				)
				(arc
					(start 188.438536 -4.000246)
					(mid 189.000003 -4.561332)
					(end 189.561216 -3.999992)
				)
			)
		)
		(polygon
			(pts
				(arc
					(start 185.961274 -2.600198)
					(mid 185.399934 -2.038858)
					(end 184.838594 -2.600198)
				)
				(arc
					(start 184.838594 -4.000246)
					(mid 185.400061 -4.561332)
					(end 185.961274 -3.999992)
				)
			)
		)
		(polygon
			(pts
				(arc
					(start 182.361332 -2.600198)
					(mid 181.799992 -2.038858)
					(end 181.238652 -2.600198)
				)
				(arc
					(start 181.238652 -4.000246)
					(mid 181.800119 -4.561332)
					(end 182.361332 -3.999992)
				)
			)
		)
		(polygon
			(pts
				(arc
					(start 149.561296 -2.600198)
					(mid 148.999956 -2.038858)
					(end 148.438616 -2.600198)
				)
				(arc
					(start 148.438616 -4.000246)
					(mid 149.000083 -4.561332)
					(end 149.561296 -3.999992)
				)
			)
		)
		(polygon
			(pts
				(arc
					(start 145.961354 -2.600198)
					(mid 145.400014 -2.038858)
					(end 144.838674 -2.600198)
				)
				(arc
					(start 144.838674 -4.000246)
					(mid 145.400141 -4.561332)
					(end 145.961354 -3.999992)
				)
			)
		)
		(polygon
			(pts
				(arc
					(start 142.361412 -2.600198)
					(mid 141.800072 -2.038858)
					(end 141.238732 -2.600198)
				)
				(arc
					(start 141.238732 -4.000246)
					(mid 141.800199 -4.561332)
					(end 142.361412 -3.999992)
				)
			)
		)
		(polygon
			(pts
				(arc
					(start 138.76147 -2.600198)
					(mid 138.20013 -2.038858)
					(end 137.63879 -2.600198)
				)
				(arc
					(start 137.63879 -4.000246)
					(mid 138.200257 -4.561332)
					(end 138.76147 -3.999992)
				)
			)
		)
		(polygon
			(pts
				(arc
					(start 135.161528 -2.600198)
					(mid 134.600188 -2.038858)
					(end 134.038848 -2.600198)
				)
				(arc
					(start 134.038848 -4.000246)
					(mid 134.600315 -4.561332)
					(end 135.161528 -3.999992)
				)
			)
		)
		(polygon
			(pts
				(arc
					(start 131.561332 -2.600198)
					(mid 130.999992 -2.038858)
					(end 130.438652 -2.600198)
				)
				(arc
					(start 130.438652 -4.000246)
					(mid 131.000119 -4.561332)
					(end 131.561332 -3.999992)
				)
			)
		)
		(polygon
			(pts
				(arc
					(start 127.96139 -2.600198)
					(mid 127.40005 -2.038858)
					(end 126.83871 -2.600198)
				)
				(arc
					(start 126.83871 -4.000246)
					(mid 127.400177 -4.561332)
					(end 127.96139 -3.999992)
				)
			)
		)
		(polygon
			(pts
				(arc
					(start 124.361448 -2.600198)
					(mid 123.800108 -2.038858)
					(end 123.238768 -2.600198)
				)
				(arc
					(start 123.238768 -4.000246)
					(mid 123.800235 -4.561332)
					(end 124.361448 -3.999992)
				)
			)
		)
		(polygon
			(pts
				(arc
					(start 120.761506 -2.600198)
					(mid 120.200166 -2.038858)
					(end 119.638826 -2.600198)
				)
				(arc
					(start 119.638826 -4.000246)
					(mid 120.200293 -4.561332)
					(end 120.761506 -3.999992)
				)
			)
		)
		(polygon
			(pts
				(arc
					(start 117.16131 -2.600198)
					(mid 116.59997 -2.038858)
					(end 116.03863 -2.600198)
				)
				(arc
					(start 116.03863 -4.000246)
					(mid 116.600097 -4.561332)
					(end 117.16131 -3.999992)
				)
			)
		)
		(polygon
			(pts
				(arc
					(start 113.561368 -2.600198)
					(mid 113.000028 -2.038858)
					(end 112.438688 -2.600198)
				)
				(arc
					(start 112.438688 -4.000246)
					(mid 113.000155 -4.561332)
					(end 113.561368 -3.999992)
				)
			)
		)
		(polygon
			(pts
				(arc
					(start 109.961426 -2.600198)
					(mid 109.400086 -2.038858)
					(end 108.838746 -2.600198)
				)
				(arc
					(start 108.838746 -4.000246)
					(mid 109.400213 -4.561332)
					(end 109.961426 -3.999992)
				)
			)
		)
		(polygon
			(pts
				(arc
					(start 106.361484 -2.600198)
					(mid 105.800144 -2.038858)
					(end 105.238804 -2.600198)
				)
				(arc
					(start 105.238804 -4.000246)
					(mid 105.800271 -4.561332)
					(end 106.361484 -3.999992)
				)
			)
		)
		(polygon
			(pts
				(arc
					(start 102.761542 -2.600198)
					(mid 102.200202 -2.038858)
					(end 101.638862 -2.600198)
				)
				(arc
					(start 101.638862 -4.000246)
					(mid 102.200329 -4.561332)
					(end 102.761542 -3.999992)
				)
			)
		)
		(polygon
			(pts
				(arc
					(start 99.161346 -2.600198)
					(mid 98.600006 -2.038858)
					(end 98.038666 -2.600198)
				)
				(arc
					(start 98.038666 -4.000246)
					(mid 98.600133 -4.561332)
					(end 99.161346 -3.999992)
				)
			)
		)
		(polygon
			(pts
				(arc
					(start 95.561404 -2.600198)
					(mid 95.000064 -2.038858)
					(end 94.438724 -2.600198)
				)
				(arc
					(start 94.438724 -4.000246)
					(mid 95.000191 -4.561332)
					(end 95.561404 -3.999992)
				)
			)
		)
		(polygon
			(pts
				(arc
					(start 91.961462 -2.600198)
					(mid 91.400122 -2.038858)
					(end 90.838782 -2.600198)
				)
				(arc
					(start 90.838782 -4.000246)
					(mid 91.400249 -4.561332)
					(end 91.961462 -3.999992)
				)
			)
		)
		(polygon
			(pts
				(arc
					(start 88.36152 -2.600198)
					(mid 87.80018 -2.038858)
					(end 87.23884 -2.600198)
				)
				(arc
					(start 87.23884 -4.000246)
					(mid 87.800307 -4.561332)
					(end 88.36152 -3.999992)
				)
			)
		)
	)
	(zone
		(net "P1V8_C")
		(layer "In3.Cu")
		(hatch none 0.5)
		(connect_pads
			(clearance 0.5)
		)
		(min_thickness 0.25)
		(fill yes
			(thermal_gap 0.5)
			(thermal_bridge_width 0.5)
			(island_removal_mode 0)
		)
		(polygon
			(pts
				(xy 177.904394 -26.2509) (xy 177.421794 -26.7335) (xy 171.923202 -26.7335) (xy 171.5643 -27.092402)
				(xy 171.5643 -34.064194) (xy 170.7261 -34.902394) (xy 170.7261 -40.515794) (xy 169.801794 -41.4401)
				(xy 165.534086 -41.4401) (xy 165.1635 -41.810686) (xy 165.1635 -58.905648) (xy 186.8805 -80.622648)
				(xy 186.8805 -91.595194) (xy 186.53125 -91.944444) (xy 186.53125 -122.06478) (xy 186.83097 -122.3645)
				(xy 208.389474 -122.3645) (xy 208.730088 -122.023886) (xy 208.730088 -26.57348) (xy 208.407508 -26.2509)
			)
		)
		(polygon
			(pts
				(arc
					(start 176.158144 -30.400244)
					(mid 175.800004 -30.042104)
					(end 175.441864 -30.400244)
				)
				(arc
					(start 175.441864 -31.200344)
					(mid 175.800131 -31.55823)
					(end 176.158144 -31.20009)
				)
			)
		)
		(polygon
			(pts
				(arc
					(start 175.358044 -30.39999)
					(mid 174.999777 -30.04185)
					(end 174.641764 -30.400244)
				)
				(arc
					(start 174.642018 -31.199836)
					(mid 175.000158 -31.55823)
					(end 175.358298 -31.199836)
				)
				(xy 175.358044 -30.400244)
			)
		)
		(polygon
			(pts
				(arc
					(start 173.758098 -30.39999)
					(mid 173.399831 -30.04185)
					(end 173.041818 -30.400244)
				)
				(arc
					(start 173.042072 -31.199836)
					(mid 173.400212 -31.55823)
					(end 173.758352 -31.199836)
				)
				(xy 173.758098 -30.400244)
			)
		)
		(polygon
			(pts
				(arc
					(start 172.957998 -30.39999)
					(mid 172.599731 -30.04185)
					(end 172.241718 -30.400244)
				)
				(arc
					(start 172.241972 -31.199836)
					(mid 172.600112 -31.55823)
					(end 172.958252 -31.199836)
				)
				(xy 172.957998 -30.400244)
			)
		)
	)
	(zone
		(net "GND")
		(layer "In3.Cu")
		(hatch none 0.5)
		(connect_pads
			(clearance 0.5)
		)
		(min_thickness 0.25)
		(fill yes
			(thermal_gap 0.5)
			(thermal_bridge_width 0.5)
			(island_removal_mode 0)
		)
		(polygon
			(pts
				(xy 173.646338 -101.124512) (xy 168.1861 -106.58475) (xy 168.1861 -143.306546) (xy 168.609518 -143.729964)
				(arc
					(start 208.000092 -143.729964)
					(mid 208.516277 -143.516153)
					(end 208.730088 -142.999968)
				)
				(xy 208.730088 -123.086114) (xy 208.389474 -122.7455) (xy 186.672982 -122.7455) (xy 186.15025 -122.222768)
				(xy 186.15025 -101.451156) (xy 185.823606 -101.124512)
			)
		)
	)
	(zone
		(net "GB_VDDA")
		(layer "In3.Cu")
		(hatch none 0.5)
		(connect_pads
			(clearance 0.5)
		)
		(min_thickness 0.25)
		(fill yes
			(thermal_gap 0.5)
			(thermal_bridge_width 0.5)
			(island_removal_mode 0)
		)
		(polygon
			(pts
				(xy 88.674194 -30.4165) (xy 85.219794 -33.8709) (xy 72.98817 -33.8709) (xy 72.98817 -33.895284)
				(xy 72.5551 -34.328354) (xy 72.5551 -60.474606) (xy 73.942194 -61.8617) (xy 97.851214 -61.8617)
				(xy 98.2853 -62.295786) (xy 121.184924 -62.295786) (xy 121.700544 -62.811406) (xy 121.700544 -77.08265)
				(xy 121.948194 -77.3303)
				(arc
					(start 125.861318 -77.3303)
					(mid 125.64889 -76.929489)
					(end 125.999748 -76.64196)
				)
				(arc
					(start 127 -76.64196)
					(mid 127.351085 -76.929365)
					(end 127.138684 -77.3303)
				)
				(xy 140.711682 -77.3303) (xy 141.901672 -76.14031) (xy 141.901672 -47.272194) (xy 142.880334 -46.293532)
				(xy 142.880334 -30.835854) (xy 142.46098 -30.4165)
			)
		)
		(polygon
			(pts
				(xy 139.622022 -76.14158) (xy 138.479276 -76.14158) (xy 138.479022 -76.141834)
				(arc
					(start 138.479022 -76.142342)
					(mid 138.096244 -76.52512)
					(end 138.479022 -76.907898)
				)
				(xy 138.479022 -76.90866) (xy 139.622022 -76.90866)
				(arc
					(start 139.622022 -76.907898)
					(mid 140.0048 -76.52512)
					(end 139.622022 -76.142342)
				)
			)
		)
		(polygon
			(pts
				(arc
					(start 127 -76.358242)
					(mid 127.35814 -76.000102)
					(end 127 -75.641962)
				)
				(arc
					(start 125.999748 -75.641962)
					(mid 125.641862 -76.000229)
					(end 126.000002 -76.358242)
				)
			)
		)
		(polygon
			(pts
				(arc
					(start 127 -75.358244)
					(mid 127.35814 -75.000104)
					(end 127 -74.641964)
				)
				(arc
					(start 125.999748 -74.641964)
					(mid 125.641862 -75.000231)
					(end 126.000002 -75.358244)
				)
			)
		)
		(polygon
			(pts
				(arc
					(start 127 -74.358246)
					(mid 127.35814 -74.000106)
					(end 127 -73.641966)
				)
				(arc
					(start 125.999748 -73.641966)
					(mid 125.641862 -74.000233)
					(end 126.000002 -74.358246)
				)
			)
		)
		(polygon
			(pts
				(arc
					(start 130.999992 -73.358248)
					(mid 131.358132 -73.000108)
					(end 130.999992 -72.641968)
				)
				(arc
					(start 129.99974 -72.641968)
					(mid 129.641854 -73.000235)
					(end 129.999994 -73.358248)
				)
			)
		)
		(polygon
			(pts
				(arc
					(start 127 -73.358248)
					(mid 127.35814 -73.000108)
					(end 127 -72.641968)
				)
				(arc
					(start 125.999748 -72.641968)
					(mid 125.641862 -73.000235)
					(end 126.000002 -73.358248)
				)
			)
		)
		(polygon
			(pts
				(arc
					(start 129.999994 -72.35825)
					(mid 130.358134 -72.00011)
					(end 129.999994 -71.64197)
				)
				(arc
					(start 128.999742 -71.64197)
					(mid 128.641856 -72.000237)
					(end 128.999996 -72.35825)
				)
			)
		)
		(polygon
			(pts
				(arc
					(start 127 -72.35825)
					(mid 127.35814 -72.00011)
					(end 127 -71.64197)
				)
				(arc
					(start 125.999748 -71.64197)
					(mid 125.641862 -72.000237)
					(end 126.000002 -72.35825)
				)
			)
		)
		(polygon
			(pts
				(arc
					(start 130.999992 -71.358252)
					(mid 131.358132 -71.000112)
					(end 130.999992 -70.641972)
				)
				(arc
					(start 129.99974 -70.641972)
					(mid 129.641854 -71.000239)
					(end 129.999994 -71.358252)
				)
			)
		)
		(polygon
			(pts
				(arc
					(start 127 -71.358252)
					(mid 127.35814 -71.000112)
					(end 127 -70.641972)
				)
				(arc
					(start 125.999748 -70.641972)
					(mid 125.641862 -71.000239)
					(end 126.000002 -71.358252)
				)
			)
		)
		(polygon
			(pts
				(arc
					(start 129.999994 -70.358254)
					(mid 130.358134 -70.000114)
					(end 129.999994 -69.641974)
				)
				(arc
					(start 128.999742 -69.641974)
					(mid 128.641856 -70.000241)
					(end 128.999996 -70.358254)
				)
			)
		)
		(polygon
			(pts
				(arc
					(start 127 -70.358254)
					(mid 127.35814 -70.000114)
					(end 127 -69.641974)
				)
				(arc
					(start 125.999748 -69.641974)
					(mid 125.641862 -70.000241)
					(end 126.000002 -70.358254)
				)
			)
		)
		(polygon
			(pts
				(arc
					(start 130.999992 -69.358256)
					(mid 131.358132 -69.000116)
					(end 130.999992 -68.641976)
				)
				(arc
					(start 129.99974 -68.641976)
					(mid 129.641854 -69.000243)
					(end 129.999994 -69.358256)
				)
			)
		)
		(polygon
			(pts
				(arc
					(start 127 -69.358256)
					(mid 127.35814 -69.000116)
					(end 127 -68.641976)
				)
				(arc
					(start 125.999748 -68.641976)
					(mid 125.641862 -69.000243)
					(end 126.000002 -69.358256)
				)
			)
		)
		(polygon
			(pts
				(arc
					(start 129.999994 -68.358258)
					(mid 130.358134 -68.000118)
					(end 129.999994 -67.641978)
				)
				(arc
					(start 128.999742 -67.641978)
					(mid 128.641856 -68.000245)
					(end 128.999996 -68.358258)
				)
			)
		)
		(polygon
			(pts
				(arc
					(start 127 -68.358258)
					(mid 127.35814 -68.000118)
					(end 127 -67.641978)
				)
				(arc
					(start 125.999748 -67.641978)
					(mid 125.641862 -68.000245)
					(end 126.000002 -68.358258)
				)
			)
		)
		(polygon
			(pts
				(arc
					(start 130.999992 -66.358262)
					(mid 131.358132 -66.000122)
					(end 130.999992 -65.641982)
				)
				(arc
					(start 129.99974 -65.641982)
					(mid 129.641854 -66.000249)
					(end 129.999994 -66.358262)
				)
			)
		)
		(polygon
			(pts
				(arc
					(start 127 -66.358262)
					(mid 127.35814 -66.000122)
					(end 127 -65.641982)
				)
				(arc
					(start 125.999748 -65.641982)
					(mid 125.641862 -66.000249)
					(end 126.000002 -66.358262)
				)
			)
		)
		(polygon
			(pts
				(arc
					(start 129.999994 -65.358264)
					(mid 130.358134 -65.000124)
					(end 129.999994 -64.641984)
				)
				(arc
					(start 128.999742 -64.641984)
					(mid 128.641856 -65.000251)
					(end 128.999996 -65.358264)
				)
			)
		)
		(polygon
			(pts
				(arc
					(start 127 -65.358264)
					(mid 127.35814 -65.000124)
					(end 127 -64.641984)
				)
				(arc
					(start 125.999748 -64.641984)
					(mid 125.641862 -65.000251)
					(end 126.000002 -65.358264)
				)
			)
		)
		(polygon
			(pts
				(arc
					(start 139.882372 -65.426844)
					(mid 140.336778 -64.972057)
					(end 139.882118 -64.517524)
				)
				(arc
					(start 138.739118 -64.517524)
					(mid 138.284458 -64.972184)
					(end 138.739118 -65.426844)
				)
			)
		)
		(polygon
			(pts
				(arc
					(start 130.999992 -64.358266)
					(mid 131.358132 -64.000126)
					(end 130.999992 -63.641986)
				)
				(arc
					(start 129.99974 -63.641986)
					(mid 129.641854 -64.000253)
					(end 129.999994 -64.358266)
				)
			)
		)
		(polygon
			(pts
				(arc
					(start 127 -64.358266)
					(mid 127.35814 -64.000126)
					(end 127 -63.641986)
				)
				(arc
					(start 125.999748 -63.641986)
					(mid 125.641862 -64.000253)
					(end 126.000002 -64.358266)
				)
			)
		)
		(polygon
			(pts
				(arc
					(start 129.999994 -63.358268)
					(mid 130.358134 -63.000128)
					(end 129.999994 -62.641988)
				)
				(arc
					(start 128.999742 -62.641988)
					(mid 128.641856 -63.000255)
					(end 128.999996 -63.358268)
				)
			)
		)
		(polygon
			(pts
				(arc
					(start 127 -63.358268)
					(mid 127.35814 -63.000128)
					(end 127 -62.641988)
				)
				(arc
					(start 125.999748 -62.641988)
					(mid 125.641862 -63.000255)
					(end 126.000002 -63.358268)
				)
			)
		)
		(polygon
			(pts
				(arc
					(start 139.947904 -63.499746)
					(mid 140.40231 -63.044959)
					(end 139.94765 -62.590426)
				)
				(arc
					(start 138.80465 -62.590426)
					(mid 138.34999 -63.045086)
					(end 138.80465 -63.499746)
				)
			)
		)
		(polygon
			(pts
				(arc
					(start 130.999992 -62.35827)
					(mid 131.358132 -62.00013)
					(end 130.999992 -61.64199)
				)
				(arc
					(start 129.99974 -61.64199)
					(mid 129.641854 -62.000257)
					(end 129.999994 -62.35827)
				)
			)
		)
		(polygon
			(pts
				(arc
					(start 127 -62.35827)
					(mid 127.35814 -62.00013)
					(end 127 -61.64199)
				)
				(arc
					(start 125.999748 -61.64199)
					(mid 125.641862 -62.000257)
					(end 126.000002 -62.35827)
				)
			)
		)
		(polygon
			(pts
				(arc
					(start 140.173964 -61.576712)
					(mid 140.62837 -61.121925)
					(end 140.17371 -60.667392)
				)
				(arc
					(start 139.03071 -60.667392)
					(mid 138.57605 -61.122052)
					(end 139.03071 -61.576712)
				)
			)
		)
		(polygon
			(pts
				(arc
					(start 129.999994 -61.358272)
					(mid 130.358134 -61.000132)
					(end 129.999994 -60.641992)
				)
				(arc
					(start 128.999742 -60.641992)
					(mid 128.641856 -61.000259)
					(end 128.999996 -61.358272)
				)
			)
		)
		(polygon
			(pts
				(arc
					(start 127 -61.358272)
					(mid 127.35814 -61.000132)
					(end 127 -60.641992)
				)
				(arc
					(start 125.999748 -60.641992)
					(mid 125.641862 -61.000259)
					(end 126.000002 -61.358272)
				)
			)
		)
		(polygon
			(pts
				(arc
					(start 127 -60.358274)
					(mid 127.35814 -60.000134)
					(end 127 -59.641994)
				)
				(arc
					(start 125.999748 -59.641994)
					(mid 125.641862 -60.000261)
					(end 126.000002 -60.358274)
				)
			)
		)
		(polygon
			(pts
				(arc
					(start 127 -59.358276)
					(mid 127.35814 -59.000136)
					(end 127 -58.641996)
				)
				(arc
					(start 125.999748 -58.641996)
					(mid 125.641862 -59.000263)
					(end 126.000002 -59.358276)
				)
			)
		)
		(polygon
			(pts
				(arc
					(start 140.589254 -59.35726)
					(mid 141.04366 -58.902473)
					(end 140.589 -58.44794)
				)
				(arc
					(start 139.446 -58.44794)
					(mid 138.99134 -58.9026)
					(end 139.446 -59.35726)
				)
			)
		)
		(polygon
			(pts
				(arc
					(start 127 -58.358278)
					(mid 127.35814 -58.000138)
					(end 127 -57.641998)
				)
				(arc
					(start 125.999748 -57.641998)
					(mid 125.641862 -58.000265)
					(end 126.000002 -58.358278)
				)
			)
		)
		(polygon
			(pts
				(arc
					(start 127 -57.35828)
					(mid 127.35814 -57.00014)
					(end 127 -56.642)
				)
				(arc
					(start 125.999748 -56.642)
					(mid 125.641862 -57.000267)
					(end 126.000002 -57.35828)
				)
			)
		)
		(polygon
			(pts
				(arc
					(start 127 -56.358282)
					(mid 127.35814 -56.000142)
					(end 127 -55.642002)
				)
				(arc
					(start 125.999748 -55.642002)
					(mid 125.641862 -56.000269)
					(end 126.000002 -56.358282)
				)
			)
		)
		(polygon
			(pts
				(arc
					(start 127 -55.358284)
					(mid 127.35814 -55.000144)
					(end 127 -54.642004)
				)
				(arc
					(start 125.999748 -54.642004)
					(mid 125.641862 -55.000271)
					(end 126.000002 -55.358284)
				)
			)
		)
		(polygon
			(pts
				(arc
					(start 124.358146 -55.000144)
					(mid 124.000006 -54.642004)
					(end 123.641866 -55.000144)
				)
				(arc
					(start 123.641866 -56.000396)
					(mid 124.000133 -56.358282)
					(end 124.358146 -56.000142)
				)
			)
		)
		(polygon
			(pts
				(arc
					(start 123.358148 -55.000144)
					(mid 123.000008 -54.642004)
					(end 122.641868 -55.000144)
				)
				(arc
					(start 122.641868 -56.000396)
					(mid 123.000135 -56.358282)
					(end 123.358148 -56.000142)
				)
			)
		)
		(polygon
			(pts
				(arc
					(start 122.35815 -55.000144)
					(mid 122.00001 -54.642004)
					(end 121.64187 -55.000144)
				)
				(arc
					(start 121.64187 -56.000396)
					(mid 122.000137 -56.358282)
					(end 122.35815 -56.000142)
				)
			)
		)
		(polygon
			(pts
				(arc
					(start 121.358152 -55.000144)
					(mid 121.000012 -54.642004)
					(end 120.641872 -55.000144)
				)
				(arc
					(start 120.641872 -56.000396)
					(mid 121.000139 -56.358282)
					(end 121.358152 -56.000142)
				)
			)
		)
		(polygon
			(pts
				(arc
					(start 120.358154 -55.000144)
					(mid 120.000014 -54.642004)
					(end 119.641874 -55.000144)
				)
				(arc
					(start 119.641874 -56.000396)
					(mid 120.000141 -56.358282)
					(end 120.358154 -56.000142)
				)
			)
		)
		(polygon
			(pts
				(arc
					(start 119.358156 -55.000144)
					(mid 119.000016 -54.642004)
					(end 118.641876 -55.000144)
				)
				(arc
					(start 118.641876 -56.000396)
					(mid 119.000143 -56.358282)
					(end 119.358156 -56.000142)
				)
			)
		)
		(polygon
			(pts
				(arc
					(start 118.358158 -55.000144)
					(mid 118.000018 -54.642004)
					(end 117.641878 -55.000144)
				)
				(arc
					(start 117.641878 -56.000396)
					(mid 118.000145 -56.358282)
					(end 118.358158 -56.000142)
				)
			)
		)
		(polygon
			(pts
				(arc
					(start 117.35816 -55.000144)
					(mid 117.00002 -54.642004)
					(end 116.64188 -55.000144)
				)
				(arc
					(start 116.64188 -56.000396)
					(mid 117.000147 -56.358282)
					(end 117.35816 -56.000142)
				)
			)
		)
		(polygon
			(pts
				(arc
					(start 116.358162 -55.000144)
					(mid 116.000022 -54.642004)
					(end 115.641882 -55.000144)
				)
				(arc
					(start 115.641882 -56.000396)
					(mid 116.000149 -56.358282)
					(end 116.358162 -56.000142)
				)
			)
		)
		(polygon
			(pts
				(arc
					(start 114.358166 -55.000144)
					(mid 114.000026 -54.642004)
					(end 113.641886 -55.000144)
				)
				(arc
					(start 113.641886 -56.000396)
					(mid 114.000153 -56.358282)
					(end 114.358166 -56.000142)
				)
			)
		)
		(polygon
			(pts
				(arc
					(start 113.358168 -55.000144)
					(mid 113.000028 -54.642004)
					(end 112.641888 -55.000144)
				)
				(arc
					(start 112.641888 -56.000396)
					(mid 113.000155 -56.358282)
					(end 113.358168 -56.000142)
				)
			)
		)
		(polygon
			(pts
				(arc
					(start 112.35817 -55.000144)
					(mid 112.00003 -54.642004)
					(end 111.64189 -55.000144)
				)
				(arc
					(start 111.64189 -56.000396)
					(mid 112.000157 -56.358282)
					(end 112.35817 -56.000142)
				)
			)
		)
		(polygon
			(pts
				(arc
					(start 111.358172 -55.000144)
					(mid 111.000032 -54.642004)
					(end 110.641892 -55.000144)
				)
				(arc
					(start 110.641892 -56.000396)
					(mid 111.000159 -56.358282)
					(end 111.358172 -56.000142)
				)
			)
		)
		(polygon
			(pts
				(arc
					(start 110.358174 -55.000144)
					(mid 110.000034 -54.642004)
					(end 109.641894 -55.000144)
				)
				(arc
					(start 109.641894 -56.000396)
					(mid 110.000161 -56.358282)
					(end 110.358174 -56.000142)
				)
			)
		)
		(polygon
			(pts
				(arc
					(start 109.358176 -55.000144)
					(mid 109.000036 -54.642004)
					(end 108.641896 -55.000144)
				)
				(arc
					(start 108.641896 -56.000396)
					(mid 109.000163 -56.358282)
					(end 109.358176 -56.000142)
				)
			)
		)
		(polygon
			(pts
				(arc
					(start 108.358178 -55.000144)
					(mid 108.000038 -54.642004)
					(end 107.641898 -55.000144)
				)
				(arc
					(start 107.641898 -56.000396)
					(mid 108.000165 -56.358282)
					(end 108.358178 -56.000142)
				)
			)
		)
		(polygon
			(pts
				(arc
					(start 107.35818 -55.000144)
					(mid 107.00004 -54.642004)
					(end 106.6419 -55.000144)
				)
				(arc
					(start 106.6419 -56.000396)
					(mid 107.000167 -56.358282)
					(end 107.35818 -56.000142)
				)
			)
		)
		(polygon
			(pts
				(arc
					(start 106.358182 -55.000144)
					(mid 106.000042 -54.642004)
					(end 105.641902 -55.000144)
				)
				(arc
					(start 105.641902 -56.000396)
					(mid 106.000169 -56.358282)
					(end 106.358182 -56.000142)
				)
			)
		)
		(polygon
			(pts
				(arc
					(start 105.358184 -55.000144)
					(mid 105.000044 -54.642004)
					(end 104.641904 -55.000144)
				)
				(arc
					(start 104.641904 -56.000396)
					(mid 105.000171 -56.358282)
					(end 105.358184 -56.000142)
				)
			)
		)
		(polygon
			(pts
				(arc
					(start 104.358186 -55.000144)
					(mid 104.000046 -54.642004)
					(end 103.641906 -55.000144)
				)
				(arc
					(start 103.641906 -56.000396)
					(mid 104.000173 -56.358282)
					(end 104.358186 -56.000142)
				)
			)
		)
		(polygon
			(pts
				(arc
					(start 103.358188 -55.000144)
					(mid 103.000048 -54.642004)
					(end 102.641908 -55.000144)
				)
				(arc
					(start 102.641908 -56.000396)
					(mid 103.000175 -56.358282)
					(end 103.358188 -56.000142)
				)
			)
		)
		(polygon
			(pts
				(arc
					(start 102.35819 -55.000144)
					(mid 102.00005 -54.642004)
					(end 101.64191 -55.000144)
				)
				(arc
					(start 101.64191 -56.000396)
					(mid 102.000177 -56.358282)
					(end 102.35819 -56.000142)
				)
			)
		)
		(polygon
			(pts
				(arc
					(start 101.358192 -55.000144)
					(mid 101.000052 -54.642004)
					(end 100.641912 -55.000144)
				)
				(arc
					(start 100.641912 -56.000396)
					(mid 101.000179 -56.358282)
					(end 101.358192 -56.000142)
				)
			)
		)
		(polygon
			(pts
				(arc
					(start 127 -54.358286)
					(mid 127.35814 -54.000146)
					(end 127 -53.642006)
				)
				(arc
					(start 125.999748 -53.642006)
					(mid 125.641862 -54.000273)
					(end 126.000002 -54.358286)
				)
			)
		)
		(polygon
			(pts
				(arc
					(start 99.358196 -54.000146)
					(mid 99.000056 -53.642006)
					(end 98.641916 -54.000146)
				)
				(arc
					(start 98.641916 -55.000398)
					(mid 99.000183 -55.358284)
					(end 99.358196 -55.000144)
				)
			)
		)
		(polygon
			(pts
				(arc
					(start 127.999998 -53.358288)
					(mid 128.358138 -53.000148)
					(end 127.999998 -52.642008)
				)
				(arc
					(start 126.999746 -52.642008)
					(mid 126.64186 -53.000275)
					(end 127 -53.358288)
				)
			)
		)
		(polygon
			(pts
				(arc
					(start 124.358146 -52.00015)
					(mid 124.000006 -51.64201)
					(end 123.641866 -52.00015)
				)
				(arc
					(start 123.641866 -53.000402)
					(mid 124.000133 -53.358288)
					(end 124.358146 -53.000148)
				)
			)
		)
		(polygon
			(pts
				(arc
					(start 122.35815 -52.00015)
					(mid 122.00001 -51.64201)
					(end 121.64187 -52.00015)
				)
				(arc
					(start 121.64187 -53.000402)
					(mid 122.000137 -53.358288)
					(end 122.35815 -53.000148)
				)
			)
		)
		(polygon
			(pts
				(arc
					(start 120.358154 -52.00015)
					(mid 120.000014 -51.64201)
					(end 119.641874 -52.00015)
				)
				(arc
					(start 119.641874 -53.000402)
					(mid 120.000141 -53.358288)
					(end 120.358154 -53.000148)
				)
			)
		)
		(polygon
			(pts
				(arc
					(start 118.358158 -52.00015)
					(mid 118.000018 -51.64201)
					(end 117.641878 -52.00015)
				)
				(arc
					(start 117.641878 -53.000402)
					(mid 118.000145 -53.358288)
					(end 118.358158 -53.000148)
				)
			)
		)
		(polygon
			(pts
				(arc
					(start 116.358162 -52.00015)
					(mid 116.000022 -51.64201)
					(end 115.641882 -52.00015)
				)
				(arc
					(start 115.641882 -53.000402)
					(mid 116.000149 -53.358288)
					(end 116.358162 -53.000148)
				)
			)
		)
		(polygon
			(pts
				(arc
					(start 113.358168 -52.00015)
					(mid 113.000028 -51.64201)
					(end 112.641888 -52.00015)
				)
				(arc
					(start 112.641888 -53.000402)
					(mid 113.000155 -53.358288)
					(end 113.358168 -53.000148)
				)
			)
		)
		(polygon
			(pts
				(arc
					(start 111.358172 -52.00015)
					(mid 111.000032 -51.64201)
					(end 110.641892 -52.00015)
				)
				(arc
					(start 110.641892 -53.000402)
					(mid 111.000159 -53.358288)
					(end 111.358172 -53.000148)
				)
			)
		)
		(polygon
			(pts
				(arc
					(start 109.358176 -52.00015)
					(mid 109.000036 -51.64201)
					(end 108.641896 -52.00015)
				)
				(arc
					(start 108.641896 -53.000402)
					(mid 109.000163 -53.358288)
					(end 109.358176 -53.000148)
				)
			)
		)
		(polygon
			(pts
				(arc
					(start 107.35818 -52.00015)
					(mid 107.00004 -51.64201)
					(end 106.6419 -52.00015)
				)
				(arc
					(start 106.6419 -53.000402)
					(mid 107.000167 -53.358288)
					(end 107.35818 -53.000148)
				)
			)
		)
		(polygon
			(pts
				(arc
					(start 105.358184 -52.00015)
					(mid 105.000044 -51.64201)
					(end 104.641904 -52.00015)
				)
				(arc
					(start 104.641904 -53.000402)
					(mid 105.000171 -53.358288)
					(end 105.358184 -53.000148)
				)
			)
		)
		(polygon
			(pts
				(arc
					(start 103.358188 -52.00015)
					(mid 103.000048 -51.64201)
					(end 102.641908 -52.00015)
				)
				(arc
					(start 102.641908 -53.000402)
					(mid 103.000175 -53.358288)
					(end 103.358188 -53.000148)
				)
			)
		)
		(polygon
			(pts
				(arc
					(start 101.358192 -52.00015)
					(mid 101.000052 -51.64201)
					(end 100.641912 -52.00015)
				)
				(arc
					(start 100.641912 -53.000402)
					(mid 101.000179 -53.358288)
					(end 101.358192 -53.000148)
				)
			)
		)
		(polygon
			(pts
				(arc
					(start 123.358148 -51.000152)
					(mid 123.000008 -50.642012)
					(end 122.641868 -51.000152)
				)
				(arc
					(start 122.641868 -52.000404)
					(mid 123.000135 -52.35829)
					(end 123.358148 -52.00015)
				)
			)
		)
		(polygon
			(pts
				(arc
					(start 121.358152 -51.000152)
					(mid 121.000012 -50.642012)
					(end 120.641872 -51.000152)
				)
				(arc
					(start 120.641872 -52.000404)
					(mid 121.000139 -52.35829)
					(end 121.358152 -52.00015)
				)
			)
		)
		(polygon
			(pts
				(arc
					(start 119.358156 -51.000152)
					(mid 119.000016 -50.642012)
					(end 118.641876 -51.000152)
				)
				(arc
					(start 118.641876 -52.000404)
					(mid 119.000143 -52.35829)
					(end 119.358156 -52.00015)
				)
			)
		)
		(polygon
			(pts
				(arc
					(start 117.35816 -51.000152)
					(mid 117.00002 -50.642012)
					(end 116.64188 -51.000152)
				)
				(arc
					(start 116.64188 -52.000404)
					(mid 117.000147 -52.35829)
					(end 117.35816 -52.00015)
				)
			)
		)
		(polygon
			(pts
				(arc
					(start 114.358166 -51.000152)
					(mid 114.000026 -50.642012)
					(end 113.641886 -51.000152)
				)
				(arc
					(start 113.641886 -52.000404)
					(mid 114.000153 -52.35829)
					(end 114.358166 -52.00015)
				)
			)
		)
		(polygon
			(pts
				(arc
					(start 112.35817 -51.000152)
					(mid 112.00003 -50.642012)
					(end 111.64189 -51.000152)
				)
				(arc
					(start 111.64189 -52.000404)
					(mid 112.000157 -52.35829)
					(end 112.35817 -52.00015)
				)
			)
		)
		(polygon
			(pts
				(arc
					(start 110.358174 -51.000152)
					(mid 110.000034 -50.642012)
					(end 109.641894 -51.000152)
				)
				(arc
					(start 109.641894 -52.000404)
					(mid 110.000161 -52.35829)
					(end 110.358174 -52.00015)
				)
			)
		)
		(polygon
			(pts
				(arc
					(start 108.358178 -51.000152)
					(mid 108.000038 -50.642012)
					(end 107.641898 -51.000152)
				)
				(arc
					(start 107.641898 -52.000404)
					(mid 108.000165 -52.35829)
					(end 108.358178 -52.00015)
				)
			)
		)
		(polygon
			(pts
				(arc
					(start 106.358182 -51.000152)
					(mid 106.000042 -50.642012)
					(end 105.641902 -51.000152)
				)
				(arc
					(start 105.641902 -52.000404)
					(mid 106.000169 -52.35829)
					(end 106.358182 -52.00015)
				)
			)
		)
		(polygon
			(pts
				(arc
					(start 104.358186 -51.000152)
					(mid 104.000046 -50.642012)
					(end 103.641906 -51.000152)
				)
				(arc
					(start 103.641906 -52.000404)
					(mid 104.000173 -52.35829)
					(end 104.358186 -52.00015)
				)
			)
		)
		(polygon
			(pts
				(arc
					(start 102.35819 -51.000152)
					(mid 102.00005 -50.642012)
					(end 101.64191 -51.000152)
				)
				(arc
					(start 101.64191 -52.000404)
					(mid 102.000177 -52.35829)
					(end 102.35819 -52.00015)
				)
			)
		)
		(polygon
			(pts
				(arc
					(start 100.358194 -51.000152)
					(mid 100.000054 -50.642012)
					(end 99.641914 -51.000152)
				)
				(arc
					(start 99.641914 -52.000404)
					(mid 100.000181 -52.35829)
					(end 100.358194 -52.00015)
				)
			)
		)
		(polygon
			(pts
				(arc
					(start 125.139958 -45.858938)
					(mid 124.682758 -45.401738)
					(end 124.225558 -45.858938)
				)
				(arc
					(start 124.225558 -47.002192)
					(mid 124.682885 -47.459138)
					(end 125.139958 -47.001938)
				)
			)
		)
		(polygon
			(pts
				(arc
					(start 127.533908 -45.844206)
					(mid 127.076708 -45.387006)
					(end 126.619508 -45.844206)
				)
				(arc
					(start 126.619508 -46.98746)
					(mid 127.076835 -47.444406)
					(end 127.533908 -46.987206)
				)
			)
		)
		(polygon
			(pts
				(arc
					(start 130.105658 -45.829474)
					(mid 129.648458 -45.372274)
					(end 129.191258 -45.829474)
				)
				(arc
					(start 129.191258 -46.972728)
					(mid 129.648585 -47.429674)
					(end 130.105658 -46.972474)
				)
			)
		)
		(polygon
			(pts
				(arc
					(start 132.677408 -45.814742)
					(mid 132.220208 -45.357542)
					(end 131.763008 -45.814742)
				)
				(arc
					(start 131.763008 -46.957996)
					(mid 132.220335 -47.414942)
					(end 132.677408 -46.957742)
				)
			)
		)
	)
	(zone
		(net "P12V_STBY_SCC")
		(layer "In3.Cu")
		(hatch none 0.5)
		(connect_pads
			(clearance 0.5)
		)
		(min_thickness 0.25)
		(fill yes
			(thermal_gap 0.5)
			(thermal_bridge_width 0.5)
			(island_removal_mode 0)
		)
		(polygon
			(pts
				(xy 1.27 -36.605464)
				(arc
					(start 1.27 -142.999968)
					(mid 1.483811 -143.516153)
					(end 1.999996 -143.729964)
				)
				(arc
					(start 83.002374 -143.729964)
					(mid 83.518723 -143.516243)
					(end 83.732624 -142.999968)
				)
				(arc
					(start 83.732624 -132.26288)
					(mid 85.23167 -128.194605)
					(end 89.012014 -126.07163)
				)
				(xy 97.399094 -124.730002) (xy 112.60074 -124.730002)
				(arc
					(start 120.9929 -126.072392)
					(mid 124.773392 -128.195293)
					(end 126.272544 -132.263642)
				)
				(arc
					(start 126.272544 -142.999968)
					(mid 126.486355 -143.516153)
					(end 127.00254 -143.729964)
				)
				(xy 167.371522 -143.729964) (xy 167.8051 -143.296386) (xy 167.8051 -106.426762) (xy 172.93844 -101.293422)
				(xy 172.93844 -77.246734) (xy 172.437806 -76.7461) (xy 158.016194 -76.7461) (xy 157.6959 -77.066394)
				(xy 157.6959 -94.777814) (xy 157.193234 -95.28048) (xy 138.460734 -95.28048) (xy 136.278874 -97.46234)
				(xy 133.768846 -97.46234) (xy 131.960366 -95.65386) (xy 51.330606 -95.65386) (xy 50.6095 -94.932754)
				(xy 50.6095 -88.242394) (xy 50.441606 -88.0745) (xy 35.682682 -88.0745) (xy 31.354776 -83.746594)
				(xy 31.354776 -62.432438) (xy 33.605978 -60.181236) (xy 33.605978 -37.13099) (xy 33.080452 -36.605464)
			)
		)
		(polygon
			(pts
				(arc
					(start 106.233722 -115.10899)
					(mid 106.009186 -114.366294)
					(end 105.26649 -114.59083)
				)
				(arc
					(start 104.516428 -115.990624)
					(mid 104.740809 -116.733627)
					(end 105.48366 -116.509038)
				)
			)
		)
		(polygon
			(pts
				(arc
					(start 103.983536 -115.10899)
					(mid 103.759 -114.366294)
					(end 103.016304 -114.59083)
				)
				(xy 102.266496 -115.990624)
				(arc
					(start 102.266496 -115.990878)
					(mid 102.491032 -116.733574)
					(end 103.233728 -116.509038)
				)
			)
		)
		(polygon
			(pts
				(arc
					(start 106.233722 -111.30915)
					(mid 106.009186 -110.566454)
					(end 105.26649 -110.79099)
				)
				(arc
					(start 104.516428 -112.190784)
					(mid 104.740809 -112.933787)
					(end 105.48366 -112.709198)
				)
			)
		)
		(polygon
			(pts
				(arc
					(start 103.983536 -111.30915)
					(mid 103.759 -110.566454)
					(end 103.016304 -110.79099)
				)
				(xy 102.266496 -112.190784)
				(arc
					(start 102.266496 -112.191038)
					(mid 102.491032 -112.933734)
					(end 103.233728 -112.709198)
				)
			)
		)
		(polygon
			(pts
				(arc
					(start 106.188256 -107.484672)
					(mid 105.984802 -106.811826)
					(end 105.311956 -107.01528)
				)
				(xy 105.311194 -107.014772) (xy 104.561386 -108.41482) (xy 104.561386 -108.415074)
				(arc
					(start 104.561894 -108.415328)
					(mid 104.765348 -109.088174)
					(end 105.438194 -108.88472)
				)
				(xy 105.438956 -108.885228) (xy 106.189018 -107.48518)
			)
		)
		(polygon
			(pts
				(arc
					(start 103.93807 -107.484672)
					(mid 103.734616 -106.811826)
					(end 103.06177 -107.01528)
				)
				(xy 103.061008 -107.015026) (xy 102.311454 -108.41482) (xy 102.311454 -108.415074)
				(arc
					(start 102.311962 -108.415328)
					(mid 102.515416 -109.088174)
					(end 103.188262 -108.88472)
				)
				(xy 103.189024 -108.884974) (xy 103.938832 -107.484926)
			)
		)
		(polygon
			(pts
				(arc
					(start 106.188256 -103.684832)
					(mid 105.984802 -103.011986)
					(end 105.311956 -103.21544)
				)
				(xy 105.311194 -103.214932) (xy 104.561386 -104.614472) (xy 104.561386 -104.61498)
				(arc
					(start 104.561894 -104.615234)
					(mid 104.765348 -105.28808)
					(end 105.438194 -105.084626)
				)
				(xy 105.438956 -105.085134) (xy 106.189018 -103.68534)
			)
		)
		(polygon
			(pts
				(arc
					(start 103.93807 -103.684832)
					(mid 103.734616 -103.011986)
					(end 103.06177 -103.21544)
				)
				(xy 103.061008 -103.215186) (xy 102.311454 -104.614726) (xy 102.311454 -104.61498)
				(arc
					(start 102.311962 -104.615234)
					(mid 102.515416 -105.28808)
					(end 103.188262 -105.084626)
				)
				(xy 103.189024 -105.08488) (xy 103.938832 -103.685086)
			)
		)
	)
	(zone
		(net "P12V_MAIN")
		(layer "In3.Cu")
		(hatch none 0.5)
		(connect_pads
			(clearance 0.5)
		)
		(min_thickness 0.25)
		(fill yes
			(thermal_gap 0.5)
			(thermal_bridge_width 0.5)
			(island_removal_mode 0)
		)
		(polygon
			(pts
				(arc
					(start 1.999996 -1.27)
					(mid 1.483811 -1.483811)
					(end 1.27 -1.999996)
				)
				(xy 1.27 -36.224464) (xy 33.080452 -36.224464) (xy 33.605978 -35.698938) (xy 33.605978 -28.02001)
				(xy 38.338252 -23.287736) (xy 38.338252 -1.754886) (xy 37.853366 -1.27)
			)
		)
	)
	(zone
		(net "P0V9")
		(layer "In3.Cu")
		(hatch none 0.5)
		(connect_pads
			(clearance 0.5)
		)
		(min_thickness 0.25)
		(fill yes
			(thermal_gap 0.5)
			(thermal_bridge_width 0.5)
			(island_removal_mode 0)
		)
		(polygon
			(pts
				(xy 59.921394 -33.8709) (xy 59.5503 -34.241994) (xy 59.5503 -46.662594) (xy 50.9905 -55.222394)
				(xy 50.9905 -94.774766) (xy 51.488594 -95.27286) (xy 121.094246 -95.27286) (xy 121.319544 -95.047562)
				(xy 121.319544 -71.520812) (xy 121.31929 -71.520558) (xy 121.31929 -71.36257) (xy 121.319544 -71.362316)
				(xy 121.319544 -62.969394) (xy 121.026936 -62.676786) (xy 98.127312 -62.676786) (xy 97.693226 -62.2427)
				(xy 73.784206 -62.2427) (xy 72.1741 -60.632594) (xy 72.1741 -34.328354) (xy 71.74103 -33.895284)
				(xy 71.74103 -33.8709)
			)
		)
	)
	(zone
		(net "SAS0_AVDD")
		(layer "In3.Cu")
		(hatch none 0.5)
		(connect_pads
			(clearance 0.5)
		)
		(min_thickness 0.25)
		(fill yes
			(thermal_gap 0.5)
			(thermal_bridge_width 0.5)
			(island_removal_mode 0)
		)
		(polygon
			(pts
				(xy 156.186886 -26.7335) (xy 154.887422 -28.032964) (xy 154.887422 -73.22312) (xy 158.029402 -76.3651)
				(xy 172.595794 -76.3651) (xy 173.31944 -77.088746) (xy 173.31944 -100.416614) (xy 173.646338 -100.743512)
				(xy 185.823606 -100.743512) (xy 186.15025 -100.416868) (xy 186.15025 -91.786456) (xy 186.4995 -91.437206)
				(xy 186.4995 -80.780636) (xy 164.7825 -59.063636) (xy 164.7825 -41.652698) (xy 165.376098 -41.0591)
				(xy 169.643806 -41.0591) (xy 170.3451 -40.357806) (xy 170.3451 -34.833814)
				(arc
					(start 170.3451 -34.833052)
					(mid 170.36161 -34.751006)
					(end 170.408092 -34.681414)
				)
				(xy 171.1833 -33.906206)
				(arc
					(start 171.1833 -31.507938)
					(mid 170.822983 -31.511401)
					(end 170.642026 -31.199836)
				)
				(arc
					(start 170.641772 -30.400244)
					(mid 170.822911 -30.088646)
					(end 171.1833 -30.092396)
				)
				(xy 171.1833 -27.079194) (xy 170.837606 -26.7335)
			)
		)
		(polygon
			(pts
				(arc
					(start 166.58336 -37.59962)
					(mid 166.199693 -37.216334)
					(end 165.81628 -37.599874)
				)
				(arc
					(start 165.81628 -38.399974)
					(mid 166.19982 -38.783514)
					(end 166.58336 -38.399974)
				)
			)
		)
		(polygon
			(pts
				(arc
					(start 166.200074 -37.183568)
					(mid 166.58336 -36.799901)
					(end 166.19982 -36.416488)
				)
				(arc
					(start 165.399974 -36.416488)
					(mid 165.016434 -36.800028)
					(end 165.399974 -37.183568)
				)
			)
		)
		(polygon
			(pts
				(arc
					(start 166.58336 -35.199574)
					(mid 166.199693 -34.816288)
					(end 165.81628 -35.199828)
				)
				(arc
					(start 165.81628 -35.999928)
					(mid 166.19982 -36.383468)
					(end 166.58336 -35.999928)
				)
			)
		)
		(polygon
			(pts
				(arc
					(start 166.200074 -34.783522)
					(mid 166.58336 -34.399855)
					(end 166.19982 -34.016442)
				)
				(arc
					(start 165.399974 -34.016442)
					(mid 165.016434 -34.399982)
					(end 165.399974 -34.783522)
				)
			)
		)
		(polygon
			(pts
				(arc
					(start 166.58336 -32.799782)
					(mid 166.199693 -32.416496)
					(end 165.81628 -32.800036)
				)
				(arc
					(start 165.81628 -33.599882)
					(mid 166.19982 -33.983422)
					(end 166.58336 -33.599882)
				)
			)
		)
		(polygon
			(pts
				(arc
					(start 167.000174 -32.383476)
					(mid 167.38346 -31.999809)
					(end 166.99992 -31.616396)
				)
				(arc
					(start 166.200074 -31.616396)
					(mid 165.816534 -31.999936)
					(end 166.200074 -32.383476)
				)
			)
		)
		(polygon
			(pts
				(arc
					(start 168.958006 -30.39999)
					(mid 168.599866 -30.04185)
					(end 168.241726 -30.39999)
				)
				(arc
					(start 168.241726 -31.20009)
					(mid 168.599993 -31.557976)
					(end 168.958006 -31.199836)
				)
			)
		)
		(polygon
			(pts
				(arc
					(start 170.557952 -30.39999)
					(mid 170.199685 -30.04185)
					(end 169.841672 -30.400244)
				)
				(arc
					(start 169.841926 -31.199836)
					(mid 170.200066 -31.55823)
					(end 170.558206 -31.199836)
				)
				(xy 170.557952 -30.400244)
			)
		)
		(polygon
			(pts
				(arc
					(start 168.157906 -30.39999)
					(mid 167.799639 -30.04185)
					(end 167.441626 -30.400244)
				)
				(arc
					(start 167.44188 -31.199582)
					(mid 167.80002 -31.557976)
					(end 168.15816 -31.199582)
				)
				(xy 168.157906 -30.400244)
			)
		)
		(polygon
			(pts
				(arc
					(start 166.58336 -30.399736)
					(mid 166.199693 -30.01645)
					(end 165.81628 -30.39999)
				)
				(arc
					(start 165.81628 -31.199836)
					(mid 166.19982 -31.583376)
					(end 166.58336 -31.199836)
				)
			)
		)
		(polygon
			(pts
				(arc
					(start 166.200074 -29.21635)
					(mid 165.81628 -29.599763)
					(end 166.19982 -29.98343)
				)
				(arc
					(start 166.999412 -29.983684)
					(mid 167.383206 -29.600271)
					(end 166.999666 -29.216604)
				)
			)
		)
	)
	(zone
		(net "P3V3")
		(layer "In4.Cu")
		(hatch none 0.5)
		(connect_pads
			(clearance 0.5)
		)
		(min_thickness 0.25)
		(fill yes
			(thermal_gap 0.5)
			(thermal_bridge_width 0.5)
			(island_removal_mode 0)
		)
		(polygon
			(pts
				(xy 91.010994 -98.1075) (xy 83.841082 -105.277412) (xy 46.88586 -105.277412) (xy 45.9105 -106.252772)
				(xy 45.9105 -143.411702) (xy 46.228762 -143.729964)
				(arc
					(start 83.002374 -143.729964)
					(mid 83.518723 -143.516243)
					(end 83.732624 -142.999968)
				)
				(arc
					(start 83.732624 -132.26288)
					(mid 85.23167 -128.194605)
					(end 89.012014 -126.07163)
				)
				(xy 97.399094 -124.730002) (xy 112.60074 -124.730002)
				(arc
					(start 120.9929 -126.072392)
					(mid 124.773392 -128.195293)
					(end 126.272544 -132.263642)
				)
				(arc
					(start 126.272544 -142.999968)
					(mid 126.486355 -143.516153)
					(end 127.00254 -143.729964)
				)
				(arc
					(start 208.000092 -143.729964)
					(mid 208.516277 -143.516153)
					(end 208.730088 -142.999968)
				)
				(arc
					(start 208.730088 -103.87203)
					(mid 208.710655 -103.858694)
					(end 208.693004 -103.843074)
				)
				(xy 208.418176 -103.5685) (xy 201.526394 -103.5685) (xy 200.078594 -105.0163) (xy 165.788594 -105.0163)
				(xy 163.146994 -107.6579) (xy 156.187394 -107.6579) (xy 153.494994 -110.3503) (xy 136.778238 -110.3503)
				(xy 127.964438 -101.5365) (xy 114.729006 -101.5365) (xy 111.300006 -98.1075)
			)
		)
		(polygon
			(pts
				(arc
					(start 106.233722 -115.10899)
					(mid 106.009186 -114.366294)
					(end 105.26649 -114.59083)
				)
				(arc
					(start 104.516428 -115.990624)
					(mid 104.740809 -116.733627)
					(end 105.48366 -116.509038)
				)
			)
		)
		(polygon
			(pts
				(arc
					(start 103.983536 -115.10899)
					(mid 103.759 -114.366294)
					(end 103.016304 -114.59083)
				)
				(xy 102.266496 -115.990624)
				(arc
					(start 102.266496 -115.990878)
					(mid 102.491032 -116.733574)
					(end 103.233728 -116.509038)
				)
			)
		)
		(polygon
			(pts
				(arc
					(start 106.233722 -111.30915)
					(mid 106.009186 -110.566454)
					(end 105.26649 -110.79099)
				)
				(arc
					(start 104.516428 -112.190784)
					(mid 104.740809 -112.933787)
					(end 105.48366 -112.709198)
				)
			)
		)
		(polygon
			(pts
				(arc
					(start 103.983536 -111.30915)
					(mid 103.759 -110.566454)
					(end 103.016304 -110.79099)
				)
				(xy 102.266496 -112.190784)
				(arc
					(start 102.266496 -112.191038)
					(mid 102.491032 -112.933734)
					(end 103.233728 -112.709198)
				)
			)
		)
		(polygon
			(pts
				(arc
					(start 106.188256 -107.484672)
					(mid 105.984802 -106.811826)
					(end 105.311956 -107.01528)
				)
				(xy 105.311194 -107.014772) (xy 104.561386 -108.41482) (xy 104.561386 -108.415074)
				(arc
					(start 104.561894 -108.415328)
					(mid 104.765348 -109.088174)
					(end 105.438194 -108.88472)
				)
				(xy 105.438956 -108.885228) (xy 106.189018 -107.48518)
			)
		)
		(polygon
			(pts
				(arc
					(start 103.93807 -107.484672)
					(mid 103.734616 -106.811826)
					(end 103.06177 -107.01528)
				)
				(xy 103.061008 -107.015026) (xy 102.311454 -108.41482) (xy 102.311454 -108.415074)
				(arc
					(start 102.311962 -108.415328)
					(mid 102.515416 -109.088174)
					(end 103.188262 -108.88472)
				)
				(xy 103.189024 -108.884974) (xy 103.938832 -107.484926)
			)
		)
		(polygon
			(pts
				(arc
					(start 106.188256 -103.684832)
					(mid 105.984802 -103.011986)
					(end 105.311956 -103.21544)
				)
				(xy 105.311194 -103.214932) (xy 104.561386 -104.614472) (xy 104.561386 -104.61498)
				(arc
					(start 104.561894 -104.615234)
					(mid 104.765348 -105.28808)
					(end 105.438194 -105.084626)
				)
				(xy 105.438956 -105.085134) (xy 106.189018 -103.68534)
			)
		)
		(polygon
			(pts
				(arc
					(start 103.93807 -103.684832)
					(mid 103.734616 -103.011986)
					(end 103.06177 -103.21544)
				)
				(xy 103.061008 -103.215186) (xy 102.311454 -104.614726) (xy 102.311454 -104.61498)
				(arc
					(start 102.311962 -104.615234)
					(mid 102.515416 -105.28808)
					(end 103.188262 -105.084626)
				)
				(xy 103.189024 -105.08488) (xy 103.938832 -103.685086)
			)
		)
	)
	(zone
		(net "P0V9")
		(layer "In4.Cu")
		(hatch none 0.5)
		(connect_pads
			(clearance 0.5)
		)
		(min_thickness 0.25)
		(fill yes
			(thermal_gap 0.5)
			(thermal_bridge_width 0.5)
			(island_removal_mode 0)
		)
		(polygon
			(pts
				(xy 59.921394 -33.8709) (xy 59.5503 -34.241994) (xy 59.5503 -46.801786)
				(arc
					(start 59.5503 -46.802548)
					(mid 59.53379 -46.884594)
					(end 59.487308 -46.954186)
				)
				(xy 50.9905 -55.450994) (xy 50.9905 -77.390752) (xy 50.990754 -77.391006) (xy 50.990754 -79.14386)
				(xy 52.377594 -80.5307) (xy 85.797644 -80.5307) (xy 86.957662 -79.370682) (xy 95.46463 -79.370682)
				(xy 96.624648 -80.5307) (xy 98.193606 -80.5307) (xy 98.447606 -80.2767) (xy 105.18267 -80.2767)
				(xy 105.27919 -80.18018) (xy 105.27919 -79.691992) (xy 105.753662 -79.21752) (xy 106.249978 -79.21752)
				(xy 106.2863 -79.181198) (xy 106.2863 -72.038972) (xy 107.074208 -71.251064) (xy 118.242842 -71.251064)
				(xy 118.4529 -71.041006) (xy 118.4529 -65.052194) (xy 117.980206 -64.5795) (xy 111.000794 -64.5795)
				(xy 109.883194 -65.6971) (xy 98.142806 -65.6971) (xy 97.5233 -65.077594) (xy 97.5233 -62.235334)
				(xy 73.77684 -62.235334) (xy 72.1741 -60.632594) (xy 72.1741 -34.216594) (xy 71.828406 -33.8709)
			)
		)
	)
	(zone
		(net "P5V")
		(layer "In4.Cu")
		(hatch none 0.5)
		(connect_pads
			(clearance 0.5)
		)
		(min_thickness 0.25)
		(fill yes
			(thermal_gap 0.5)
			(thermal_bridge_width 0.5)
			(island_removal_mode 0)
		)
		(polygon
			(pts
				(xy 193.271394 -74.0537) (xy 192.6463 -74.678794) (xy 192.6463 -95.049594) (xy 189.969394 -97.7265)
				(xy 184.655206 -97.7265) (xy 182.750206 -95.8215) (xy 175.643794 -95.8215) (xy 171.808394 -99.6569)
				(xy 163.832794 -99.6569) (xy 161.114994 -102.3747) (xy 148.841206 -102.3747) (xy 142.2908 -95.824294)
				(xy 128.3208 -95.824294) (xy 119.8626 -95.824294) (xy 114.424206 -90.3859) (xy 69.212206 -90.3859)
				(xy 68.348606 -89.5223) (xy 22.928072 -89.5223) (xy 22.665182 -89.78519) (xy 22.665182 -114.112802)
				(xy 23.999698 -115.447318) (xy 45.289978 -115.447318) (xy 45.5295 -115.207796) (xy 45.5295 -106.094784)
				(xy 46.727872 -104.896412) (xy 83.683094 -104.896412) (xy 90.853006 -97.7265) (xy 111.457994 -97.7265)
				(xy 114.886994 -101.1555) (xy 128.122426 -101.1555) (xy 136.936226 -109.9693) (xy 153.337006 -109.9693)
				(xy 156.029406 -107.2769) (xy 162.989006 -107.2769) (xy 165.630606 -104.6353) (xy 199.920606 -104.6353)
				(xy 201.2569 -103.299006) (xy 201.2569 -78.615794) (xy 196.694806 -74.0537)
			)
		)
	)
	(zone
		(net "PCE_AVDD")
		(layer "In4.Cu")
		(hatch none 0.5)
		(connect_pads
			(clearance 0.5)
		)
		(min_thickness 0.25)
		(fill yes
			(thermal_gap 0.5)
			(thermal_bridge_width 0.5)
			(island_removal_mode 0)
		)
		(polygon
			(pts
				(xy 156.688536 -25.698958) (xy 155.8925 -26.494994) (xy 155.8925 -81.251806) (xy 156.974794 -82.3341)
				(xy 175.104806 -82.3341) (xy 175.3743 -82.064606) (xy 175.3743 -74.831194) (xy 164.8079 -64.264794)
				(arc
					(start 164.8079 -41.25976)
					(mid 164.824294 -41.177744)
					(end 164.870638 -41.108122)
				)
				(xy 164.871146 -41.107614) (xy 165.376606 -40.6019) (xy 166.951406 -40.6019) (xy 167.1955 -40.357806)
				(xy 167.1955 -35.049206)
				(arc
					(start 167.523414 -34.721292)
					(mid 167.593012 -34.674825)
					(end 167.675052 -34.6583)
				)
				(xy 167.675814 -34.6583) (xy 179.829206 -34.6583) (xy 180.0733 -34.414206) (xy 180.0733 -27.764994)
				(xy 178.007264 -25.698958)
			)
		)
		(polygon
			(pts
				(arc
					(start 166.58336 -37.59962)
					(mid 166.199693 -37.216334)
					(end 165.81628 -37.599874)
				)
				(arc
					(start 165.81628 -38.399974)
					(mid 166.19982 -38.783514)
					(end 166.58336 -38.399974)
				)
			)
		)
		(polygon
			(pts
				(arc
					(start 166.200074 -37.183568)
					(mid 166.58336 -36.799901)
					(end 166.19982 -36.416488)
				)
				(arc
					(start 165.399974 -36.416488)
					(mid 165.016434 -36.800028)
					(end 165.399974 -37.183568)
				)
			)
		)
		(polygon
			(pts
				(arc
					(start 166.58336 -35.199574)
					(mid 166.199693 -34.816288)
					(end 165.81628 -35.199828)
				)
				(arc
					(start 165.81628 -35.999928)
					(mid 166.19982 -36.383468)
					(end 166.58336 -35.999928)
				)
			)
		)
		(polygon
			(pts
				(arc
					(start 166.200074 -34.783522)
					(mid 166.58336 -34.399855)
					(end 166.19982 -34.016442)
				)
				(arc
					(start 165.399974 -34.016442)
					(mid 165.016434 -34.399982)
					(end 165.399974 -34.783522)
				)
			)
		)
		(polygon
			(pts
				(arc
					(start 166.58336 -32.799782)
					(mid 166.199693 -32.416496)
					(end 165.81628 -32.800036)
				)
				(arc
					(start 165.81628 -33.599882)
					(mid 166.19982 -33.983422)
					(end 166.58336 -33.599882)
				)
			)
		)
		(polygon
			(pts
				(arc
					(start 167.000174 -32.383476)
					(mid 167.38346 -31.999809)
					(end 166.99992 -31.616396)
				)
				(arc
					(start 166.200074 -31.616396)
					(mid 165.816534 -31.999936)
					(end 166.200074 -32.383476)
				)
			)
		)
		(polygon
			(pts
				(arc
					(start 176.158144 -30.400244)
					(mid 175.800004 -30.042104)
					(end 175.441864 -30.400244)
				)
				(arc
					(start 175.441864 -31.200344)
					(mid 175.800131 -31.55823)
					(end 176.158144 -31.20009)
				)
			)
		)
		(polygon
			(pts
				(arc
					(start 168.958006 -30.39999)
					(mid 168.599866 -30.04185)
					(end 168.241726 -30.39999)
				)
				(arc
					(start 168.241726 -31.20009)
					(mid 168.599993 -31.557976)
					(end 168.958006 -31.199836)
				)
			)
		)
		(polygon
			(pts
				(arc
					(start 175.358044 -30.39999)
					(mid 174.999777 -30.04185)
					(end 174.641764 -30.400244)
				)
				(arc
					(start 174.642018 -31.199836)
					(mid 175.000158 -31.55823)
					(end 175.358298 -31.199836)
				)
				(xy 175.358044 -30.400244)
			)
		)
		(polygon
			(pts
				(arc
					(start 173.758098 -30.39999)
					(mid 173.399831 -30.04185)
					(end 173.041818 -30.400244)
				)
				(arc
					(start 173.042072 -31.199836)
					(mid 173.400212 -31.55823)
					(end 173.758352 -31.199836)
				)
				(xy 173.758098 -30.400244)
			)
		)
		(polygon
			(pts
				(arc
					(start 172.957998 -30.39999)
					(mid 172.599731 -30.04185)
					(end 172.241718 -30.400244)
				)
				(arc
					(start 172.241972 -31.199836)
					(mid 172.600112 -31.55823)
					(end 172.958252 -31.199836)
				)
				(xy 172.957998 -30.400244)
			)
		)
		(polygon
			(pts
				(arc
					(start 171.358052 -30.39999)
					(mid 170.999785 -30.04185)
					(end 170.641772 -30.400244)
				)
				(arc
					(start 170.642026 -31.199836)
					(mid 171.000166 -31.55823)
					(end 171.358306 -31.199836)
				)
				(xy 171.358052 -30.400244)
			)
		)
		(polygon
			(pts
				(arc
					(start 170.557952 -30.39999)
					(mid 170.199685 -30.04185)
					(end 169.841672 -30.400244)
				)
				(arc
					(start 169.841926 -31.199836)
					(mid 170.200066 -31.55823)
					(end 170.558206 -31.199836)
				)
				(xy 170.557952 -30.400244)
			)
		)
		(polygon
			(pts
				(arc
					(start 168.157906 -30.39999)
					(mid 167.799639 -30.04185)
					(end 167.441626 -30.400244)
				)
				(arc
					(start 167.44188 -31.199582)
					(mid 167.80002 -31.557976)
					(end 168.15816 -31.199582)
				)
				(xy 168.157906 -30.400244)
			)
		)
		(polygon
			(pts
				(arc
					(start 166.58336 -30.399736)
					(mid 166.199693 -30.01645)
					(end 165.81628 -30.39999)
				)
				(arc
					(start 165.81628 -31.199836)
					(mid 166.19982 -31.583376)
					(end 166.58336 -31.199836)
				)
			)
		)
		(polygon
			(pts
				(arc
					(start 166.200074 -29.21635)
					(mid 165.81628 -29.599763)
					(end 166.19982 -29.98343)
				)
				(arc
					(start 166.999412 -29.983684)
					(mid 167.383206 -29.600271)
					(end 166.999666 -29.216604)
				)
			)
		)
	)
	(zone
		(net "GND")
		(layer "In4.Cu")
		(hatch none 0.5)
		(connect_pads
			(clearance 0.5)
		)
		(min_thickness 0.25)
		(fill yes
			(thermal_gap 0.5)
			(thermal_bridge_width 0.5)
			(island_removal_mode 0)
		)
		(polygon
			(pts
				(arc
					(start 1.999996 -1.27)
					(mid 1.483811 -1.483811)
					(end 1.27 -1.999996)
				)
				(arc
					(start 1.27 -142.999968)
					(mid 1.483811 -143.516153)
					(end 1.999996 -143.729964)
				)
				(arc
					(start 45.221906 -143.729964)
					(mid 45.236819 -143.706793)
					(end 45.254926 -143.686022)
				)
				(xy 45.5295 -143.411194) (xy 45.5295 -116.067332) (xy 45.290486 -115.828318) (xy 23.84171 -115.828318)
				(xy 22.284182 -114.27079) (xy 22.284182 -89.784682) (xy 22.0218 -89.5223) (xy 7.947406 -89.5223)
				(xy 6.0579 -87.632794) (xy 6.0579 -80.947006) (xy 9.217406 -77.7875) (xy 23.314406 -77.7875) (xy 25.0571 -76.044806)
				(xy 25.0571 -46.022006) (xy 30.5943 -40.484806) (xy 30.5943 -25.067006) (xy 38.402006 -17.2593)
				(xy 59.204606 -17.2593) (xy 59.9313 -16.532606) (xy 59.9313 -13.891006) (xy 61.416692 -12.405614)
				(xy 66.729102 -12.405614) (xy 67.3735 -13.050012) (xy 67.3735 -19.992594) (xy 63.832994 -23.5331)
				(xy 40.210994 -23.5331) (xy 35.2171 -28.526994) (xy 35.2171 -45.113194) (xy 30.0355 -50.294794)
				(xy 30.0355 -75.867006) (xy 31.447994 -77.2795) (xy 50.263806 -77.2795) (xy 50.6095 -76.933806)
				(xy 50.6095 -55.293006) (xy 59.1693 -46.733206)
				(arc
					(start 59.1693 -34.17316)
					(mid 59.185694 -34.091144)
					(end 59.232038 -34.021522)
				)
				(xy 59.232546 -34.021014) (xy 59.763406 -33.4899) (xy 85.061806 -33.4899) (xy 88.516206 -30.0355)
				(xy 142.542006 -30.0355) (xy 142.9131 -29.664406) (xy 142.9131 -25.771856) (xy 150.718774 -17.966182)
				(xy 150.718774 -4.07035) (xy 152.04186 -2.747264) (xy 168.04259 -2.747264) (xy 168.753536 -3.45821)
				(xy 168.753536 -5.207) (xy 167.24884 -6.711696) (xy 155.552394 -6.711696) (xy 155.011374 -7.252716)
				(xy 155.011374 -20.6375) (xy 147.5613 -28.087574) (xy 147.5613 -34.597594) (xy 146.4945 -35.664394)
				(xy 146.4945 -55.013606) (xy 148.3233 -56.842406) (xy 148.3233 -77.137006) (xy 151.1681 -79.981806)
				(xy 151.1681 -86.382606) (xy 151.742394 -86.9569) (xy 155.780994 -86.9569) (xy 163.9443 -95.120206)
				(xy 163.9443 -98.981006) (xy 164.239194 -99.2759) (xy 171.650406 -99.2759) (xy 175.3743 -95.552006)
				(xy 175.3743 -83.0326) (xy 175.35398 -83.01482) (xy 175.054006 -82.7151) (xy 156.816806 -82.7151)
				(xy 155.5115 -81.409794) (xy 155.5115 -26.337006) (xy 156.530548 -25.317958) (xy 178.165252 -25.317958)
				(xy 180.4543 -27.607006) (xy 180.4543 -34.414206) (xy 180.698394 -34.6583) (xy 186.057794 -34.6583)
				(xy 186.8551 -35.455606) (xy 186.8551 -63.649606) (xy 193.3829 -70.177406) (xy 193.3829 -73.301606)
				(xy 193.753994 -73.6727) (xy 196.852794 -73.6727) (xy 201.6379 -78.457806) (xy 201.6379 -103.1875)
				(xy 208.418684 -103.1875) (xy 208.730088 -102.876096)
				(arc
					(start 208.730088 -1.999996)
					(mid 208.516277 -1.483811)
					(end 208.000092 -1.27)
				)
			)
		)
		(polygon
			(pts
				(arc
					(start 150.087584 -54.478174)
					(mid 149.735286 -53.935884)
					(end 149.192996 -54.288182)
				)
				(arc
					(start 148.957792 -55.395876)
					(mid 149.302356 -55.947245)
					(end 149.84984 -55.596282)
				)
			)
		)
		(polygon
			(pts
				(arc
					(start 149.037294 -50.520092)
					(mid 148.69273 -49.968723)
					(end 148.145246 -50.319686)
				)
				(arc
					(start 147.907502 -51.437794)
					(mid 148.2598 -51.980084)
					(end 148.80209 -51.627786)
				)
			)
		)
		(polygon
			(pts
				(arc
					(start 147.989544 -46.551596)
					(mid 147.64498 -46.000227)
					(end 147.097496 -46.35119)
				)
				(arc
					(start 146.859752 -47.469298)
					(mid 147.21205 -48.011588)
					(end 147.75434 -47.65929)
				)
			)
		)
		(polygon
			(pts
				(arc
					(start 150.230078 -44.309284)
					(mid 149.885514 -43.757915)
					(end 149.33803 -44.108878)
				)
				(arc
					(start 149.100286 -45.226986)
					(mid 149.452584 -45.769276)
					(end 149.994874 -45.416978)
				)
			)
		)
		(polygon
			(pts
				(arc
					(start 149.309328 -40.340788)
					(mid 148.964764 -39.789419)
					(end 148.41728 -40.140382)
				)
				(arc
					(start 148.179536 -41.25849)
					(mid 148.531834 -41.80078)
					(end 149.074124 -41.448482)
				)
			)
		)
		(polygon
			(pts
				(arc
					(start 151.676862 -38.098476)
					(mid 151.332298 -37.547107)
					(end 150.784814 -37.89807)
				)
				(arc
					(start 150.54707 -39.016178)
					(mid 150.899368 -39.558468)
					(end 151.441658 -39.20617)
				)
			)
		)
		(polygon
			(pts
				(arc
					(start 149.814534 -35.21329)
					(mid 149.46997 -34.661921)
					(end 148.922486 -35.012884)
				)
				(arc
					(start 148.684742 -36.130992)
					(mid 149.03704 -36.673282)
					(end 149.57933 -36.320984)
				)
			)
		)
		(polygon
			(pts
				(arc
					(start 180.819552 -23.596346)
					(mid 180.436012 -23.212806)
					(end 180.052472 -23.596346)
				)
				(arc
					(start 180.052472 -24.4856)
					(mid 180.436139 -24.868886)
					(end 180.819552 -24.485346)
				)
			)
		)
		(polygon
			(pts
				(arc
					(start 166.508938 -23.166832)
					(mid 166.125398 -22.783292)
					(end 165.741858 -23.166832)
				)
				(arc
					(start 165.741858 -24.056086)
					(mid 166.125525 -24.439372)
					(end 166.508938 -24.055832)
				)
			)
		)
		(polygon
			(pts
				(arc
					(start 168.543478 -23.123906)
					(mid 168.159938 -22.740366)
					(end 167.776398 -23.123906)
				)
				(arc
					(start 167.776398 -24.01316)
					(mid 168.160065 -24.396446)
					(end 168.543478 -24.012906)
				)
			)
		)
		(polygon
			(pts
				(arc
					(start 178.790854 -23.11654)
					(mid 178.407314 -22.733)
					(end 178.023774 -23.11654)
				)
				(arc
					(start 178.023774 -24.005794)
					(mid 178.407441 -24.38908)
					(end 178.790854 -24.00554)
				)
			)
		)
		(polygon
			(pts
				(arc
					(start 170.600624 -23.11527)
					(mid 170.217084 -22.73173)
					(end 169.833544 -23.11527)
				)
				(arc
					(start 169.833544 -24.004524)
					(mid 170.217211 -24.38781)
					(end 170.600624 -24.00427)
				)
			)
		)
		(polygon
			(pts
				(arc
					(start 172.65269 -23.112984)
					(mid 172.26915 -22.729444)
					(end 171.88561 -23.112984)
				)
				(arc
					(start 171.88561 -24.002238)
					(mid 172.269277 -24.385524)
					(end 172.65269 -24.001984)
				)
			)
		)
		(polygon
			(pts
				(arc
					(start 174.698406 -23.112476)
					(mid 174.314866 -22.728936)
					(end 173.931326 -23.112476)
				)
				(arc
					(start 173.931326 -24.00173)
					(mid 174.314993 -24.385016)
					(end 174.698406 -24.001476)
				)
			)
		)
		(polygon
			(pts
				(arc
					(start 176.75225 -23.103332)
					(mid 176.36871 -22.719792)
					(end 175.98517 -23.103332)
				)
				(arc
					(start 175.98517 -23.992586)
					(mid 176.368837 -24.375872)
					(end 176.75225 -23.992332)
				)
			)
		)
		(polygon
			(pts
				(arc
					(start 191.361314 -10.999978)
					(mid 190.799974 -10.438638)
					(end 190.238634 -10.999978)
				)
				(arc
					(start 190.238634 -12.40028)
					(mid 190.800101 -12.961366)
					(end 191.361314 -12.400026)
				)
			)
		)
		(polygon
			(pts
				(arc
					(start 187.761118 -10.999978)
					(mid 187.199778 -10.438638)
					(end 186.638438 -10.999978)
				)
				(arc
					(start 186.638438 -12.40028)
					(mid 187.199905 -12.961366)
					(end 187.761118 -12.400026)
				)
			)
		)
		(polygon
			(pts
				(arc
					(start 184.161176 -10.999978)
					(mid 183.599836 -10.438638)
					(end 183.038496 -10.999978)
				)
				(arc
					(start 183.038496 -12.40028)
					(mid 183.599963 -12.961366)
					(end 184.161176 -12.400026)
				)
			)
		)
		(polygon
			(pts
				(arc
					(start 180.561234 -10.999978)
					(mid 179.999894 -10.438638)
					(end 179.438554 -10.999978)
				)
				(arc
					(start 179.438554 -12.40028)
					(mid 180.000021 -12.961366)
					(end 180.561234 -12.400026)
				)
			)
		)
		(polygon
			(pts
				(arc
					(start 147.761452 -10.999978)
					(mid 147.200112 -10.438638)
					(end 146.638772 -10.999978)
				)
				(arc
					(start 146.638772 -12.40028)
					(mid 147.200239 -12.961366)
					(end 147.761452 -12.400026)
				)
			)
		)
		(polygon
			(pts
				(arc
					(start 144.16151 -10.999978)
					(mid 143.60017 -10.438638)
					(end 143.03883 -10.999978)
				)
				(arc
					(start 143.03883 -12.40028)
					(mid 143.600297 -12.961366)
					(end 144.16151 -12.400026)
				)
			)
		)
		(polygon
			(pts
				(arc
					(start 140.561314 -10.999978)
					(mid 139.999974 -10.438638)
					(end 139.438634 -10.999978)
				)
				(arc
					(start 139.438634 -12.40028)
					(mid 140.000101 -12.961366)
					(end 140.561314 -12.400026)
				)
			)
		)
		(polygon
			(pts
				(arc
					(start 136.961372 -10.999978)
					(mid 136.400032 -10.438638)
					(end 135.838692 -10.999978)
				)
				(arc
					(start 135.838692 -12.40028)
					(mid 136.400159 -12.961366)
					(end 136.961372 -12.400026)
				)
			)
		)
		(polygon
			(pts
				(arc
					(start 133.36143 -10.999978)
					(mid 132.80009 -10.438638)
					(end 132.23875 -10.999978)
				)
				(arc
					(start 132.23875 -12.40028)
					(mid 132.800217 -12.961366)
					(end 133.36143 -12.400026)
				)
			)
		)
		(polygon
			(pts
				(arc
					(start 129.761488 -10.999978)
					(mid 129.200148 -10.438638)
					(end 128.638808 -10.999978)
				)
				(arc
					(start 128.638808 -12.40028)
					(mid 129.200275 -12.961366)
					(end 129.761488 -12.400026)
				)
			)
		)
		(polygon
			(pts
				(arc
					(start 126.161546 -10.999978)
					(mid 125.600206 -10.438638)
					(end 125.038866 -10.999978)
				)
				(arc
					(start 125.038866 -12.40028)
					(mid 125.600333 -12.961366)
					(end 126.161546 -12.400026)
				)
			)
		)
		(polygon
			(pts
				(arc
					(start 122.56135 -10.999978)
					(mid 122.00001 -10.438638)
					(end 121.43867 -10.999978)
				)
				(arc
					(start 121.43867 -12.40028)
					(mid 122.000137 -12.961366)
					(end 122.56135 -12.400026)
				)
			)
		)
		(polygon
			(pts
				(arc
					(start 118.961408 -10.999978)
					(mid 118.400068 -10.438638)
					(end 117.838728 -10.999978)
				)
				(arc
					(start 117.838728 -12.40028)
					(mid 118.400195 -12.961366)
					(end 118.961408 -12.400026)
				)
			)
		)
		(polygon
			(pts
				(arc
					(start 115.361466 -10.999978)
					(mid 114.800126 -10.438638)
					(end 114.238786 -10.999978)
				)
				(arc
					(start 114.238786 -12.40028)
					(mid 114.800253 -12.961366)
					(end 115.361466 -12.400026)
				)
			)
		)
		(polygon
			(pts
				(arc
					(start 111.761524 -10.999978)
					(mid 111.200184 -10.438638)
					(end 110.638844 -10.999978)
				)
				(arc
					(start 110.638844 -12.40028)
					(mid 111.200311 -12.961366)
					(end 111.761524 -12.400026)
				)
			)
		)
		(polygon
			(pts
				(arc
					(start 108.161328 -10.999978)
					(mid 107.599988 -10.438638)
					(end 107.038648 -10.999978)
				)
				(arc
					(start 107.038648 -12.40028)
					(mid 107.600115 -12.961366)
					(end 108.161328 -12.400026)
				)
			)
		)
		(polygon
			(pts
				(arc
					(start 104.561386 -10.999978)
					(mid 104.000046 -10.438638)
					(end 103.438706 -10.999978)
				)
				(arc
					(start 103.438706 -12.40028)
					(mid 104.000173 -12.961366)
					(end 104.561386 -12.400026)
				)
			)
		)
		(polygon
			(pts
				(arc
					(start 100.961444 -10.999978)
					(mid 100.400104 -10.438638)
					(end 99.838764 -10.999978)
				)
				(arc
					(start 99.838764 -12.40028)
					(mid 100.400231 -12.961366)
					(end 100.961444 -12.400026)
				)
			)
		)
		(polygon
			(pts
				(arc
					(start 97.361502 -10.999978)
					(mid 96.800162 -10.438638)
					(end 96.238822 -10.999978)
				)
				(arc
					(start 96.238822 -12.40028)
					(mid 96.800289 -12.961366)
					(end 97.361502 -12.400026)
				)
			)
		)
		(polygon
			(pts
				(arc
					(start 93.761306 -10.999978)
					(mid 93.199966 -10.438638)
					(end 92.638626 -10.999978)
				)
				(arc
					(start 92.638626 -12.40028)
					(mid 93.200093 -12.961366)
					(end 93.761306 -12.400026)
				)
			)
		)
		(polygon
			(pts
				(arc
					(start 90.161364 -10.999978)
					(mid 89.600024 -10.438638)
					(end 89.038684 -10.999978)
				)
				(arc
					(start 89.038684 -12.40028)
					(mid 89.600151 -12.961366)
					(end 90.161364 -12.400026)
				)
			)
		)
		(polygon
			(pts
				(arc
					(start 86.561422 -10.999978)
					(mid 86.000082 -10.438638)
					(end 85.438742 -10.999978)
				)
				(arc
					(start 85.438742 -12.40028)
					(mid 86.000209 -12.961366)
					(end 86.561422 -12.400026)
				)
			)
		)
		(polygon
			(pts
				(arc
					(start 193.161158 -9.800082)
					(mid 192.599818 -9.238742)
					(end 192.038478 -9.800082)
				)
				(arc
					(start 192.038478 -11.200384)
					(mid 192.599945 -11.76147)
					(end 193.161158 -11.20013)
				)
			)
		)
		(polygon
			(pts
				(arc
					(start 189.561216 -9.800082)
					(mid 188.999876 -9.238742)
					(end 188.438536 -9.800082)
				)
				(arc
					(start 188.438536 -11.200384)
					(mid 189.000003 -11.76147)
					(end 189.561216 -11.20013)
				)
			)
		)
		(polygon
			(pts
				(arc
					(start 185.961274 -9.800082)
					(mid 185.399934 -9.238742)
					(end 184.838594 -9.800082)
				)
				(arc
					(start 184.838594 -11.200384)
					(mid 185.400061 -11.76147)
					(end 185.961274 -11.20013)
				)
			)
		)
		(polygon
			(pts
				(arc
					(start 182.361332 -9.800082)
					(mid 181.799992 -9.238742)
					(end 181.238652 -9.800082)
				)
				(arc
					(start 181.238652 -11.200384)
					(mid 181.800119 -11.76147)
					(end 182.361332 -11.20013)
				)
			)
		)
		(polygon
			(pts
				(arc
					(start 149.561296 -9.800082)
					(mid 148.999956 -9.238742)
					(end 148.438616 -9.800082)
				)
				(arc
					(start 148.438616 -11.200384)
					(mid 149.000083 -11.76147)
					(end 149.561296 -11.20013)
				)
			)
		)
		(polygon
			(pts
				(arc
					(start 145.961354 -9.800082)
					(mid 145.400014 -9.238742)
					(end 144.838674 -9.800082)
				)
				(arc
					(start 144.838674 -11.200384)
					(mid 145.400141 -11.76147)
					(end 145.961354 -11.20013)
				)
			)
		)
		(polygon
			(pts
				(arc
					(start 142.361412 -9.800082)
					(mid 141.800072 -9.238742)
					(end 141.238732 -9.800082)
				)
				(arc
					(start 141.238732 -11.200384)
					(mid 141.800199 -11.76147)
					(end 142.361412 -11.20013)
				)
			)
		)
		(polygon
			(pts
				(arc
					(start 138.76147 -9.800082)
					(mid 138.20013 -9.238742)
					(end 137.63879 -9.800082)
				)
				(arc
					(start 137.63879 -11.200384)
					(mid 138.200257 -11.76147)
					(end 138.76147 -11.20013)
				)
			)
		)
		(polygon
			(pts
				(arc
					(start 135.161528 -9.800082)
					(mid 134.600188 -9.238742)
					(end 134.038848 -9.800082)
				)
				(arc
					(start 134.038848 -11.200384)
					(mid 134.600315 -11.76147)
					(end 135.161528 -11.20013)
				)
			)
		)
		(polygon
			(pts
				(arc
					(start 131.561332 -9.800082)
					(mid 130.999992 -9.238742)
					(end 130.438652 -9.800082)
				)
				(arc
					(start 130.438652 -11.200384)
					(mid 131.000119 -11.76147)
					(end 131.561332 -11.20013)
				)
			)
		)
		(polygon
			(pts
				(arc
					(start 127.96139 -9.800082)
					(mid 127.40005 -9.238742)
					(end 126.83871 -9.800082)
				)
				(arc
					(start 126.83871 -11.200384)
					(mid 127.400177 -11.76147)
					(end 127.96139 -11.20013)
				)
			)
		)
		(polygon
			(pts
				(arc
					(start 124.361448 -9.800082)
					(mid 123.800108 -9.238742)
					(end 123.238768 -9.800082)
				)
				(arc
					(start 123.238768 -11.200384)
					(mid 123.800235 -11.76147)
					(end 124.361448 -11.20013)
				)
			)
		)
		(polygon
			(pts
				(arc
					(start 120.761506 -9.800082)
					(mid 120.200166 -9.238742)
					(end 119.638826 -9.800082)
				)
				(arc
					(start 119.638826 -11.200384)
					(mid 120.200293 -11.76147)
					(end 120.761506 -11.20013)
				)
			)
		)
		(polygon
			(pts
				(arc
					(start 117.16131 -9.800082)
					(mid 116.59997 -9.238742)
					(end 116.03863 -9.800082)
				)
				(arc
					(start 116.03863 -11.200384)
					(mid 116.600097 -11.76147)
					(end 117.16131 -11.20013)
				)
			)
		)
		(polygon
			(pts
				(arc
					(start 113.561368 -9.800082)
					(mid 113.000028 -9.238742)
					(end 112.438688 -9.800082)
				)
				(arc
					(start 112.438688 -11.200384)
					(mid 113.000155 -11.76147)
					(end 113.561368 -11.20013)
				)
			)
		)
		(polygon
			(pts
				(arc
					(start 109.961426 -9.800082)
					(mid 109.400086 -9.238742)
					(end 108.838746 -9.800082)
				)
				(arc
					(start 108.838746 -11.200384)
					(mid 109.400213 -11.76147)
					(end 109.961426 -11.20013)
				)
			)
		)
		(polygon
			(pts
				(arc
					(start 106.361484 -9.800082)
					(mid 105.800144 -9.238742)
					(end 105.238804 -9.800082)
				)
				(arc
					(start 105.238804 -11.200384)
					(mid 105.800271 -11.76147)
					(end 106.361484 -11.20013)
				)
			)
		)
		(polygon
			(pts
				(arc
					(start 102.761542 -9.800082)
					(mid 102.200202 -9.238742)
					(end 101.638862 -9.800082)
				)
				(arc
					(start 101.638862 -11.200384)
					(mid 102.200329 -11.76147)
					(end 102.761542 -11.20013)
				)
			)
		)
		(polygon
			(pts
				(arc
					(start 99.161346 -9.800082)
					(mid 98.600006 -9.238742)
					(end 98.038666 -9.800082)
				)
				(arc
					(start 98.038666 -11.200384)
					(mid 98.600133 -11.76147)
					(end 99.161346 -11.20013)
				)
			)
		)
		(polygon
			(pts
				(arc
					(start 95.561404 -9.800082)
					(mid 95.000064 -9.238742)
					(end 94.438724 -9.800082)
				)
				(arc
					(start 94.438724 -11.200384)
					(mid 95.000191 -11.76147)
					(end 95.561404 -11.20013)
				)
			)
		)
		(polygon
			(pts
				(arc
					(start 91.961462 -9.800082)
					(mid 91.400122 -9.238742)
					(end 90.838782 -9.800082)
				)
				(arc
					(start 90.838782 -11.200384)
					(mid 91.400249 -11.76147)
					(end 91.961462 -11.20013)
				)
			)
		)
		(polygon
			(pts
				(arc
					(start 88.36152 -9.800082)
					(mid 87.80018 -9.238742)
					(end 87.23884 -9.800082)
				)
				(arc
					(start 87.23884 -11.200384)
					(mid 87.800307 -11.76147)
					(end 88.36152 -11.20013)
				)
			)
		)
		(polygon
			(pts
				(arc
					(start 180.561234 -7.400036)
					(mid 179.999894 -6.838696)
					(end 179.438554 -7.400036)
				)
				(arc
					(start 179.438554 -8.800338)
					(mid 180.000021 -9.361424)
					(end 180.561234 -8.800084)
				)
			)
		)
		(polygon
			(pts
				(arc
					(start 191.361314 -3.800094)
					(mid 190.799974 -3.238754)
					(end 190.238634 -3.800094)
				)
				(arc
					(start 190.238634 -5.200396)
					(mid 190.800101 -5.761482)
					(end 191.361314 -5.200142)
				)
			)
		)
		(polygon
			(pts
				(arc
					(start 187.761118 -3.800094)
					(mid 187.199778 -3.238754)
					(end 186.638438 -3.800094)
				)
				(arc
					(start 186.638438 -5.200396)
					(mid 187.199905 -5.761482)
					(end 187.761118 -5.200142)
				)
			)
		)
		(polygon
			(pts
				(arc
					(start 184.161176 -3.800094)
					(mid 183.599836 -3.238754)
					(end 183.038496 -3.800094)
				)
				(arc
					(start 183.038496 -5.200396)
					(mid 183.599963 -5.761482)
					(end 184.161176 -5.200142)
				)
			)
		)
		(polygon
			(pts
				(arc
					(start 180.561234 -3.800094)
					(mid 179.999894 -3.238754)
					(end 179.438554 -3.800094)
				)
				(arc
					(start 179.438554 -5.200396)
					(mid 180.000021 -5.761482)
					(end 180.561234 -5.200142)
				)
			)
		)
		(polygon
			(pts
				(arc
					(start 147.761452 -3.800094)
					(mid 147.200112 -3.238754)
					(end 146.638772 -3.800094)
				)
				(arc
					(start 146.638772 -5.200396)
					(mid 147.200239 -5.761482)
					(end 147.761452 -5.200142)
				)
			)
		)
		(polygon
			(pts
				(arc
					(start 144.16151 -3.800094)
					(mid 143.60017 -3.238754)
					(end 143.03883 -3.800094)
				)
				(arc
					(start 143.03883 -5.200396)
					(mid 143.600297 -5.761482)
					(end 144.16151 -5.200142)
				)
			)
		)
		(polygon
			(pts
				(arc
					(start 140.561314 -3.800094)
					(mid 139.999974 -3.238754)
					(end 139.438634 -3.800094)
				)
				(arc
					(start 139.438634 -5.200396)
					(mid 140.000101 -5.761482)
					(end 140.561314 -5.200142)
				)
			)
		)
		(polygon
			(pts
				(arc
					(start 136.961372 -3.800094)
					(mid 136.400032 -3.238754)
					(end 135.838692 -3.800094)
				)
				(arc
					(start 135.838692 -5.200396)
					(mid 136.400159 -5.761482)
					(end 136.961372 -5.200142)
				)
			)
		)
		(polygon
			(pts
				(arc
					(start 133.36143 -3.800094)
					(mid 132.80009 -3.238754)
					(end 132.23875 -3.800094)
				)
				(arc
					(start 132.23875 -5.200396)
					(mid 132.800217 -5.761482)
					(end 133.36143 -5.200142)
				)
			)
		)
		(polygon
			(pts
				(arc
					(start 129.761488 -3.800094)
					(mid 129.200148 -3.238754)
					(end 128.638808 -3.800094)
				)
				(arc
					(start 128.638808 -5.200396)
					(mid 129.200275 -5.761482)
					(end 129.761488 -5.200142)
				)
			)
		)
		(polygon
			(pts
				(arc
					(start 126.161546 -3.800094)
					(mid 125.600206 -3.238754)
					(end 125.038866 -3.800094)
				)
				(arc
					(start 125.038866 -5.200396)
					(mid 125.600333 -5.761482)
					(end 126.161546 -5.200142)
				)
			)
		)
		(polygon
			(pts
				(arc
					(start 122.56135 -3.800094)
					(mid 122.00001 -3.238754)
					(end 121.43867 -3.800094)
				)
				(arc
					(start 121.43867 -5.200396)
					(mid 122.000137 -5.761482)
					(end 122.56135 -5.200142)
				)
			)
		)
		(polygon
			(pts
				(arc
					(start 118.961408 -3.800094)
					(mid 118.400068 -3.238754)
					(end 117.838728 -3.800094)
				)
				(arc
					(start 117.838728 -5.200396)
					(mid 118.400195 -5.761482)
					(end 118.961408 -5.200142)
				)
			)
		)
		(polygon
			(pts
				(arc
					(start 115.361466 -3.800094)
					(mid 114.800126 -3.238754)
					(end 114.238786 -3.800094)
				)
				(arc
					(start 114.238786 -5.200396)
					(mid 114.800253 -5.761482)
					(end 115.361466 -5.200142)
				)
			)
		)
		(polygon
			(pts
				(arc
					(start 111.761524 -3.800094)
					(mid 111.200184 -3.238754)
					(end 110.638844 -3.800094)
				)
				(arc
					(start 110.638844 -5.200396)
					(mid 111.200311 -5.761482)
					(end 111.761524 -5.200142)
				)
			)
		)
		(polygon
			(pts
				(arc
					(start 108.161328 -3.800094)
					(mid 107.599988 -3.238754)
					(end 107.038648 -3.800094)
				)
				(arc
					(start 107.038648 -5.200396)
					(mid 107.600115 -5.761482)
					(end 108.161328 -5.200142)
				)
			)
		)
		(polygon
			(pts
				(arc
					(start 104.561386 -3.800094)
					(mid 104.000046 -3.238754)
					(end 103.438706 -3.800094)
				)
				(arc
					(start 103.438706 -5.200396)
					(mid 104.000173 -5.761482)
					(end 104.561386 -5.200142)
				)
			)
		)
		(polygon
			(pts
				(arc
					(start 100.961444 -3.800094)
					(mid 100.400104 -3.238754)
					(end 99.838764 -3.800094)
				)
				(arc
					(start 99.838764 -5.200396)
					(mid 100.400231 -5.761482)
					(end 100.961444 -5.200142)
				)
			)
		)
		(polygon
			(pts
				(arc
					(start 97.361502 -3.800094)
					(mid 96.800162 -3.238754)
					(end 96.238822 -3.800094)
				)
				(arc
					(start 96.238822 -5.200396)
					(mid 96.800289 -5.761482)
					(end 97.361502 -5.200142)
				)
			)
		)
		(polygon
			(pts
				(arc
					(start 93.761306 -3.800094)
					(mid 93.199966 -3.238754)
					(end 92.638626 -3.800094)
				)
				(arc
					(start 92.638626 -5.200396)
					(mid 93.200093 -5.761482)
					(end 93.761306 -5.200142)
				)
			)
		)
		(polygon
			(pts
				(arc
					(start 90.161364 -3.800094)
					(mid 89.600024 -3.238754)
					(end 89.038684 -3.800094)
				)
				(arc
					(start 89.038684 -5.200396)
					(mid 89.600151 -5.761482)
					(end 90.161364 -5.200142)
				)
			)
		)
		(polygon
			(pts
				(arc
					(start 86.561422 -3.800094)
					(mid 86.000082 -3.238754)
					(end 85.438742 -3.800094)
				)
				(arc
					(start 85.438742 -5.200396)
					(mid 86.000209 -5.761482)
					(end 86.561422 -5.200142)
				)
			)
		)
		(polygon
			(pts
				(arc
					(start 193.161158 -2.600198)
					(mid 192.599818 -2.038858)
					(end 192.038478 -2.600198)
				)
				(arc
					(start 192.038478 -4.000246)
					(mid 192.599945 -4.561332)
					(end 193.161158 -3.999992)
				)
			)
		)
		(polygon
			(pts
				(arc
					(start 189.561216 -2.600198)
					(mid 188.999876 -2.038858)
					(end 188.438536 -2.600198)
				)
				(arc
					(start 188.438536 -4.000246)
					(mid 189.000003 -4.561332)
					(end 189.561216 -3.999992)
				)
			)
		)
		(polygon
			(pts
				(arc
					(start 185.961274 -2.600198)
					(mid 185.399934 -2.038858)
					(end 184.838594 -2.600198)
				)
				(arc
					(start 184.838594 -4.000246)
					(mid 185.400061 -4.561332)
					(end 185.961274 -3.999992)
				)
			)
		)
		(polygon
			(pts
				(arc
					(start 182.361332 -2.600198)
					(mid 181.799992 -2.038858)
					(end 181.238652 -2.600198)
				)
				(arc
					(start 181.238652 -4.000246)
					(mid 181.800119 -4.561332)
					(end 182.361332 -3.999992)
				)
			)
		)
		(polygon
			(pts
				(arc
					(start 149.561296 -2.600198)
					(mid 148.999956 -2.038858)
					(end 148.438616 -2.600198)
				)
				(arc
					(start 148.438616 -4.000246)
					(mid 149.000083 -4.561332)
					(end 149.561296 -3.999992)
				)
			)
		)
		(polygon
			(pts
				(arc
					(start 145.961354 -2.600198)
					(mid 145.400014 -2.038858)
					(end 144.838674 -2.600198)
				)
				(arc
					(start 144.838674 -4.000246)
					(mid 145.400141 -4.561332)
					(end 145.961354 -3.999992)
				)
			)
		)
		(polygon
			(pts
				(arc
					(start 142.361412 -2.600198)
					(mid 141.800072 -2.038858)
					(end 141.238732 -2.600198)
				)
				(arc
					(start 141.238732 -4.000246)
					(mid 141.800199 -4.561332)
					(end 142.361412 -3.999992)
				)
			)
		)
		(polygon
			(pts
				(arc
					(start 138.76147 -2.600198)
					(mid 138.20013 -2.038858)
					(end 137.63879 -2.600198)
				)
				(arc
					(start 137.63879 -4.000246)
					(mid 138.200257 -4.561332)
					(end 138.76147 -3.999992)
				)
			)
		)
		(polygon
			(pts
				(arc
					(start 135.161528 -2.600198)
					(mid 134.600188 -2.038858)
					(end 134.038848 -2.600198)
				)
				(arc
					(start 134.038848 -4.000246)
					(mid 134.600315 -4.561332)
					(end 135.161528 -3.999992)
				)
			)
		)
		(polygon
			(pts
				(arc
					(start 131.561332 -2.600198)
					(mid 130.999992 -2.038858)
					(end 130.438652 -2.600198)
				)
				(arc
					(start 130.438652 -4.000246)
					(mid 131.000119 -4.561332)
					(end 131.561332 -3.999992)
				)
			)
		)
		(polygon
			(pts
				(arc
					(start 127.96139 -2.600198)
					(mid 127.40005 -2.038858)
					(end 126.83871 -2.600198)
				)
				(arc
					(start 126.83871 -4.000246)
					(mid 127.400177 -4.561332)
					(end 127.96139 -3.999992)
				)
			)
		)
		(polygon
			(pts
				(arc
					(start 124.361448 -2.600198)
					(mid 123.800108 -2.038858)
					(end 123.238768 -2.600198)
				)
				(arc
					(start 123.238768 -4.000246)
					(mid 123.800235 -4.561332)
					(end 124.361448 -3.999992)
				)
			)
		)
		(polygon
			(pts
				(arc
					(start 120.761506 -2.600198)
					(mid 120.200166 -2.038858)
					(end 119.638826 -2.600198)
				)
				(arc
					(start 119.638826 -4.000246)
					(mid 120.200293 -4.561332)
					(end 120.761506 -3.999992)
				)
			)
		)
		(polygon
			(pts
				(arc
					(start 117.16131 -2.600198)
					(mid 116.59997 -2.038858)
					(end 116.03863 -2.600198)
				)
				(arc
					(start 116.03863 -4.000246)
					(mid 116.600097 -4.561332)
					(end 117.16131 -3.999992)
				)
			)
		)
		(polygon
			(pts
				(arc
					(start 113.561368 -2.600198)
					(mid 113.000028 -2.038858)
					(end 112.438688 -2.600198)
				)
				(arc
					(start 112.438688 -4.000246)
					(mid 113.000155 -4.561332)
					(end 113.561368 -3.999992)
				)
			)
		)
		(polygon
			(pts
				(arc
					(start 109.961426 -2.600198)
					(mid 109.400086 -2.038858)
					(end 108.838746 -2.600198)
				)
				(arc
					(start 108.838746 -4.000246)
					(mid 109.400213 -4.561332)
					(end 109.961426 -3.999992)
				)
			)
		)
		(polygon
			(pts
				(arc
					(start 106.361484 -2.600198)
					(mid 105.800144 -2.038858)
					(end 105.238804 -2.600198)
				)
				(arc
					(start 105.238804 -4.000246)
					(mid 105.800271 -4.561332)
					(end 106.361484 -3.999992)
				)
			)
		)
		(polygon
			(pts
				(arc
					(start 102.761542 -2.600198)
					(mid 102.200202 -2.038858)
					(end 101.638862 -2.600198)
				)
				(arc
					(start 101.638862 -4.000246)
					(mid 102.200329 -4.561332)
					(end 102.761542 -3.999992)
				)
			)
		)
		(polygon
			(pts
				(arc
					(start 99.161346 -2.600198)
					(mid 98.600006 -2.038858)
					(end 98.038666 -2.600198)
				)
				(arc
					(start 98.038666 -4.000246)
					(mid 98.600133 -4.561332)
					(end 99.161346 -3.999992)
				)
			)
		)
		(polygon
			(pts
				(arc
					(start 95.561404 -2.600198)
					(mid 95.000064 -2.038858)
					(end 94.438724 -2.600198)
				)
				(arc
					(start 94.438724 -4.000246)
					(mid 95.000191 -4.561332)
					(end 95.561404 -3.999992)
				)
			)
		)
		(polygon
			(pts
				(arc
					(start 91.961462 -2.600198)
					(mid 91.400122 -2.038858)
					(end 90.838782 -2.600198)
				)
				(arc
					(start 90.838782 -4.000246)
					(mid 91.400249 -4.561332)
					(end 91.961462 -3.999992)
				)
			)
		)
		(polygon
			(pts
				(arc
					(start 88.36152 -2.600198)
					(mid 87.80018 -2.038858)
					(end 87.23884 -2.600198)
				)
				(arc
					(start 87.23884 -4.000246)
					(mid 87.800307 -4.561332)
					(end 88.36152 -3.999992)
				)
			)
		)
	)
	(zone
		(net "GB_VDDA")
		(layer "In4.Cu")
		(hatch none 0.5)
		(connect_pads
			(clearance 0.5)
		)
		(min_thickness 0.25)
		(fill yes
			(thermal_gap 0.5)
			(thermal_bridge_width 0.5)
			(island_removal_mode 0)
		)
		(polygon
			(pts
				(xy 88.674194 -30.4165) (xy 85.219794 -33.8709) (xy 72.900794 -33.8709) (xy 72.5551 -34.216594)
				(xy 72.5551 -60.474606) (xy 73.934828 -61.854334) (xy 97.5233 -61.854334) (xy 97.5233 -58.37682)
				(xy 99.52482 -56.3753) (xy 105.138474 -56.3753) (xy 109.075474 -60.3123) (xy 122.176794 -60.3123)
				(xy 122.631454 -60.767214)
				(arc
					(start 122.631962 -60.767722)
					(mid 122.678293 -60.837349)
					(end 122.6947 -60.91936)
				)
				(xy 122.6947 -70.898766) (xy 124.681742 -72.885808) (xy 124.681742 -76.999592) (xy 124.96165 -77.2795)
				(arc
					(start 125.775974 -77.2795)
					(mid 125.66209 -76.881491)
					(end 125.999748 -76.64196)
				)
				(arc
					(start 127 -76.64196)
					(mid 127.337885 -76.881366)
					(end 127.224028 -77.2795)
				)
				(xy 140.891006 -77.2795) (xy 141.9479 -76.222606) (xy 141.9479 -47.317406) (xy 142.9131 -46.352206)
				(xy 142.9131 -30.787594) (xy 142.542006 -30.4165)
			)
		)
		(polygon
			(pts
				(xy 139.622022 -76.14158) (xy 138.479276 -76.14158) (xy 138.479022 -76.141834)
				(arc
					(start 138.479022 -76.142342)
					(mid 138.096244 -76.52512)
					(end 138.479022 -76.907898)
				)
				(xy 138.479022 -76.90866) (xy 139.622022 -76.90866)
				(arc
					(start 139.622022 -76.907898)
					(mid 140.0048 -76.52512)
					(end 139.622022 -76.142342)
				)
			)
		)
		(polygon
			(pts
				(arc
					(start 127 -76.358242)
					(mid 127.35814 -76.000102)
					(end 127 -75.641962)
				)
				(arc
					(start 125.999748 -75.641962)
					(mid 125.641862 -76.000229)
					(end 126.000002 -76.358242)
				)
			)
		)
		(polygon
			(pts
				(arc
					(start 127 -75.358244)
					(mid 127.35814 -75.000104)
					(end 127 -74.641964)
				)
				(arc
					(start 125.999748 -74.641964)
					(mid 125.641862 -75.000231)
					(end 126.000002 -75.358244)
				)
			)
		)
		(polygon
			(pts
				(arc
					(start 127 -74.358246)
					(mid 127.35814 -74.000106)
					(end 127 -73.641966)
				)
				(arc
					(start 125.999748 -73.641966)
					(mid 125.641862 -74.000233)
					(end 126.000002 -74.358246)
				)
			)
		)
		(polygon
			(pts
				(arc
					(start 130.999992 -73.358248)
					(mid 131.358132 -73.000108)
					(end 130.999992 -72.641968)
				)
				(arc
					(start 129.99974 -72.641968)
					(mid 129.641854 -73.000235)
					(end 129.999994 -73.358248)
				)
			)
		)
		(polygon
			(pts
				(arc
					(start 127 -73.358248)
					(mid 127.35814 -73.000108)
					(end 127 -72.641968)
				)
				(arc
					(start 125.999748 -72.641968)
					(mid 125.641862 -73.000235)
					(end 126.000002 -73.358248)
				)
			)
		)
		(polygon
			(pts
				(arc
					(start 129.999994 -72.35825)
					(mid 130.358134 -72.00011)
					(end 129.999994 -71.64197)
				)
				(arc
					(start 128.999742 -71.64197)
					(mid 128.641856 -72.000237)
					(end 128.999996 -72.35825)
				)
			)
		)
		(polygon
			(pts
				(arc
					(start 127 -72.35825)
					(mid 127.35814 -72.00011)
					(end 127 -71.64197)
				)
				(arc
					(start 125.999748 -71.64197)
					(mid 125.641862 -72.000237)
					(end 126.000002 -72.35825)
				)
			)
		)
		(polygon
			(pts
				(arc
					(start 130.999992 -71.358252)
					(mid 131.358132 -71.000112)
					(end 130.999992 -70.641972)
				)
				(arc
					(start 129.99974 -70.641972)
					(mid 129.641854 -71.000239)
					(end 129.999994 -71.358252)
				)
			)
		)
		(polygon
			(pts
				(arc
					(start 127 -71.358252)
					(mid 127.35814 -71.000112)
					(end 127 -70.641972)
				)
				(arc
					(start 125.999748 -70.641972)
					(mid 125.641862 -71.000239)
					(end 126.000002 -71.358252)
				)
			)
		)
		(polygon
			(pts
				(arc
					(start 129.999994 -70.358254)
					(mid 130.358134 -70.000114)
					(end 129.999994 -69.641974)
				)
				(arc
					(start 128.999742 -69.641974)
					(mid 128.641856 -70.000241)
					(end 128.999996 -70.358254)
				)
			)
		)
		(polygon
			(pts
				(arc
					(start 127 -70.358254)
					(mid 127.35814 -70.000114)
					(end 127 -69.641974)
				)
				(arc
					(start 125.999748 -69.641974)
					(mid 125.641862 -70.000241)
					(end 126.000002 -70.358254)
				)
			)
		)
		(polygon
			(pts
				(arc
					(start 130.999992 -69.358256)
					(mid 131.358132 -69.000116)
					(end 130.999992 -68.641976)
				)
				(arc
					(start 129.99974 -68.641976)
					(mid 129.641854 -69.000243)
					(end 129.999994 -69.358256)
				)
			)
		)
		(polygon
			(pts
				(arc
					(start 127 -69.358256)
					(mid 127.35814 -69.000116)
					(end 127 -68.641976)
				)
				(arc
					(start 125.999748 -68.641976)
					(mid 125.641862 -69.000243)
					(end 126.000002 -69.358256)
				)
			)
		)
		(polygon
			(pts
				(arc
					(start 129.999994 -68.358258)
					(mid 130.358134 -68.000118)
					(end 129.999994 -67.641978)
				)
				(arc
					(start 128.999742 -67.641978)
					(mid 128.641856 -68.000245)
					(end 128.999996 -68.358258)
				)
			)
		)
		(polygon
			(pts
				(arc
					(start 127 -68.358258)
					(mid 127.35814 -68.000118)
					(end 127 -67.641978)
				)
				(arc
					(start 125.999748 -67.641978)
					(mid 125.641862 -68.000245)
					(end 126.000002 -68.358258)
				)
			)
		)
		(polygon
			(pts
				(arc
					(start 130.999992 -66.358262)
					(mid 131.358132 -66.000122)
					(end 130.999992 -65.641982)
				)
				(arc
					(start 129.99974 -65.641982)
					(mid 129.641854 -66.000249)
					(end 129.999994 -66.358262)
				)
			)
		)
		(polygon
			(pts
				(arc
					(start 127 -66.358262)
					(mid 127.35814 -66.000122)
					(end 127 -65.641982)
				)
				(arc
					(start 125.999748 -65.641982)
					(mid 125.641862 -66.000249)
					(end 126.000002 -66.358262)
				)
			)
		)
		(polygon
			(pts
				(arc
					(start 129.999994 -65.358264)
					(mid 130.358134 -65.000124)
					(end 129.999994 -64.641984)
				)
				(arc
					(start 128.999742 -64.641984)
					(mid 128.641856 -65.000251)
					(end 128.999996 -65.358264)
				)
			)
		)
		(polygon
			(pts
				(arc
					(start 127 -65.358264)
					(mid 127.35814 -65.000124)
					(end 127 -64.641984)
				)
				(arc
					(start 125.999748 -64.641984)
					(mid 125.641862 -65.000251)
					(end 126.000002 -65.358264)
				)
			)
		)
		(polygon
			(pts
				(arc
					(start 139.882372 -65.426844)
					(mid 140.336778 -64.972057)
					(end 139.882118 -64.517524)
				)
				(arc
					(start 138.739118 -64.517524)
					(mid 138.284458 -64.972184)
					(end 138.739118 -65.426844)
				)
			)
		)
		(polygon
			(pts
				(arc
					(start 130.999992 -64.358266)
					(mid 131.358132 -64.000126)
					(end 130.999992 -63.641986)
				)
				(arc
					(start 129.99974 -63.641986)
					(mid 129.641854 -64.000253)
					(end 129.999994 -64.358266)
				)
			)
		)
		(polygon
			(pts
				(arc
					(start 127 -64.358266)
					(mid 127.35814 -64.000126)
					(end 127 -63.641986)
				)
				(arc
					(start 125.999748 -63.641986)
					(mid 125.641862 -64.000253)
					(end 126.000002 -64.358266)
				)
			)
		)
		(polygon
			(pts
				(arc
					(start 129.999994 -63.358268)
					(mid 130.358134 -63.000128)
					(end 129.999994 -62.641988)
				)
				(arc
					(start 128.999742 -62.641988)
					(mid 128.641856 -63.000255)
					(end 128.999996 -63.358268)
				)
			)
		)
		(polygon
			(pts
				(arc
					(start 127 -63.358268)
					(mid 127.35814 -63.000128)
					(end 127 -62.641988)
				)
				(arc
					(start 125.999748 -62.641988)
					(mid 125.641862 -63.000255)
					(end 126.000002 -63.358268)
				)
			)
		)
		(polygon
			(pts
				(arc
					(start 139.947904 -63.499746)
					(mid 140.40231 -63.044959)
					(end 139.94765 -62.590426)
				)
				(arc
					(start 138.80465 -62.590426)
					(mid 138.34999 -63.045086)
					(end 138.80465 -63.499746)
				)
			)
		)
		(polygon
			(pts
				(arc
					(start 130.999992 -62.35827)
					(mid 131.358132 -62.00013)
					(end 130.999992 -61.64199)
				)
				(arc
					(start 129.99974 -61.64199)
					(mid 129.641854 -62.000257)
					(end 129.999994 -62.35827)
				)
			)
		)
		(polygon
			(pts
				(arc
					(start 127 -62.35827)
					(mid 127.35814 -62.00013)
					(end 127 -61.64199)
				)
				(arc
					(start 125.999748 -61.64199)
					(mid 125.641862 -62.000257)
					(end 126.000002 -62.35827)
				)
			)
		)
		(polygon
			(pts
				(arc
					(start 140.173964 -61.576712)
					(mid 140.62837 -61.121925)
					(end 140.17371 -60.667392)
				)
				(arc
					(start 139.03071 -60.667392)
					(mid 138.57605 -61.122052)
					(end 139.03071 -61.576712)
				)
			)
		)
		(polygon
			(pts
				(arc
					(start 129.999994 -61.358272)
					(mid 130.358134 -61.000132)
					(end 129.999994 -60.641992)
				)
				(arc
					(start 128.999742 -60.641992)
					(mid 128.641856 -61.000259)
					(end 128.999996 -61.358272)
				)
			)
		)
		(polygon
			(pts
				(arc
					(start 127 -61.358272)
					(mid 127.35814 -61.000132)
					(end 127 -60.641992)
				)
				(arc
					(start 125.999748 -60.641992)
					(mid 125.641862 -61.000259)
					(end 126.000002 -61.358272)
				)
			)
		)
		(polygon
			(pts
				(arc
					(start 127 -60.358274)
					(mid 127.35814 -60.000134)
					(end 127 -59.641994)
				)
				(arc
					(start 125.999748 -59.641994)
					(mid 125.641862 -60.000261)
					(end 126.000002 -60.358274)
				)
			)
		)
		(polygon
			(pts
				(arc
					(start 127 -59.358276)
					(mid 127.35814 -59.000136)
					(end 127 -58.641996)
				)
				(arc
					(start 125.999748 -58.641996)
					(mid 125.641862 -59.000263)
					(end 126.000002 -59.358276)
				)
			)
		)
		(polygon
			(pts
				(arc
					(start 140.589254 -59.35726)
					(mid 141.04366 -58.902473)
					(end 140.589 -58.44794)
				)
				(arc
					(start 139.446 -58.44794)
					(mid 138.99134 -58.9026)
					(end 139.446 -59.35726)
				)
			)
		)
		(polygon
			(pts
				(arc
					(start 127 -58.358278)
					(mid 127.35814 -58.000138)
					(end 127 -57.641998)
				)
				(arc
					(start 125.999748 -57.641998)
					(mid 125.641862 -58.000265)
					(end 126.000002 -58.358278)
				)
			)
		)
		(polygon
			(pts
				(arc
					(start 127 -57.35828)
					(mid 127.35814 -57.00014)
					(end 127 -56.642)
				)
				(arc
					(start 125.999748 -56.642)
					(mid 125.641862 -57.000267)
					(end 126.000002 -57.35828)
				)
			)
		)
		(polygon
			(pts
				(arc
					(start 127 -56.358282)
					(mid 127.35814 -56.000142)
					(end 127 -55.642002)
				)
				(arc
					(start 125.999748 -55.642002)
					(mid 125.641862 -56.000269)
					(end 126.000002 -56.358282)
				)
			)
		)
		(polygon
			(pts
				(arc
					(start 127 -55.358284)
					(mid 127.35814 -55.000144)
					(end 127 -54.642004)
				)
				(arc
					(start 125.999748 -54.642004)
					(mid 125.641862 -55.000271)
					(end 126.000002 -55.358284)
				)
			)
		)
		(polygon
			(pts
				(arc
					(start 124.358146 -55.000144)
					(mid 124.000006 -54.642004)
					(end 123.641866 -55.000144)
				)
				(arc
					(start 123.641866 -56.000396)
					(mid 124.000133 -56.358282)
					(end 124.358146 -56.000142)
				)
			)
		)
		(polygon
			(pts
				(arc
					(start 123.358148 -55.000144)
					(mid 123.000008 -54.642004)
					(end 122.641868 -55.000144)
				)
				(arc
					(start 122.641868 -56.000396)
					(mid 123.000135 -56.358282)
					(end 123.358148 -56.000142)
				)
			)
		)
		(polygon
			(pts
				(arc
					(start 122.35815 -55.000144)
					(mid 122.00001 -54.642004)
					(end 121.64187 -55.000144)
				)
				(arc
					(start 121.64187 -56.000396)
					(mid 122.000137 -56.358282)
					(end 122.35815 -56.000142)
				)
			)
		)
		(polygon
			(pts
				(arc
					(start 121.358152 -55.000144)
					(mid 121.000012 -54.642004)
					(end 120.641872 -55.000144)
				)
				(arc
					(start 120.641872 -56.000396)
					(mid 121.000139 -56.358282)
					(end 121.358152 -56.000142)
				)
			)
		)
		(polygon
			(pts
				(arc
					(start 120.358154 -55.000144)
					(mid 120.000014 -54.642004)
					(end 119.641874 -55.000144)
				)
				(arc
					(start 119.641874 -56.000396)
					(mid 120.000141 -56.358282)
					(end 120.358154 -56.000142)
				)
			)
		)
		(polygon
			(pts
				(arc
					(start 119.358156 -55.000144)
					(mid 119.000016 -54.642004)
					(end 118.641876 -55.000144)
				)
				(arc
					(start 118.641876 -56.000396)
					(mid 119.000143 -56.358282)
					(end 119.358156 -56.000142)
				)
			)
		)
		(polygon
			(pts
				(arc
					(start 118.358158 -55.000144)
					(mid 118.000018 -54.642004)
					(end 117.641878 -55.000144)
				)
				(arc
					(start 117.641878 -56.000396)
					(mid 118.000145 -56.358282)
					(end 118.358158 -56.000142)
				)
			)
		)
		(polygon
			(pts
				(arc
					(start 117.35816 -55.000144)
					(mid 117.00002 -54.642004)
					(end 116.64188 -55.000144)
				)
				(arc
					(start 116.64188 -56.000396)
					(mid 117.000147 -56.358282)
					(end 117.35816 -56.000142)
				)
			)
		)
		(polygon
			(pts
				(arc
					(start 116.358162 -55.000144)
					(mid 116.000022 -54.642004)
					(end 115.641882 -55.000144)
				)
				(arc
					(start 115.641882 -56.000396)
					(mid 116.000149 -56.358282)
					(end 116.358162 -56.000142)
				)
			)
		)
		(polygon
			(pts
				(arc
					(start 114.358166 -55.000144)
					(mid 114.000026 -54.642004)
					(end 113.641886 -55.000144)
				)
				(arc
					(start 113.641886 -56.000396)
					(mid 114.000153 -56.358282)
					(end 114.358166 -56.000142)
				)
			)
		)
		(polygon
			(pts
				(arc
					(start 113.358168 -55.000144)
					(mid 113.000028 -54.642004)
					(end 112.641888 -55.000144)
				)
				(arc
					(start 112.641888 -56.000396)
					(mid 113.000155 -56.358282)
					(end 113.358168 -56.000142)
				)
			)
		)
		(polygon
			(pts
				(arc
					(start 112.35817 -55.000144)
					(mid 112.00003 -54.642004)
					(end 111.64189 -55.000144)
				)
				(arc
					(start 111.64189 -56.000396)
					(mid 112.000157 -56.358282)
					(end 112.35817 -56.000142)
				)
			)
		)
		(polygon
			(pts
				(arc
					(start 111.358172 -55.000144)
					(mid 111.000032 -54.642004)
					(end 110.641892 -55.000144)
				)
				(arc
					(start 110.641892 -56.000396)
					(mid 111.000159 -56.358282)
					(end 111.358172 -56.000142)
				)
			)
		)
		(polygon
			(pts
				(arc
					(start 110.358174 -55.000144)
					(mid 110.000034 -54.642004)
					(end 109.641894 -55.000144)
				)
				(arc
					(start 109.641894 -56.000396)
					(mid 110.000161 -56.358282)
					(end 110.358174 -56.000142)
				)
			)
		)
		(polygon
			(pts
				(arc
					(start 109.358176 -55.000144)
					(mid 109.000036 -54.642004)
					(end 108.641896 -55.000144)
				)
				(arc
					(start 108.641896 -56.000396)
					(mid 109.000163 -56.358282)
					(end 109.358176 -56.000142)
				)
			)
		)
		(polygon
			(pts
				(arc
					(start 108.358178 -55.000144)
					(mid 108.000038 -54.642004)
					(end 107.641898 -55.000144)
				)
				(arc
					(start 107.641898 -56.000396)
					(mid 108.000165 -56.358282)
					(end 108.358178 -56.000142)
				)
			)
		)
		(polygon
			(pts
				(arc
					(start 107.35818 -55.000144)
					(mid 107.00004 -54.642004)
					(end 106.6419 -55.000144)
				)
				(arc
					(start 106.6419 -56.000396)
					(mid 107.000167 -56.358282)
					(end 107.35818 -56.000142)
				)
			)
		)
		(polygon
			(pts
				(arc
					(start 106.358182 -55.000144)
					(mid 106.000042 -54.642004)
					(end 105.641902 -55.000144)
				)
				(arc
					(start 105.641902 -56.000396)
					(mid 106.000169 -56.358282)
					(end 106.358182 -56.000142)
				)
			)
		)
		(polygon
			(pts
				(arc
					(start 105.358184 -55.000144)
					(mid 105.000044 -54.642004)
					(end 104.641904 -55.000144)
				)
				(arc
					(start 104.641904 -56.000396)
					(mid 105.000171 -56.358282)
					(end 105.358184 -56.000142)
				)
			)
		)
		(polygon
			(pts
				(arc
					(start 104.358186 -55.000144)
					(mid 104.000046 -54.642004)
					(end 103.641906 -55.000144)
				)
				(arc
					(start 103.641906 -56.000396)
					(mid 104.000173 -56.358282)
					(end 104.358186 -56.000142)
				)
			)
		)
		(polygon
			(pts
				(arc
					(start 103.358188 -55.000144)
					(mid 103.000048 -54.642004)
					(end 102.641908 -55.000144)
				)
				(arc
					(start 102.641908 -56.000396)
					(mid 103.000175 -56.358282)
					(end 103.358188 -56.000142)
				)
			)
		)
		(polygon
			(pts
				(arc
					(start 102.35819 -55.000144)
					(mid 102.00005 -54.642004)
					(end 101.64191 -55.000144)
				)
				(arc
					(start 101.64191 -56.000396)
					(mid 102.000177 -56.358282)
					(end 102.35819 -56.000142)
				)
			)
		)
		(polygon
			(pts
				(arc
					(start 101.358192 -55.000144)
					(mid 101.000052 -54.642004)
					(end 100.641912 -55.000144)
				)
				(arc
					(start 100.641912 -56.000396)
					(mid 101.000179 -56.358282)
					(end 101.358192 -56.000142)
				)
			)
		)
		(polygon
			(pts
				(arc
					(start 127 -54.358286)
					(mid 127.35814 -54.000146)
					(end 127 -53.642006)
				)
				(arc
					(start 125.999748 -53.642006)
					(mid 125.641862 -54.000273)
					(end 126.000002 -54.358286)
				)
			)
		)
		(polygon
			(pts
				(arc
					(start 99.358196 -54.000146)
					(mid 99.000056 -53.642006)
					(end 98.641916 -54.000146)
				)
				(arc
					(start 98.641916 -55.000398)
					(mid 99.000183 -55.358284)
					(end 99.358196 -55.000144)
				)
			)
		)
		(polygon
			(pts
				(arc
					(start 127.999998 -53.358288)
					(mid 128.358138 -53.000148)
					(end 127.999998 -52.642008)
				)
				(arc
					(start 126.999746 -52.642008)
					(mid 126.64186 -53.000275)
					(end 127 -53.358288)
				)
			)
		)
		(polygon
			(pts
				(arc
					(start 124.358146 -52.00015)
					(mid 124.000006 -51.64201)
					(end 123.641866 -52.00015)
				)
				(arc
					(start 123.641866 -53.000402)
					(mid 124.000133 -53.358288)
					(end 124.358146 -53.000148)
				)
			)
		)
		(polygon
			(pts
				(arc
					(start 122.35815 -52.00015)
					(mid 122.00001 -51.64201)
					(end 121.64187 -52.00015)
				)
				(arc
					(start 121.64187 -53.000402)
					(mid 122.000137 -53.358288)
					(end 122.35815 -53.000148)
				)
			)
		)
		(polygon
			(pts
				(arc
					(start 120.358154 -52.00015)
					(mid 120.000014 -51.64201)
					(end 119.641874 -52.00015)
				)
				(arc
					(start 119.641874 -53.000402)
					(mid 120.000141 -53.358288)
					(end 120.358154 -53.000148)
				)
			)
		)
		(polygon
			(pts
				(arc
					(start 118.358158 -52.00015)
					(mid 118.000018 -51.64201)
					(end 117.641878 -52.00015)
				)
				(arc
					(start 117.641878 -53.000402)
					(mid 118.000145 -53.358288)
					(end 118.358158 -53.000148)
				)
			)
		)
		(polygon
			(pts
				(arc
					(start 116.358162 -52.00015)
					(mid 116.000022 -51.64201)
					(end 115.641882 -52.00015)
				)
				(arc
					(start 115.641882 -53.000402)
					(mid 116.000149 -53.358288)
					(end 116.358162 -53.000148)
				)
			)
		)
		(polygon
			(pts
				(arc
					(start 113.358168 -52.00015)
					(mid 113.000028 -51.64201)
					(end 112.641888 -52.00015)
				)
				(arc
					(start 112.641888 -53.000402)
					(mid 113.000155 -53.358288)
					(end 113.358168 -53.000148)
				)
			)
		)
		(polygon
			(pts
				(arc
					(start 111.358172 -52.00015)
					(mid 111.000032 -51.64201)
					(end 110.641892 -52.00015)
				)
				(arc
					(start 110.641892 -53.000402)
					(mid 111.000159 -53.358288)
					(end 111.358172 -53.000148)
				)
			)
		)
		(polygon
			(pts
				(arc
					(start 109.358176 -52.00015)
					(mid 109.000036 -51.64201)
					(end 108.641896 -52.00015)
				)
				(arc
					(start 108.641896 -53.000402)
					(mid 109.000163 -53.358288)
					(end 109.358176 -53.000148)
				)
			)
		)
		(polygon
			(pts
				(arc
					(start 107.35818 -52.00015)
					(mid 107.00004 -51.64201)
					(end 106.6419 -52.00015)
				)
				(arc
					(start 106.6419 -53.000402)
					(mid 107.000167 -53.358288)
					(end 107.35818 -53.000148)
				)
			)
		)
		(polygon
			(pts
				(arc
					(start 105.358184 -52.00015)
					(mid 105.000044 -51.64201)
					(end 104.641904 -52.00015)
				)
				(arc
					(start 104.641904 -53.000402)
					(mid 105.000171 -53.358288)
					(end 105.358184 -53.000148)
				)
			)
		)
		(polygon
			(pts
				(arc
					(start 103.358188 -52.00015)
					(mid 103.000048 -51.64201)
					(end 102.641908 -52.00015)
				)
				(arc
					(start 102.641908 -53.000402)
					(mid 103.000175 -53.358288)
					(end 103.358188 -53.000148)
				)
			)
		)
		(polygon
			(pts
				(arc
					(start 101.358192 -52.00015)
					(mid 101.000052 -51.64201)
					(end 100.641912 -52.00015)
				)
				(arc
					(start 100.641912 -53.000402)
					(mid 101.000179 -53.358288)
					(end 101.358192 -53.000148)
				)
			)
		)
		(polygon
			(pts
				(arc
					(start 123.358148 -51.000152)
					(mid 123.000008 -50.642012)
					(end 122.641868 -51.000152)
				)
				(arc
					(start 122.641868 -52.000404)
					(mid 123.000135 -52.35829)
					(end 123.358148 -52.00015)
				)
			)
		)
		(polygon
			(pts
				(arc
					(start 121.358152 -51.000152)
					(mid 121.000012 -50.642012)
					(end 120.641872 -51.000152)
				)
				(arc
					(start 120.641872 -52.000404)
					(mid 121.000139 -52.35829)
					(end 121.358152 -52.00015)
				)
			)
		)
		(polygon
			(pts
				(arc
					(start 119.358156 -51.000152)
					(mid 119.000016 -50.642012)
					(end 118.641876 -51.000152)
				)
				(arc
					(start 118.641876 -52.000404)
					(mid 119.000143 -52.35829)
					(end 119.358156 -52.00015)
				)
			)
		)
		(polygon
			(pts
				(arc
					(start 117.35816 -51.000152)
					(mid 117.00002 -50.642012)
					(end 116.64188 -51.000152)
				)
				(arc
					(start 116.64188 -52.000404)
					(mid 117.000147 -52.35829)
					(end 117.35816 -52.00015)
				)
			)
		)
		(polygon
			(pts
				(arc
					(start 114.358166 -51.000152)
					(mid 114.000026 -50.642012)
					(end 113.641886 -51.000152)
				)
				(arc
					(start 113.641886 -52.000404)
					(mid 114.000153 -52.35829)
					(end 114.358166 -52.00015)
				)
			)
		)
		(polygon
			(pts
				(arc
					(start 112.35817 -51.000152)
					(mid 112.00003 -50.642012)
					(end 111.64189 -51.000152)
				)
				(arc
					(start 111.64189 -52.000404)
					(mid 112.000157 -52.35829)
					(end 112.35817 -52.00015)
				)
			)
		)
		(polygon
			(pts
				(arc
					(start 110.358174 -51.000152)
					(mid 110.000034 -50.642012)
					(end 109.641894 -51.000152)
				)
				(arc
					(start 109.641894 -52.000404)
					(mid 110.000161 -52.35829)
					(end 110.358174 -52.00015)
				)
			)
		)
		(polygon
			(pts
				(arc
					(start 108.358178 -51.000152)
					(mid 108.000038 -50.642012)
					(end 107.641898 -51.000152)
				)
				(arc
					(start 107.641898 -52.000404)
					(mid 108.000165 -52.35829)
					(end 108.358178 -52.00015)
				)
			)
		)
		(polygon
			(pts
				(arc
					(start 106.358182 -51.000152)
					(mid 106.000042 -50.642012)
					(end 105.641902 -51.000152)
				)
				(arc
					(start 105.641902 -52.000404)
					(mid 106.000169 -52.35829)
					(end 106.358182 -52.00015)
				)
			)
		)
		(polygon
			(pts
				(arc
					(start 104.358186 -51.000152)
					(mid 104.000046 -50.642012)
					(end 103.641906 -51.000152)
				)
				(arc
					(start 103.641906 -52.000404)
					(mid 104.000173 -52.35829)
					(end 104.358186 -52.00015)
				)
			)
		)
		(polygon
			(pts
				(arc
					(start 102.35819 -51.000152)
					(mid 102.00005 -50.642012)
					(end 101.64191 -51.000152)
				)
				(arc
					(start 101.64191 -52.000404)
					(mid 102.000177 -52.35829)
					(end 102.35819 -52.00015)
				)
			)
		)
		(polygon
			(pts
				(arc
					(start 100.358194 -51.000152)
					(mid 100.000054 -50.642012)
					(end 99.641914 -51.000152)
				)
				(arc
					(start 99.641914 -52.000404)
					(mid 100.000181 -52.35829)
					(end 100.358194 -52.00015)
				)
			)
		)
		(polygon
			(pts
				(arc
					(start 125.139958 -45.858938)
					(mid 124.682758 -45.401738)
					(end 124.225558 -45.858938)
				)
				(arc
					(start 124.225558 -47.002192)
					(mid 124.682885 -47.459138)
					(end 125.139958 -47.001938)
				)
			)
		)
		(polygon
			(pts
				(arc
					(start 127.533908 -45.844206)
					(mid 127.076708 -45.387006)
					(end 126.619508 -45.844206)
				)
				(arc
					(start 126.619508 -46.98746)
					(mid 127.076835 -47.444406)
					(end 127.533908 -46.987206)
				)
			)
		)
		(polygon
			(pts
				(arc
					(start 130.105658 -45.829474)
					(mid 129.648458 -45.372274)
					(end 129.191258 -45.829474)
				)
				(arc
					(start 129.191258 -46.972728)
					(mid 129.648585 -47.429674)
					(end 130.105658 -46.972474)
				)
			)
		)
		(polygon
			(pts
				(arc
					(start 132.677408 -45.814742)
					(mid 132.220208 -45.357542)
					(end 131.763008 -45.814742)
				)
				(arc
					(start 131.763008 -46.957996)
					(mid 132.220335 -47.414942)
					(end 132.677408 -46.957742)
				)
			)
		)
	)
	(zone
		(net "P1V8_E")
		(layer "In4.Cu")
		(hatch none 0.5)
		(connect_pads
			(clearance 0.5)
		)
		(min_thickness 0.25)
		(fill yes
			(thermal_gap 0.5)
			(thermal_bridge_width 0.5)
			(island_removal_mode 0)
		)
		(polygon
			(pts
				(xy 152.199848 -3.128264) (xy 151.099774 -4.228338) (xy 151.099774 -18.12417) (xy 143.2941 -25.929844)
				(xy 143.2941 -46.510194) (xy 142.3289 -47.475394) (xy 142.3289 -76.380594) (xy 141.048994 -77.6605)
				(xy 124.803662 -77.6605) (xy 124.300742 -77.15758) (xy 124.300742 -73.043796) (xy 122.3137 -71.056754)
				(xy 122.3137 -60.988194) (xy 122.018806 -60.6933) (xy 108.917486 -60.6933) (xy 104.980486 -56.7563)
				(xy 99.682808 -56.7563) (xy 97.9043 -58.534808) (xy 97.9043 -64.919606) (xy 98.300794 -65.3161)
				(xy 109.725206 -65.3161) (xy 110.842806 -64.1985) (xy 118.138194 -64.1985) (xy 118.8339 -64.894206)
				(xy 118.8339 -71.198994) (xy 118.40083 -71.632064) (xy 107.232196 -71.632064) (xy 106.6673 -72.19696)
				(xy 106.6673 -79.339186) (xy 106.407966 -79.59852) (xy 105.91165 -79.59852) (xy 105.66019 -79.84998)
				(xy 105.66019 -80.338168) (xy 105.340658 -80.6577) (xy 98.605594 -80.6577) (xy 98.351594 -80.9117)
				(xy 96.46666 -80.9117) (xy 95.306642 -79.751682) (xy 87.11565 -79.751682) (xy 85.955632 -80.9117)
				(xy 52.219606 -80.9117) (xy 50.609754 -79.301848) (xy 50.609754 -78.031848) (xy 50.238406 -77.6605)
				(xy 31.290006 -77.6605) (xy 29.6545 -76.024994) (xy 29.6545 -50.136806) (xy 34.8361 -44.955206)
				(xy 34.8361 -28.369006) (xy 40.053006 -23.1521) (xy 63.675006 -23.1521) (xy 66.9925 -19.834606)
				(xy 66.9925 -13.208) (xy 66.571114 -12.786614) (xy 61.57468 -12.786614) (xy 60.3123 -14.048994)
				(xy 60.3123 -16.690594) (xy 59.362594 -17.6403) (xy 38.559994 -17.6403) (xy 30.9753 -25.224994)
				(xy 30.9753 -40.642794) (xy 25.4381 -46.179994) (xy 25.4381 -76.202794) (xy 23.472394 -78.1685)
				(xy 9.375394 -78.1685) (xy 6.4389 -81.104994) (xy 6.4389 -87.474806) (xy 8.105394 -89.1413) (xy 68.506594 -89.1413)
				(xy 69.370194 -90.0049) (xy 114.582194 -90.0049) (xy 120.020588 -95.443294) (xy 128.162812 -95.443294)
				(xy 142.448788 -95.443294) (xy 148.999194 -101.9937) (xy 160.957006 -101.9937) (xy 163.5633 -99.387406)
				(xy 163.5633 -95.278194) (xy 155.623006 -87.3379) (xy 151.584406 -87.3379) (xy 150.7871 -86.540594)
				(xy 150.7871 -80.139794) (xy 147.9423 -77.294994) (xy 147.9423 -57.000394) (xy 146.1135 -55.171594)
				(xy 146.1135 -35.506406) (xy 147.1803 -34.439606) (xy 147.1803 -27.929586) (xy 154.630374 -20.479512)
				(xy 154.630374 -7.094728) (xy 155.394406 -6.330696) (xy 167.090852 -6.330696) (xy 168.372536 -5.049012)
				(xy 168.372536 -3.616198) (xy 167.884602 -3.128264)
			)
		)
		(polygon
			(pts
				(xy 139.986258 -81.924906) (xy 138.843512 -81.924906) (xy 138.843258 -81.92516)
				(arc
					(start 138.843258 -81.925668)
					(mid 138.46048 -82.308446)
					(end 138.843258 -82.691224)
				)
				(xy 138.843258 -82.691986) (xy 139.986258 -82.691986)
				(arc
					(start 139.986258 -82.691224)
					(mid 140.369036 -82.308446)
					(end 139.986258 -81.925668)
				)
			)
		)
		(polygon
			(pts
				(xy 139.643612 -79.813912) (xy 138.500866 -79.813912) (xy 138.500612 -79.814166)
				(arc
					(start 138.500612 -79.814674)
					(mid 138.117834 -80.197452)
					(end 138.500612 -80.58023)
				)
				(xy 138.500612 -80.580992) (xy 139.643612 -80.580992)
				(arc
					(start 139.643612 -80.58023)
					(mid 140.02639 -80.197452)
					(end 139.643612 -79.814674)
				)
			)
		)
		(polygon
			(pts
				(xy 139.629134 -78.044294) (xy 138.486134 -78.044294)
				(arc
					(start 138.486134 -78.045056)
					(mid 138.103356 -78.427834)
					(end 138.486134 -78.810612)
				)
				(xy 138.486134 -78.811374) (xy 139.62888 -78.811374) (xy 139.629134 -78.81112)
				(arc
					(start 139.629134 -78.810612)
					(mid 140.011912 -78.427834)
					(end 139.629134 -78.045056)
				)
			)
		)
		(polygon
			(pts
				(arc
					(start 146.969226 -32.460184)
					(mid 146.624662 -31.908815)
					(end 146.077178 -32.259778)
				)
				(arc
					(start 145.839434 -33.377886)
					(mid 146.191732 -33.920176)
					(end 146.734022 -33.567878)
				)
			)
		)
	)
	(zone
		(net "P0V975")
		(layer "In4.Cu")
		(hatch none 0.5)
		(connect_pads
			(clearance 0.5)
		)
		(min_thickness 0.25)
		(fill yes
			(thermal_gap 0.5)
			(thermal_bridge_width 0.5)
			(island_removal_mode 0)
		)
		(polygon
			(pts
				(xy 167.744394 -35.0393) (xy 167.5765 -35.207194) (xy 167.5765 -40.515794) (xy 167.109394 -40.9829)
				(xy 165.534594 -40.9829) (xy 165.1889 -41.328594) (xy 165.1889 -64.106806) (xy 175.7553 -74.673206)
				(xy 175.7553 -95.120206) (xy 176.075594 -95.4405) (xy 182.908194 -95.4405) (xy 184.813194 -97.3455)
				(xy 189.811406 -97.3455) (xy 192.2653 -94.891606) (xy 192.2653 -74.520806) (xy 193.0019 -73.784206)
				(xy 193.0019 -70.335394) (xy 186.4741 -63.807594) (xy 186.4741 -35.613594) (xy 185.899806 -35.0393)
			)
		)
	)
	(zone
		(layer "In5.Cu")
		(hatch none 0.5)
		(connect_pads
			(clearance 0)
		)
		(min_thickness 0.25)
		(keepout
			(tracks not_allowed)
			(vias allowed)
			(pads allowed)
			(copperpour not_allowed)
			(footprints allowed)
		)
		(placement
			(enabled no)
			(sheetname "")
		)
		(fill
			(thermal_gap 0.5)
			(thermal_bridge_width 0.5)
			(island_removal_mode 0)
		)
		(polygon
			(pts
				(arc
					(start 91.961462 -9.800082)
					(mid 91.400122 -9.238742)
					(end 90.838782 -9.800082)
				)
				(xy 90.838782 -10.285222) (xy 90.84437 -10.284714) (xy 90.844878 -10.284206)
				(arc
					(start 91.220798 -10.284206)
					(mid 91.295265 -10.257095)
					(end 91.334844 -10.188448)
				)
				(arc
					(start 91.334844 -10.188448)
					(mid 91.40102 -9.406269)
					(end 91.463622 -10.188702)
				)
				(xy 91.463622 -10.194798)
				(arc
					(start 91.462098 -10.196322)
					(mid 91.392563 -10.340147)
					(end 91.248738 -10.409682)
				)
				(xy 91.247214 -10.411206) (xy 90.871294 -10.411206) (xy 90.838782 -10.412476) (xy 90.838782 -10.590784)
				(xy 90.843608 -10.590276) (xy 90.844878 -10.589006) (xy 91.247214 -10.589006)
				(arc
					(start 91.248738 -10.59053)
					(mid 91.392563 -10.660065)
					(end 91.462098 -10.80389)
				)
				(xy 91.463622 -10.805414)
				(arc
					(start 91.463622 -10.81151)
					(mid 91.40102 -11.593903)
					(end 91.334844 -10.811764)
				)
				(arc
					(start 91.334844 -10.811764)
					(mid 91.295248 -10.743137)
					(end 91.220798 -10.716006)
				)
				(arc
					(start 90.871294 -10.716006)
					(mid 90.854943 -10.716922)
					(end 90.838782 -10.719562)
				)
				(arc
					(start 90.838782 -11.199876)
					(mid 91.399995 -11.76147)
					(end 91.961462 -11.20013)
				)
			)
		)
	)
	(zone
		(layer "In5.Cu")
		(hatch none 0.5)
		(connect_pads
			(clearance 0)
		)
		(min_thickness 0.25)
		(keepout
			(tracks not_allowed)
			(vias allowed)
			(pads allowed)
			(copperpour not_allowed)
			(footprints allowed)
		)
		(placement
			(enabled no)
			(sheetname "")
		)
		(fill
			(thermal_gap 0.5)
			(thermal_bridge_width 0.5)
			(island_removal_mode 0)
		)
		(polygon
			(pts
				(arc
					(start 114.356642 -50.967132)
					(mid 113.983498 -50.642392)
					(end 113.641886 -51.000152)
				)
				(arc
					(start 113.641886 -51.999896)
					(mid 113.999899 -52.35829)
					(end 114.358166 -52.00015)
				)
				(arc
					(start 114.358166 -51.645058)
					(mid 114.333258 -51.649203)
					(end 114.308128 -51.651662)
				)
				(xy 114.307366 -51.652424)
				(arc
					(start 114.088926 -51.652424)
					(mid 114.066475 -51.661723)
					(end 114.057176 -51.684174)
				)
				(arc
					(start 114.057176 -51.765708)
					(mid 114.000026 -52.241457)
					(end 113.942876 -51.765708)
				)
				(xy 113.942876 -51.660552)
				(arc
					(start 113.945162 -51.658266)
					(mid 113.985632 -51.58088)
					(end 114.063018 -51.54041)
				)
				(xy 114.065304 -51.538124)
				(arc
					(start 114.284252 -51.538124)
					(mid 114.32159 -51.535428)
					(end 114.358166 -51.527456)
				)
				(arc
					(start 114.358166 -51.44643)
					(mid 114.334122 -51.454956)
					(end 114.309144 -51.460146)
				)
				(xy 114.307366 -51.461924) (xy 114.065304 -51.461924)
				(arc
					(start 114.063018 -51.459638)
					(mid 113.985632 -51.419168)
					(end 113.945162 -51.341782)
				)
				(xy 113.942876 -51.339496)
				(arc
					(start 113.942876 -51.234594)
					(mid 114.000026 -50.758845)
					(end 114.057176 -51.234594)
				)
				(arc
					(start 114.057176 -51.315874)
					(mid 114.066475 -51.338325)
					(end 114.088926 -51.347624)
				)
				(arc
					(start 114.283744 -51.347624)
					(mid 114.311641 -51.342075)
					(end 114.335306 -51.326288)
				)
				(arc
					(start 114.335306 -51.326288)
					(mid 114.351113 -51.302631)
					(end 114.356642 -51.274726)
				)
			)
		)
	)
	(zone
		(layer "In5.Cu")
		(hatch none 0.5)
		(connect_pads
			(clearance 0)
		)
		(min_thickness 0.25)
		(keepout
			(tracks not_allowed)
			(vias allowed)
			(pads allowed)
			(copperpour not_allowed)
			(footprints allowed)
		)
		(placement
			(enabled no)
			(sheetname "")
		)
		(fill
			(thermal_gap 0.5)
			(thermal_bridge_width 0.5)
			(island_removal_mode 0)
		)
		(polygon
			(pts
				(arc
					(start 106.361484 -9.800082)
					(mid 105.800144 -9.238742)
					(end 105.238804 -9.800082)
				)
				(xy 105.238804 -10.285222) (xy 105.244392 -10.284714) (xy 105.2449 -10.284206)
				(arc
					(start 105.62082 -10.284206)
					(mid 105.695287 -10.257095)
					(end 105.734866 -10.188448)
				)
				(arc
					(start 105.734866 -10.188448)
					(mid 105.801042 -9.406269)
					(end 105.863644 -10.188702)
				)
				(xy 105.863644 -10.194798)
				(arc
					(start 105.86212 -10.196322)
					(mid 105.792585 -10.340147)
					(end 105.64876 -10.409682)
				)
				(xy 105.647236 -10.411206) (xy 105.271316 -10.411206) (xy 105.238804 -10.412476) (xy 105.238804 -10.590784)
				(xy 105.24363 -10.590276) (xy 105.2449 -10.589006) (xy 105.647236 -10.589006)
				(arc
					(start 105.64876 -10.59053)
					(mid 105.792585 -10.660065)
					(end 105.86212 -10.80389)
				)
				(xy 105.863644 -10.805414)
				(arc
					(start 105.863644 -10.81151)
					(mid 105.801042 -11.593903)
					(end 105.734866 -10.811764)
				)
				(arc
					(start 105.734866 -10.811764)
					(mid 105.69527 -10.743137)
					(end 105.62082 -10.716006)
				)
				(arc
					(start 105.271316 -10.716006)
					(mid 105.254965 -10.716922)
					(end 105.238804 -10.719562)
				)
				(arc
					(start 105.238804 -11.199876)
					(mid 105.800017 -11.76147)
					(end 106.361484 -11.20013)
				)
			)
		)
	)
	(zone
		(layer "In5.Cu")
		(hatch none 0.5)
		(connect_pads
			(clearance 0)
		)
		(min_thickness 0.25)
		(keepout
			(tracks not_allowed)
			(vias allowed)
			(pads allowed)
			(copperpour not_allowed)
			(footprints allowed)
		)
		(placement
			(enabled no)
			(sheetname "")
		)
		(fill
			(thermal_gap 0.5)
			(thermal_bridge_width 0.5)
			(island_removal_mode 0)
		)
		(polygon
			(pts
				(arc
					(start 131.561332 -9.800082)
					(mid 130.999992 -9.238742)
					(end 130.438652 -9.800082)
				)
				(xy 130.438652 -10.285222) (xy 130.44424 -10.284714) (xy 130.444748 -10.284206)
				(arc
					(start 130.820668 -10.284206)
					(mid 130.895135 -10.257095)
					(end 130.934714 -10.188448)
				)
				(arc
					(start 130.934714 -10.188448)
					(mid 131.00089 -9.406269)
					(end 131.063492 -10.188702)
				)
				(xy 131.063492 -10.194798)
				(arc
					(start 131.061968 -10.196322)
					(mid 130.992433 -10.340147)
					(end 130.848608 -10.409682)
				)
				(xy 130.847084 -10.411206) (xy 130.471164 -10.411206) (xy 130.438652 -10.412476) (xy 130.438652 -10.590784)
				(xy 130.443478 -10.590276) (xy 130.444748 -10.589006) (xy 130.847084 -10.589006)
				(arc
					(start 130.848608 -10.59053)
					(mid 130.992433 -10.660065)
					(end 131.061968 -10.80389)
				)
				(xy 131.063492 -10.805414)
				(arc
					(start 131.063492 -10.81151)
					(mid 131.00089 -11.593903)
					(end 130.934714 -10.811764)
				)
				(arc
					(start 130.934714 -10.811764)
					(mid 130.895118 -10.743137)
					(end 130.820668 -10.716006)
				)
				(arc
					(start 130.471164 -10.716006)
					(mid 130.454814 -10.716924)
					(end 130.438652 -10.719562)
				)
				(arc
					(start 130.438652 -11.199876)
					(mid 130.999865 -11.76147)
					(end 131.561332 -11.20013)
				)
			)
		)
	)
	(zone
		(layer "In5.Cu")
		(hatch none 0.5)
		(connect_pads
			(clearance 0)
		)
		(min_thickness 0.25)
		(keepout
			(tracks not_allowed)
			(vias allowed)
			(pads allowed)
			(copperpour not_allowed)
			(footprints allowed)
		)
		(placement
			(enabled no)
			(sheetname "")
		)
		(fill
			(thermal_gap 0.5)
			(thermal_bridge_width 0.5)
			(island_removal_mode 0)
		)
		(polygon
			(pts
				(arc
					(start 180.819552 -23.596346)
					(mid 180.436012 -23.212806)
					(end 180.052472 -23.596346)
				)
				(arc
					(start 180.052472 -24.485092)
					(mid 180.435885 -24.868886)
					(end 180.819552 -24.485346)
				)
				(xy 180.819552 -24.288496)
				(arc
					(start 180.715412 -24.288496)
					(mid 180.673562 -24.29299)
					(end 180.633624 -24.306276)
				)
				(arc
					(start 180.633624 -24.306276)
					(mid 180.313243 -24.722083)
					(end 180.468524 -24.220678)
				)
				(arc
					(start 180.468524 -24.220678)
					(mid 180.566099 -24.155636)
					(end 180.679344 -24.125174)
				)
				(xy 180.681122 -24.123396) (xy 180.819552 -24.123396) (xy 180.819552 -23.958296) (xy 180.681122 -23.958296)
				(arc
					(start 180.679344 -23.956518)
					(mid 180.566086 -23.926083)
					(end 180.468524 -23.861014)
				)
				(arc
					(start 180.468524 -23.861014)
					(mid 180.313252 -23.359626)
					(end 180.633624 -23.775416)
				)
				(arc
					(start 180.633624 -23.775416)
					(mid 180.673564 -23.788693)
					(end 180.715412 -23.793196)
				)
				(xy 180.819552 -23.793196)
			)
		)
	)
	(zone
		(net "P1V8_C")
		(layer "In5.Cu")
		(hatch none 0.5)
		(connect_pads
			(clearance 0.5)
		)
		(min_thickness 0.25)
		(fill yes
			(thermal_gap 0.5)
			(thermal_bridge_width 0.5)
			(island_removal_mode 0)
		)
		(polygon
			(pts
				(xy 179.705 -49.8856) (xy 184.5818 -49.8856) (xy 184.8866 -49.5808) (xy 184.8866 -43.3832) (xy 185.87974 -42.39006)
				(xy 189.67958 -42.39006) (xy 194.01028 -46.72076) (xy 199.90054 -46.72076) (xy 200.99782 -45.62348)
				(xy 200.99782 -28.48102) (xy 196.723 -24.2062) (xy 180.4162 -24.2062) (xy 180.0098 -24.6126) (xy 180.0098 -25.273)
				(xy 179.6034 -25.6794) (xy 178.9303 -25.6794) (xy 159.1056 -25.6794) (xy 158.7754 -26.0096) (xy 158.7754 -34.059876)
				(xy 158.7754 -41.518332) (xy 159.7914 -42.534332) (xy 160.4391 -43.182032) (xy 160.4391 -46.0883)
				(xy 160.4137 -46.1137) (xy 160.4137 -46.8503) (xy 158.2166 -49.0474) (xy 158.2166 -53.5305) (xy 159.004 -54.3179)
				(xy 159.004 -57.3278) (xy 160.6042 -58.928) (xy 162.687 -58.928) (xy 164.5158 -58.928) (xy 164.719 -58.7248)
				(xy 164.719 -49.784) (xy 164.719 -46.482) (xy 164.1348 -45.8978) (xy 163.322 -45.085) (xy 163.322 -44.0182)
				(xy 161.8742 -42.5704) (xy 161.8742 -41.91) (xy 161.1376 -41.1734) (xy 161.1376 -41.0972) (xy 161.1376 -27.7622)
				(xy 162.0774 -26.8224) (xy 167.4876 -26.8224) (xy 178.2826 -26.8224) (xy 179.1208 -26.8224) (xy 179.1335 -26.8351)
				(xy 180.848 -28.5496) (xy 180.848 -28.9052) (xy 181.0766 -29.1338) (xy 184.023 -29.1338) (xy 184.2008 -29.3116)
				(xy 184.2008 -29.845) (xy 183.9976 -30.0482) (xy 179.6542 -30.0482) (xy 179.451 -30.2514) (xy 179.451 -32.1818)
				(xy 179.6542 -32.385) (xy 181.6354 -32.385) (xy 181.8132 -32.5628) (xy 181.8132 -33.0454) (xy 181.5338 -33.3248)
				(xy 180.3146 -33.3248) (xy 179.7304 -33.909) (xy 179.7304 -36.2204) (xy 180.1368 -36.6268) (xy 180.8226 -37.3126)
				(xy 180.8226 -42.3418) (xy 180.8226 -42.8752) (xy 180.8226 -43.4848) (xy 180.9242 -43.5864) (xy 181.1274 -43.5864)
				(xy 181.61 -43.5864) (xy 181.7878 -43.7642) (xy 181.7878 -44.196) (xy 181.61 -44.3738) (xy 180.9496 -44.3738)
				(xy 179.9336 -44.3738) (xy 179.7431 -44.5643) (xy 179.7431 -44.8437) (xy 179.7431 -47.315882) (xy 178.519582 -48.5394)
				(xy 177.9778 -48.5394) (xy 177.8254 -48.6918) (xy 177.8254 -49.8348) (xy 177.8762 -49.8856)
			)
		)
	)
	(zone
		(layer "In5.Cu")
		(hatch none 0.5)
		(connect_pads
			(clearance 0)
		)
		(min_thickness 0.25)
		(keepout
			(tracks not_allowed)
			(vias allowed)
			(pads allowed)
			(copperpour not_allowed)
			(footprints allowed)
		)
		(placement
			(enabled no)
			(sheetname "")
		)
		(fill
			(thermal_gap 0.5)
			(thermal_bridge_width 0.5)
			(island_removal_mode 0)
		)
		(polygon
			(pts
				(arc
					(start 185.961274 -2.600198)
					(mid 185.399934 -2.038858)
					(end 184.838594 -2.600198)
				)
				(arc
					(start 184.838594 -3.061462)
					(mid 184.876329 -3.056359)
					(end 184.914286 -3.053334)
				)
				(xy 184.915048 -3.052572)
				(arc
					(start 185.23331 -3.052572)
					(mid 185.286708 -3.033437)
					(end 185.31586 -2.984754)
				)
				(arc
					(start 185.31586 -2.984754)
					(mid 185.401737 -2.206452)
					(end 185.482484 -2.985262)
				)
				(xy 185.482484 -3.002788)
				(arc
					(start 185.47969 -3.005328)
					(mid 185.409463 -3.144651)
					(end 185.27014 -3.214878)
				)
				(xy 185.2676 -3.217672)
				(arc
					(start 184.949338 -3.217672)
					(mid 184.893661 -3.220619)
					(end 184.838594 -3.229356)
				)
				(arc
					(start 184.838594 -3.39979)
					(mid 184.875537 -3.390235)
					(end 184.91327 -3.38455)
				)
				(xy 184.915048 -3.382772) (xy 185.267854 -3.382772)
				(arc
					(start 185.270394 -3.385566)
					(mid 185.409539 -3.455717)
					(end 185.47969 -3.594862)
				)
				(xy 185.482484 -3.597402)
				(arc
					(start 185.482484 -3.614928)
					(mid 185.401737 -4.393697)
					(end 185.31586 -3.615436)
				)
				(arc
					(start 185.31586 -3.615436)
					(mid 185.286824 -3.566882)
					(end 185.233564 -3.547872)
				)
				(arc
					(start 184.949338 -3.547872)
					(mid 184.891558 -3.556304)
					(end 184.838594 -3.580892)
				)
				(arc
					(start 184.838594 -3.999738)
					(mid 185.399807 -4.561332)
					(end 185.961274 -3.999992)
				)
			)
		)
	)
	(zone
		(layer "In5.Cu")
		(hatch none 0.5)
		(connect_pads
			(clearance 0)
		)
		(min_thickness 0.25)
		(keepout
			(tracks not_allowed)
			(vias allowed)
			(pads allowed)
			(copperpour not_allowed)
			(footprints allowed)
		)
		(placement
			(enabled no)
			(sheetname "")
		)
		(fill
			(thermal_gap 0.5)
			(thermal_bridge_width 0.5)
			(island_removal_mode 0)
		)
		(polygon
			(pts
				(arc
					(start 168.543478 -23.123906)
					(mid 168.159938 -22.740366)
					(end 167.776398 -23.123906)
				)
				(arc
					(start 167.776398 -24.012652)
					(mid 168.159811 -24.396446)
					(end 168.543478 -24.012906)
				)
				(xy 168.543478 -23.816056)
				(arc
					(start 168.439338 -23.816056)
					(mid 168.397488 -23.82055)
					(end 168.35755 -23.833836)
				)
				(arc
					(start 168.35755 -23.833836)
					(mid 168.037169 -24.249643)
					(end 168.19245 -23.748238)
				)
				(arc
					(start 168.19245 -23.748238)
					(mid 168.290025 -23.683196)
					(end 168.40327 -23.652734)
				)
				(xy 168.405048 -23.650956) (xy 168.543478 -23.650956) (xy 168.543478 -23.485856) (xy 168.405048 -23.485856)
				(arc
					(start 168.40327 -23.484078)
					(mid 168.290012 -23.453643)
					(end 168.19245 -23.388574)
				)
				(arc
					(start 168.19245 -23.388574)
					(mid 168.037178 -22.887186)
					(end 168.35755 -23.302976)
				)
				(arc
					(start 168.35755 -23.302976)
					(mid 168.39749 -23.316253)
					(end 168.439338 -23.320756)
				)
				(xy 168.543478 -23.320756)
			)
		)
	)
	(zone
		(layer "In5.Cu")
		(hatch none 0.5)
		(connect_pads
			(clearance 0)
		)
		(min_thickness 0.25)
		(keepout
			(tracks not_allowed)
			(vias allowed)
			(pads allowed)
			(copperpour not_allowed)
			(footprints allowed)
		)
		(placement
			(enabled no)
			(sheetname "")
		)
		(fill
			(thermal_gap 0.5)
			(thermal_bridge_width 0.5)
			(island_removal_mode 0)
		)
		(polygon
			(pts
				(arc
					(start 122.34926 -51.920902)
					(mid 121.960138 -51.644248)
					(end 121.64187 -52.00015)
				)
				(arc
					(start 121.64187 -52.999894)
					(mid 121.999883 -53.358288)
					(end 122.35815 -53.000148)
				)
				(arc
					(start 122.35815 -52.622958)
					(mid 122.290687 -52.642728)
					(end 122.22099 -52.651914)
				)
				(xy 122.220228 -52.652422)
				(arc
					(start 122.08891 -52.652422)
					(mid 122.066459 -52.661721)
					(end 122.05716 -52.684172)
				)
				(arc
					(start 122.05716 -52.765706)
					(mid 122.00001 -53.241455)
					(end 121.94286 -52.765706)
				)
				(xy 121.94286 -52.66055)
				(arc
					(start 121.945146 -52.658264)
					(mid 121.985616 -52.580878)
					(end 122.063002 -52.540408)
				)
				(xy 122.065288 -52.538122)
				(arc
					(start 122.197114 -52.538122)
					(mid 122.280095 -52.527938)
					(end 122.35815 -52.49799)
				)
				(arc
					(start 122.35815 -52.407566)
					(mid 122.293545 -52.443694)
					(end 122.221498 -52.460652)
				)
				(xy 122.220228 -52.461922) (xy 122.065288 -52.461922)
				(arc
					(start 122.063002 -52.459636)
					(mid 121.985616 -52.419166)
					(end 121.945146 -52.34178)
				)
				(xy 121.94286 -52.339494)
				(arc
					(start 121.94286 -52.234592)
					(mid 122.00001 -51.758843)
					(end 122.05716 -52.234592)
				)
				(arc
					(start 122.05716 -52.315872)
					(mid 122.066459 -52.338323)
					(end 122.08891 -52.347622)
				)
				(arc
					(start 122.196606 -52.347622)
					(mid 122.255024 -52.336002)
					(end 122.304556 -52.302918)
				)
				(arc
					(start 122.304556 -52.302918)
					(mid 122.337649 -52.25339)
					(end 122.34926 -52.194968)
				)
			)
		)
	)
	(zone
		(layer "In5.Cu")
		(hatch none 0.5)
		(connect_pads
			(clearance 0)
		)
		(min_thickness 0.25)
		(keepout
			(tracks not_allowed)
			(vias allowed)
			(pads allowed)
			(copperpour not_allowed)
			(footprints allowed)
		)
		(placement
			(enabled no)
			(sheetname "")
		)
		(fill
			(thermal_gap 0.5)
			(thermal_bridge_width 0.5)
			(island_removal_mode 0)
		)
		(polygon
			(pts
				(arc
					(start 112.351566 -50.931572)
					(mid 111.96558 -50.64365)
					(end 111.64189 -51.000152)
				)
				(arc
					(start 111.64189 -51.999896)
					(mid 111.999903 -52.35829)
					(end 112.35817 -52.00015)
				)
				(arc
					(start 112.35817 -51.643788)
					(mid 112.329997 -51.648789)
					(end 112.301528 -51.651662)
				)
				(xy 112.300766 -51.652424) (xy 112.278414 -51.652424) (xy 112.277144 -51.652424)
				(arc
					(start 112.08893 -51.652424)
					(mid 112.066479 -51.661723)
					(end 112.05718 -51.684174)
				)
				(arc
					(start 112.05718 -51.765708)
					(mid 112.00003 -52.241457)
					(end 111.94288 -51.765708)
				)
				(xy 111.94288 -51.660552)
				(arc
					(start 111.945166 -51.658266)
					(mid 111.985636 -51.58088)
					(end 112.063022 -51.54041)
				)
				(xy 112.065308 -51.538124)
				(arc
					(start 112.27816 -51.538124)
					(mid 112.318642 -51.53497)
					(end 112.35817 -51.525678)
				)
				(arc
					(start 112.35817 -51.44389)
					(mid 112.331115 -51.454174)
					(end 112.302798 -51.460146)
				)
				(xy 112.30102 -51.461924) (xy 112.277906 -51.461924) (xy 112.277398 -51.461924) (xy 112.065308 -51.461924)
				(arc
					(start 112.063022 -51.459638)
					(mid 111.985636 -51.419168)
					(end 111.945166 -51.341782)
				)
				(xy 111.94288 -51.339496)
				(arc
					(start 111.94288 -51.234594)
					(mid 112.00003 -50.758845)
					(end 112.05718 -51.234594)
				)
				(arc
					(start 112.05718 -51.315874)
					(mid 112.066479 -51.338325)
					(end 112.08893 -51.347624)
				)
				(arc
					(start 112.277906 -51.347624)
					(mid 112.306069 -51.341964)
					(end 112.329976 -51.326034)
				)
				(arc
					(start 112.33023 -51.32578)
					(mid 112.346033 -51.301848)
					(end 112.351566 -51.27371)
				)
			)
		)
	)
	(zone
		(layer "In5.Cu")
		(hatch none 0.5)
		(connect_pads
			(clearance 0)
		)
		(min_thickness 0.25)
		(keepout
			(tracks not_allowed)
			(vias allowed)
			(pads allowed)
			(copperpour not_allowed)
			(footprints allowed)
		)
		(placement
			(enabled no)
			(sheetname "")
		)
		(fill
			(thermal_gap 0.5)
			(thermal_bridge_width 0.5)
			(island_removal_mode 0)
		)
		(polygon
			(pts
				(arc
					(start 166.508938 -23.166832)
					(mid 166.125398 -22.783292)
					(end 165.741858 -23.166832)
				)
				(arc
					(start 165.741858 -24.055578)
					(mid 166.125271 -24.439372)
					(end 166.508938 -24.055832)
				)
				(xy 166.508938 -23.858982)
				(arc
					(start 166.404798 -23.858982)
					(mid 166.362948 -23.863476)
					(end 166.32301 -23.876762)
				)
				(arc
					(start 166.32301 -23.876762)
					(mid 166.002629 -24.292569)
					(end 166.15791 -23.791164)
				)
				(arc
					(start 166.15791 -23.791164)
					(mid 166.255485 -23.726122)
					(end 166.36873 -23.69566)
				)
				(xy 166.370508 -23.693882) (xy 166.508938 -23.693882) (xy 166.508938 -23.528782) (xy 166.370508 -23.528782)
				(arc
					(start 166.36873 -23.527004)
					(mid 166.255472 -23.496569)
					(end 166.15791 -23.4315)
				)
				(arc
					(start 166.15791 -23.4315)
					(mid 166.002638 -22.930112)
					(end 166.32301 -23.345902)
				)
				(arc
					(start 166.32301 -23.345902)
					(mid 166.36295 -23.359179)
					(end 166.404798 -23.363682)
				)
				(xy 166.508938 -23.363682)
			)
		)
	)
	(zone
		(layer "In5.Cu")
		(hatch none 0.5)
		(connect_pads
			(clearance 0)
		)
		(min_thickness 0.25)
		(keepout
			(tracks not_allowed)
			(vias allowed)
			(pads allowed)
			(copperpour not_allowed)
			(footprints allowed)
		)
		(placement
			(enabled no)
			(sheetname "")
		)
		(fill
			(thermal_gap 0.5)
			(thermal_bridge_width 0.5)
			(island_removal_mode 0)
		)
		(polygon
			(pts
				(arc
					(start 130.000248 -70.641972)
					(mid 129.641854 -70.999985)
					(end 129.999994 -71.358252)
				)
				(arc
					(start 130.357626 -71.358252)
					(mid 130.3516 -71.326826)
					(end 130.348228 -71.295006)
				)
				(xy 130.347466 -71.294244) (xy 130.347466 -71.271638) (xy 130.347466 -71.270622)
				(arc
					(start 130.347466 -71.089012)
					(mid 130.338167 -71.066561)
					(end 130.315716 -71.057262)
				)
				(arc
					(start 130.234436 -71.057262)
					(mid 129.758687 -71.000112)
					(end 130.234436 -70.942962)
				)
				(xy 130.339338 -70.942962)
				(arc
					(start 130.341624 -70.945248)
					(mid 130.41901 -70.985718)
					(end 130.45948 -71.063104)
				)
				(xy 130.461766 -71.06539)
				(arc
					(start 130.461766 -71.271384)
					(mid 130.465433 -71.315413)
					(end 130.476244 -71.358252)
				)
				(arc
					(start 130.558794 -71.358252)
					(mid 130.546643 -71.328071)
					(end 130.539744 -71.296276)
				)
				(xy 130.537966 -71.294498) (xy 130.537966 -71.06539)
				(arc
					(start 130.540252 -71.063104)
					(mid 130.580722 -70.985718)
					(end 130.658108 -70.945248)
				)
				(xy 130.660394 -70.942962)
				(arc
					(start 130.76555 -70.942962)
					(mid 131.241299 -71.000112)
					(end 130.76555 -71.057262)
				)
				(arc
					(start 130.684016 -71.057262)
					(mid 130.661565 -71.066561)
					(end 130.652266 -71.089012)
				)
				(arc
					(start 130.652266 -71.27113)
					(mid 130.658191 -71.301096)
					(end 130.675126 -71.326502)
				)
				(arc
					(start 130.67538 -71.326756)
					(mid 130.700711 -71.343493)
					(end 130.730498 -71.349362)
				)
				(arc
					(start 131.07924 -71.349362)
					(mid 131.355894 -70.96024)
					(end 130.999992 -70.641972)
				)
			)
		)
	)
	(zone
		(layer "In5.Cu")
		(hatch none 0.5)
		(connect_pads
			(clearance 0)
		)
		(min_thickness 0.25)
		(keepout
			(tracks not_allowed)
			(vias allowed)
			(pads allowed)
			(copperpour not_allowed)
			(footprints allowed)
		)
		(placement
			(enabled no)
			(sheetname "")
		)
		(fill
			(thermal_gap 0.5)
			(thermal_bridge_width 0.5)
			(island_removal_mode 0)
		)
		(polygon
			(pts
				(arc
					(start 111.34725 -51.912266)
					(mid 110.95575 -51.64473)
					(end 110.641892 -52.00015)
				)
				(arc
					(start 110.641892 -52.999894)
					(mid 110.999905 -53.358288)
					(end 111.358172 -53.000148)
				)
				(arc
					(start 111.358172 -52.641754)
					(mid 111.32562 -52.648124)
					(end 111.29264 -52.65166)
				)
				(xy 111.291878 -52.652422)
				(arc
					(start 111.088932 -52.652422)
					(mid 111.066481 -52.661721)
					(end 111.057182 -52.684172)
				)
				(arc
					(start 111.057182 -52.765706)
					(mid 111.000032 -53.241455)
					(end 110.942882 -52.765706)
				)
				(xy 110.942882 -52.66055)
				(arc
					(start 110.945168 -52.658264)
					(mid 110.985638 -52.580878)
					(end 111.063024 -52.540408)
				)
				(xy 111.06531 -52.538122)
				(arc
					(start 111.268764 -52.538122)
					(mid 111.314112 -52.534283)
					(end 111.358172 -52.522882)
				)
				(arc
					(start 111.358172 -52.439824)
					(mid 111.326808 -52.452819)
					(end 111.293656 -52.460144)
				)
				(xy 111.291878 -52.461922) (xy 111.06531 -52.461922)
				(arc
					(start 111.063024 -52.459636)
					(mid 110.985638 -52.419166)
					(end 110.945168 -52.34178)
				)
				(xy 110.942882 -52.339494)
				(arc
					(start 110.942882 -52.234592)
					(mid 111.000032 -51.758843)
					(end 111.057182 -52.234592)
				)
				(arc
					(start 111.057182 -52.315872)
					(mid 111.066481 -52.338323)
					(end 111.088932 -52.347622)
				)
				(arc
					(start 111.268256 -52.347622)
					(mid 111.298486 -52.341609)
					(end 111.324136 -52.324508)
				)
				(arc
					(start 111.324136 -52.324508)
					(mid 111.341267 -52.29887)
					(end 111.34725 -52.268628)
				)
			)
		)
	)
	(zone
		(layer "In5.Cu")
		(hatch none 0.5)
		(connect_pads
			(clearance 0)
		)
		(min_thickness 0.25)
		(keepout
			(tracks not_allowed)
			(vias allowed)
			(pads allowed)
			(copperpour not_allowed)
			(footprints allowed)
		)
		(placement
			(enabled no)
			(sheetname "")
		)
		(fill
			(thermal_gap 0.5)
			(thermal_bridge_width 0.5)
			(island_removal_mode 0)
		)
		(polygon
			(pts
				(arc
					(start 106.188256 -103.684832)
					(mid 105.984802 -103.011986)
					(end 105.311956 -103.21544)
				)
				(xy 105.311194 -103.214932)
				(arc
					(start 105.090976 -103.626158)
					(mid 105.126176 -103.680754)
					(end 105.168192 -103.730298)
				)
				(xy 105.30205 -103.864156) (xy 105.310686 -103.87076)
				(arc
					(start 105.387394 -103.911654)
					(mid 105.41631 -103.914406)
					(end 105.438702 -103.895906)
				)
				(arc
					(start 105.516172 -103.750872)
					(mid 105.93057 -103.114577)
					(end 105.628186 -103.81107)
				)
				(arc
					(start 105.55097 -103.95585)
					(mid 105.466815 -104.031277)
					(end 105.353866 -104.034844)
				)
				(xy 105.35031 -104.03586) (xy 105.327704 -104.023668) (xy 105.327196 -104.023414) (xy 105.231438 -103.97236)
				(xy 105.230422 -103.97236) (xy 105.229406 -103.97109) (xy 105.227628 -103.970328) (xy 105.22712 -103.969058)
				(xy 105.212134 -103.954072) (xy 105.21188 -103.953818) (xy 105.090722 -103.832406) (xy 105.077514 -103.819452)
				(xy 105.071672 -103.81361)
				(arc
					(start 105.071672 -103.813356)
					(mid 105.04612 -103.784526)
					(end 105.022396 -103.754174)
				)
				(xy 104.931464 -103.923846) (xy 104.951276 -103.944674) (xy 105.006648 -104.000046) (xy 105.02519 -104.018588)
				(xy 105.043732 -104.03713) (xy 105.043732 -104.037384)
				(arc
					(start 105.085896 -104.079548)
					(mid 105.123499 -104.112023)
					(end 105.165398 -104.13873)
				)
				(xy 105.166668 -104.139492) (xy 105.219754 -104.167686) (xy 105.243122 -104.180132) (xy 105.266236 -104.192578)
				(arc
					(start 105.267252 -104.196134)
					(mid 105.323281 -104.278035)
					(end 105.322116 -104.377236)
				)
				(xy 105.323132 -104.380792) (xy 105.31094 -104.403398) (xy 105.310686 -104.403906)
				(arc
					(start 105.233216 -104.548686)
					(mid 104.81973 -105.185326)
					(end 105.121456 -104.488742)
				)
				(arc
					(start 105.198926 -104.343708)
					(mid 105.201678 -104.314792)
					(end 105.183178 -104.2924)
				)
				(xy 105.183178 -104.292146) (xy 105.182924 -104.292146) (xy 105.15981 -104.279954) (xy 105.136696 -104.267508)
				(xy 105.106724 -104.251252) (xy 105.1052 -104.25049) (xy 105.08361 -104.238806)
				(arc
					(start 105.083102 -104.238044)
					(mid 105.048325 -104.214534)
					(end 105.015792 -104.188006)
				)
				(xy 105.014522 -104.188006) (xy 104.935274 -104.108504) (xy 104.876346 -104.049576) (xy 104.868218 -104.041448)
				(xy 104.561386 -104.614472) (xy 104.561386 -104.61498)
				(arc
					(start 104.561894 -104.615234)
					(mid 104.765348 -105.28808)
					(end 105.438194 -105.084626)
				)
				(xy 105.438956 -105.085134) (xy 105.923842 -104.180132) (xy 105.945686 -104.139492) (xy 106.189018 -103.68534)
			)
		)
	)
	(zone
		(layer "In5.Cu")
		(hatch none 0.5)
		(connect_pads
			(clearance 0)
		)
		(min_thickness 0.25)
		(keepout
			(tracks not_allowed)
			(vias allowed)
			(pads allowed)
			(copperpour not_allowed)
			(footprints allowed)
		)
		(placement
			(enabled no)
			(sheetname "")
		)
		(fill
			(thermal_gap 0.5)
			(thermal_bridge_width 0.5)
			(island_removal_mode 0)
		)
		(polygon
			(pts
				(arc
					(start 142.361412 -9.800082)
					(mid 141.800072 -9.238742)
					(end 141.238732 -9.800082)
				)
				(xy 141.238732 -10.285222) (xy 141.24432 -10.284714) (xy 141.244828 -10.284206)
				(arc
					(start 141.620748 -10.284206)
					(mid 141.695215 -10.257095)
					(end 141.734794 -10.188448)
				)
				(arc
					(start 141.734794 -10.188448)
					(mid 141.80097 -9.406269)
					(end 141.863572 -10.188702)
				)
				(xy 141.863572 -10.194798)
				(arc
					(start 141.862048 -10.196322)
					(mid 141.792513 -10.340147)
					(end 141.648688 -10.409682)
				)
				(xy 141.647164 -10.411206) (xy 141.271244 -10.411206) (xy 141.238732 -10.412476) (xy 141.238732 -10.590784)
				(xy 141.243558 -10.590276) (xy 141.244828 -10.589006) (xy 141.647164 -10.589006)
				(arc
					(start 141.648688 -10.59053)
					(mid 141.792513 -10.660065)
					(end 141.862048 -10.80389)
				)
				(xy 141.863572 -10.805414)
				(arc
					(start 141.863572 -10.81151)
					(mid 141.80097 -11.593903)
					(end 141.734794 -10.811764)
				)
				(arc
					(start 141.734794 -10.811764)
					(mid 141.695198 -10.743137)
					(end 141.620748 -10.716006)
				)
				(arc
					(start 141.271244 -10.716006)
					(mid 141.254893 -10.716922)
					(end 141.238732 -10.719562)
				)
				(arc
					(start 141.238732 -11.199876)
					(mid 141.799945 -11.76147)
					(end 142.361412 -11.20013)
				)
			)
		)
	)
	(zone
		(layer "In5.Cu")
		(hatch none 0.5)
		(connect_pads
			(clearance 0)
		)
		(min_thickness 0.25)
		(keepout
			(tracks not_allowed)
			(vias allowed)
			(pads allowed)
			(copperpour not_allowed)
			(footprints allowed)
		)
		(placement
			(enabled no)
			(sheetname "")
		)
		(fill
			(thermal_gap 0.5)
			(thermal_bridge_width 0.5)
			(island_removal_mode 0)
		)
		(polygon
			(pts
				(arc
					(start 122.56135 -10.999978)
					(mid 122.00001 -10.438638)
					(end 121.43867 -10.999978)
				)
				(xy 121.43867 -11.485118) (xy 121.444258 -11.48461) (xy 121.444766 -11.484102)
				(arc
					(start 121.820686 -11.484102)
					(mid 121.895153 -11.456991)
					(end 121.934732 -11.388344)
				)
				(arc
					(start 121.934732 -11.388344)
					(mid 122.000908 -10.606165)
					(end 122.06351 -11.388598)
				)
				(xy 122.06351 -11.394694)
				(arc
					(start 122.061986 -11.396218)
					(mid 121.992451 -11.540043)
					(end 121.848626 -11.609578)
				)
				(xy 121.847102 -11.611102) (xy 121.471182 -11.611102) (xy 121.43867 -11.612372) (xy 121.43867 -11.79068)
				(xy 121.443496 -11.790172) (xy 121.444766 -11.788902) (xy 121.847102 -11.788902)
				(arc
					(start 121.848626 -11.790426)
					(mid 121.992451 -11.859961)
					(end 122.061986 -12.003786)
				)
				(xy 122.06351 -12.00531)
				(arc
					(start 122.06351 -12.011406)
					(mid 122.000908 -12.793799)
					(end 121.934732 -12.01166)
				)
				(arc
					(start 121.934732 -12.01166)
					(mid 121.895136 -11.943033)
					(end 121.820686 -11.915902)
				)
				(arc
					(start 121.471182 -11.915902)
					(mid 121.454832 -11.91682)
					(end 121.43867 -11.919458)
				)
				(arc
					(start 121.43867 -12.399772)
					(mid 121.999883 -12.961366)
					(end 122.56135 -12.400026)
				)
			)
		)
	)
	(zone
		(net "P0V975")
		(layer "In5.Cu")
		(hatch none 0.5)
		(connect_pads
			(clearance 0.5)
		)
		(min_thickness 0.25)
		(fill yes
			(thermal_gap 0.5)
			(thermal_bridge_width 0.5)
			(island_removal_mode 0)
		)
		(polygon
			(pts
				(xy 164.9476 -49.53) (xy 164.9476 -61.6204) (xy 164.9476 -62.44844) (xy 163.056062 -64.339978) (xy 163.056062 -71.1962)
				(xy 169.720514 -77.860652) (xy 169.720514 -86.13775) (xy 169.720514 -87.627714) (xy 177.1142 -95.0214)
				(xy 180.4162 -95.0214) (xy 182.8546 -97.4598) (xy 189.0776 -97.4598) (xy 190.373 -96.1644) (xy 190.373 -83.850734)
				(xy 189.2935 -82.771234) (xy 175.375824 -68.853558) (xy 175.375824 -55.537608) (xy 174.286164 -54.447948)
				(xy 174.286164 -54.01183) (xy 177.480468 -50.817526) (xy 177.480468 -48.894238) (xy 177.975514 -48.399192)
				(xy 178.372008 -48.399192) (xy 179.4002 -47.371) (xy 179.4002 -43.7134) (xy 179.5272 -43.5864) (xy 180.34 -43.5864)
				(xy 180.5432 -43.3832) (xy 180.5432 -42.888408) (xy 180.5432 -37.211) (xy 180.1241 -36.7919) (xy 179.9971 -36.7919)
				(xy 178.8922 -35.687) (xy 178.054 -35.687) (xy 172.6184 -35.687) (xy 171.50207 -36.80333) (xy 171.50207 -40.01643)
				(xy 169.1259 -42.3926) (xy 169.1259 -46.6217) (xy 168.0464 -47.7012) (xy 165.283134 -47.7012) (xy 164.9476 -48.036734)
			)
		)
	)
	(zone
		(layer "In5.Cu")
		(hatch none 0.5)
		(connect_pads
			(clearance 0)
		)
		(min_thickness 0.25)
		(keepout
			(tracks not_allowed)
			(vias allowed)
			(pads allowed)
			(copperpour not_allowed)
			(footprints allowed)
		)
		(placement
			(enabled no)
			(sheetname "")
		)
		(fill
			(thermal_gap 0.5)
			(thermal_bridge_width 0.5)
			(island_removal_mode 0)
		)
		(polygon
			(pts
				(arc
					(start 117.16131 -9.800082)
					(mid 116.59997 -9.238742)
					(end 116.03863 -9.800082)
				)
				(xy 116.03863 -10.285222) (xy 116.044218 -10.284714) (xy 116.044726 -10.284206)
				(arc
					(start 116.420646 -10.284206)
					(mid 116.495113 -10.257095)
					(end 116.534692 -10.188448)
				)
				(arc
					(start 116.534692 -10.188448)
					(mid 116.600868 -9.406269)
					(end 116.66347 -10.188702)
				)
				(xy 116.66347 -10.194798)
				(arc
					(start 116.661946 -10.196322)
					(mid 116.592411 -10.340147)
					(end 116.448586 -10.409682)
				)
				(xy 116.447062 -10.411206) (xy 116.071142 -10.411206) (xy 116.03863 -10.412476) (xy 116.03863 -10.590784)
				(xy 116.043456 -10.590276) (xy 116.044726 -10.589006) (xy 116.447062 -10.589006)
				(arc
					(start 116.448586 -10.59053)
					(mid 116.592411 -10.660065)
					(end 116.661946 -10.80389)
				)
				(xy 116.66347 -10.805414)
				(arc
					(start 116.66347 -10.81151)
					(mid 116.600868 -11.593903)
					(end 116.534692 -10.811764)
				)
				(arc
					(start 116.534692 -10.811764)
					(mid 116.495096 -10.743137)
					(end 116.420646 -10.716006)
				)
				(arc
					(start 116.071142 -10.716006)
					(mid 116.054792 -10.716924)
					(end 116.03863 -10.719562)
				)
				(arc
					(start 116.03863 -11.199876)
					(mid 116.599843 -11.76147)
					(end 117.16131 -11.20013)
				)
			)
		)
	)
	(zone
		(layer "In5.Cu")
		(hatch none 0.5)
		(connect_pads
			(clearance 0)
		)
		(min_thickness 0.25)
		(keepout
			(tracks not_allowed)
			(vias allowed)
			(pads allowed)
			(copperpour not_allowed)
			(footprints allowed)
		)
		(placement
			(enabled no)
			(sheetname "")
		)
		(fill
			(thermal_gap 0.5)
			(thermal_bridge_width 0.5)
			(island_removal_mode 0)
		)
		(polygon
			(pts
				(arc
					(start 95.561404 -9.800082)
					(mid 95.000064 -9.238742)
					(end 94.438724 -9.800082)
				)
				(xy 94.438724 -10.285222) (xy 94.444312 -10.284714) (xy 94.44482 -10.284206)
				(arc
					(start 94.82074 -10.284206)
					(mid 94.895207 -10.257095)
					(end 94.934786 -10.188448)
				)
				(arc
					(start 94.934786 -10.188448)
					(mid 95.000962 -9.406269)
					(end 95.063564 -10.188702)
				)
				(xy 95.063564 -10.194798)
				(arc
					(start 95.06204 -10.196322)
					(mid 94.992505 -10.340147)
					(end 94.84868 -10.409682)
				)
				(xy 94.847156 -10.411206) (xy 94.471236 -10.411206) (xy 94.438724 -10.412476) (xy 94.438724 -10.590784)
				(xy 94.44355 -10.590276) (xy 94.44482 -10.589006) (xy 94.847156 -10.589006)
				(arc
					(start 94.84868 -10.59053)
					(mid 94.992505 -10.660065)
					(end 95.06204 -10.80389)
				)
				(xy 95.063564 -10.805414)
				(arc
					(start 95.063564 -10.81151)
					(mid 95.000962 -11.593903)
					(end 94.934786 -10.811764)
				)
				(arc
					(start 94.934786 -10.811764)
					(mid 94.89519 -10.743137)
					(end 94.82074 -10.716006)
				)
				(arc
					(start 94.471236 -10.716006)
					(mid 94.454885 -10.716922)
					(end 94.438724 -10.719562)
				)
				(arc
					(start 94.438724 -11.199876)
					(mid 94.999937 -11.76147)
					(end 95.561404 -11.20013)
				)
			)
		)
	)
	(zone
		(layer "In5.Cu")
		(hatch none 0.5)
		(connect_pads
			(clearance 0)
		)
		(min_thickness 0.25)
		(keepout
			(tracks not_allowed)
			(vias allowed)
			(pads allowed)
			(copperpour not_allowed)
			(footprints allowed)
		)
		(placement
			(enabled no)
			(sheetname "")
		)
		(fill
			(thermal_gap 0.5)
			(thermal_bridge_width 0.5)
			(island_removal_mode 0)
		)
		(polygon
			(pts
				(arc
					(start 129.761488 -10.999978)
					(mid 129.200148 -10.438638)
					(end 128.638808 -10.999978)
				)
				(xy 128.638808 -11.485118) (xy 128.644396 -11.48461) (xy 128.644904 -11.484102)
				(arc
					(start 129.020824 -11.484102)
					(mid 129.095291 -11.456991)
					(end 129.13487 -11.388344)
				)
				(arc
					(start 129.13487 -11.388344)
					(mid 129.201046 -10.606165)
					(end 129.263648 -11.388598)
				)
				(xy 129.263648 -11.394694)
				(arc
					(start 129.262124 -11.396218)
					(mid 129.192589 -11.540043)
					(end 129.048764 -11.609578)
				)
				(xy 129.04724 -11.611102) (xy 128.67132 -11.611102) (xy 128.638808 -11.612372) (xy 128.638808 -11.79068)
				(xy 128.643634 -11.790172) (xy 128.644904 -11.788902) (xy 129.04724 -11.788902)
				(arc
					(start 129.048764 -11.790426)
					(mid 129.192589 -11.859961)
					(end 129.262124 -12.003786)
				)
				(xy 129.263648 -12.00531)
				(arc
					(start 129.263648 -12.011406)
					(mid 129.201046 -12.793799)
					(end 129.13487 -12.01166)
				)
				(arc
					(start 129.13487 -12.01166)
					(mid 129.095274 -11.943033)
					(end 129.020824 -11.915902)
				)
				(arc
					(start 128.67132 -11.915902)
					(mid 128.65497 -11.91682)
					(end 128.638808 -11.919458)
				)
				(arc
					(start 128.638808 -12.399772)
					(mid 129.200021 -12.961366)
					(end 129.761488 -12.400026)
				)
			)
		)
	)
	(zone
		(layer "In5.Cu")
		(hatch none 0.5)
		(connect_pads
			(clearance 0)
		)
		(min_thickness 0.25)
		(keepout
			(tracks not_allowed)
			(vias allowed)
			(pads allowed)
			(copperpour not_allowed)
			(footprints allowed)
		)
		(placement
			(enabled no)
			(sheetname "")
		)
		(fill
			(thermal_gap 0.5)
			(thermal_bridge_width 0.5)
			(island_removal_mode 0)
		)
		(polygon
			(pts
				(arc
					(start 102.351586 -50.931572)
					(mid 101.9656 -50.64365)
					(end 101.64191 -51.000152)
				)
				(arc
					(start 101.64191 -51.999896)
					(mid 101.999923 -52.35829)
					(end 102.35819 -52.00015)
				)
				(arc
					(start 102.35819 -51.642264)
					(mid 102.32651 -51.648304)
					(end 102.294436 -51.651662)
				)
				(xy 102.293674 -51.652424)
				(arc
					(start 102.08895 -51.652424)
					(mid 102.066499 -51.661723)
					(end 102.0572 -51.684174)
				)
				(arc
					(start 102.0572 -51.765708)
					(mid 102.00005 -52.241457)
					(end 101.9429 -51.765708)
				)
				(xy 101.9429 -51.660552)
				(arc
					(start 101.945186 -51.658266)
					(mid 101.985656 -51.58088)
					(end 102.063042 -51.54041)
				)
				(xy 102.065328 -51.538124)
				(arc
					(start 102.27056 -51.538124)
					(mid 102.314967 -51.534475)
					(end 102.35819 -51.523646)
				)
				(arc
					(start 102.35819 -51.440842)
					(mid 102.32765 -51.453285)
					(end 102.295452 -51.4604)
				)
				(xy 102.293674 -51.461924) (xy 102.065328 -51.461924)
				(arc
					(start 102.063042 -51.459638)
					(mid 101.985656 -51.419168)
					(end 101.945186 -51.341782)
				)
				(xy 101.9429 -51.339496)
				(arc
					(start 101.9429 -51.234594)
					(mid 102.00005 -50.758845)
					(end 102.0572 -51.234594)
				)
				(arc
					(start 102.0572 -51.315874)
					(mid 102.066499 -51.338325)
					(end 102.08895 -51.347624)
				)
				(arc
					(start 102.270052 -51.347624)
					(mid 102.301254 -51.341418)
					(end 102.32771 -51.323748)
				)
				(arc
					(start 102.32771 -51.323748)
					(mid 102.345386 -51.297294)
					(end 102.351586 -51.26609)
				)
			)
		)
	)
	(zone
		(layer "In5.Cu")
		(hatch none 0.5)
		(connect_pads
			(clearance 0)
		)
		(min_thickness 0.25)
		(keepout
			(tracks not_allowed)
			(vias allowed)
			(pads allowed)
			(copperpour not_allowed)
			(footprints allowed)
		)
		(placement
			(enabled no)
			(sheetname "")
		)
		(fill
			(thermal_gap 0.5)
			(thermal_bridge_width 0.5)
			(island_removal_mode 0)
		)
		(polygon
			(pts
				(arc
					(start 99.161346 -9.800082)
					(mid 98.600006 -9.238742)
					(end 98.038666 -9.800082)
				)
				(xy 98.038666 -10.285222) (xy 98.044254 -10.284714) (xy 98.044762 -10.284206)
				(arc
					(start 98.420682 -10.284206)
					(mid 98.495149 -10.257095)
					(end 98.534728 -10.188448)
				)
				(arc
					(start 98.534728 -10.188448)
					(mid 98.600904 -9.406269)
					(end 98.663506 -10.188702)
				)
				(xy 98.663506 -10.194798)
				(arc
					(start 98.661982 -10.196322)
					(mid 98.592447 -10.340147)
					(end 98.448622 -10.409682)
				)
				(xy 98.447098 -10.411206) (xy 98.071178 -10.411206) (xy 98.038666 -10.412476) (xy 98.038666 -10.590784)
				(xy 98.043492 -10.590276) (xy 98.044762 -10.589006) (xy 98.447098 -10.589006)
				(arc
					(start 98.448622 -10.59053)
					(mid 98.592447 -10.660065)
					(end 98.661982 -10.80389)
				)
				(xy 98.663506 -10.805414)
				(arc
					(start 98.663506 -10.81151)
					(mid 98.600904 -11.593903)
					(end 98.534728 -10.811764)
				)
				(arc
					(start 98.534728 -10.811764)
					(mid 98.495132 -10.743137)
					(end 98.420682 -10.716006)
				)
				(arc
					(start 98.071178 -10.716006)
					(mid 98.054828 -10.716924)
					(end 98.038666 -10.719562)
				)
				(arc
					(start 98.038666 -11.199876)
					(mid 98.599879 -11.76147)
					(end 99.161346 -11.20013)
				)
			)
		)
	)
	(zone
		(layer "In5.Cu")
		(hatch none 0.5)
		(connect_pads
			(clearance 0)
		)
		(min_thickness 0.25)
		(keepout
			(tracks not_allowed)
			(vias allowed)
			(pads allowed)
			(copperpour not_allowed)
			(footprints allowed)
		)
		(placement
			(enabled no)
			(sheetname "")
		)
		(fill
			(thermal_gap 0.5)
			(thermal_bridge_width 0.5)
			(island_removal_mode 0)
		)
		(polygon
			(pts
				(arc
					(start 119.351552 -50.931572)
					(mid 118.965566 -50.64365)
					(end 118.641876 -51.000152)
				)
				(arc
					(start 118.641876 -51.999896)
					(mid 118.999889 -52.35829)
					(end 119.358156 -52.00015)
				)
				(arc
					(start 119.358156 -51.642772)
					(mid 119.330402 -51.648382)
					(end 119.302276 -51.651662)
				)
				(xy 119.30126 -51.652424) (xy 119.278908 -51.652424) (xy 119.277638 -51.652424)
				(arc
					(start 119.088916 -51.652424)
					(mid 119.066465 -51.661723)
					(end 119.057166 -51.684174)
				)
				(arc
					(start 119.057166 -51.765708)
					(mid 119.000016 -52.241457)
					(end 118.942866 -51.765708)
				)
				(xy 118.942866 -51.660552)
				(arc
					(start 118.945152 -51.658266)
					(mid 118.985622 -51.58088)
					(end 119.063008 -51.54041)
				)
				(xy 119.065294 -51.538124)
				(arc
					(start 119.278654 -51.538124)
					(mid 119.319091 -51.534273)
					(end 119.358156 -51.523138)
				)
				(arc
					(start 119.358156 -51.438048)
					(mid 119.332071 -51.451595)
					(end 119.3038 -51.459638)
				)
				(xy 119.301514 -51.461924) (xy 119.2784 -51.461924) (xy 119.277892 -51.461924) (xy 119.065294 -51.461924)
				(arc
					(start 119.063008 -51.459638)
					(mid 118.985622 -51.419168)
					(end 118.945152 -51.341782)
				)
				(xy 118.942866 -51.339496)
				(arc
					(start 118.942866 -51.234594)
					(mid 119.000016 -50.758845)
					(end 119.057166 -51.234594)
				)
				(arc
					(start 119.057166 -51.315874)
					(mid 119.066465 -51.338325)
					(end 119.088916 -51.347624)
				)
				(arc
					(start 119.2784 -51.347624)
					(mid 119.290361 -51.345078)
					(end 119.300498 -51.338226)
				)
				(arc
					(start 119.322596 -51.316128)
					(mid 119.344032 -51.283258)
					(end 119.351552 -51.244754)
				)
			)
		)
	)
	(zone
		(layer "In5.Cu")
		(hatch none 0.5)
		(connect_pads
			(clearance 0)
		)
		(min_thickness 0.25)
		(keepout
			(tracks not_allowed)
			(vias allowed)
			(pads allowed)
			(copperpour not_allowed)
			(footprints allowed)
		)
		(placement
			(enabled no)
			(sheetname "")
		)
		(fill
			(thermal_gap 0.5)
			(thermal_bridge_width 0.5)
			(island_removal_mode 0)
		)
		(polygon
			(pts
				(arc
					(start 103.93807 -107.484672)
					(mid 103.734616 -106.811826)
					(end 103.06177 -107.01528)
				)
				(xy 103.061008 -107.015026)
				(arc
					(start 102.844092 -107.42041)
					(mid 102.881917 -107.485064)
					(end 102.930198 -107.54233)
				)
				(xy 103.052118 -107.66425) (xy 103.060754 -107.670854)
				(arc
					(start 103.137462 -107.711748)
					(mid 103.166271 -107.714533)
					(end 103.18877 -107.696254)
				)
				(arc
					(start 103.266494 -107.55122)
					(mid 103.679343 -106.914069)
					(end 103.378508 -107.611164)
				)
				(xy 103.300784 -107.755944) (xy 103.300784 -107.756452) (xy 103.288338 -107.779058)
				(arc
					(start 103.285036 -107.780074)
					(mid 103.203135 -107.836103)
					(end 103.103934 -107.834938)
				)
				(xy 103.100378 -107.835954) (xy 103.077772 -107.823762) (xy 103.077264 -107.823508) (xy 102.981506 -107.772454)
				(xy 102.98049 -107.772454) (xy 102.979474 -107.771184) (xy 102.977696 -107.770422) (xy 102.977188 -107.769152)
				(xy 102.962202 -107.754166) (xy 102.961948 -107.753912) (xy 102.840282 -107.632246) (xy 102.82174 -107.613704)
				(arc
					(start 102.82174 -107.612688)
					(mid 102.796559 -107.58304)
					(end 102.77348 -107.551728)
				)
				(xy 102.681786 -107.723178) (xy 102.714552 -107.757976) (xy 102.756716 -107.80014) (xy 102.775258 -107.818682)
				(xy 102.7938 -107.837224) (xy 102.7938 -107.837478)
				(arc
					(start 102.835964 -107.879642)
					(mid 102.873567 -107.912117)
					(end 102.915466 -107.938824)
				)
				(xy 102.916736 -107.939586) (xy 102.969822 -107.96778) (xy 102.99319 -107.980226) (xy 103.016304 -107.992672)
				(arc
					(start 103.01732 -107.996228)
					(mid 103.073349 -108.078129)
					(end 103.072184 -108.17733)
				)
				(xy 103.0732 -108.180886) (xy 103.061008 -108.203492) (xy 103.060754 -108.204)
				(arc
					(start 102.983284 -108.34878)
					(mid 102.569798 -108.98542)
					(end 102.871524 -108.288836)
				)
				(arc
					(start 102.948994 -108.143802)
					(mid 102.951746 -108.114886)
					(end 102.933246 -108.092494)
				)
				(xy 102.933246 -108.09224) (xy 102.932992 -108.09224) (xy 102.909878 -108.080048) (xy 102.886764 -108.067602)
				(xy 102.856792 -108.051346) (xy 102.855268 -108.050584) (xy 102.833678 -108.0389)
				(arc
					(start 102.83317 -108.038138)
					(mid 102.798393 -108.014628)
					(end 102.76586 -107.9881)
				)
				(xy 102.76459 -107.9881) (xy 102.685342 -107.908598) (xy 102.61854 -107.841542) (xy 102.311454 -108.41482)
				(xy 102.311454 -108.415074)
				(arc
					(start 102.311962 -108.415328)
					(mid 102.515416 -109.088174)
					(end 103.188262 -108.88472)
				)
				(xy 103.189024 -108.884974) (xy 103.673402 -107.980226) (xy 103.6955 -107.939586) (xy 103.938832 -107.484926)
			)
		)
	)
	(zone
		(layer "In5.Cu")
		(hatch none 0.5)
		(connect_pads
			(clearance 0)
		)
		(min_thickness 0.25)
		(keepout
			(tracks not_allowed)
			(vias allowed)
			(pads allowed)
			(copperpour not_allowed)
			(footprints allowed)
		)
		(placement
			(enabled no)
			(sheetname "")
		)
		(fill
			(thermal_gap 0.5)
			(thermal_bridge_width 0.5)
			(island_removal_mode 0)
		)
		(polygon
			(pts
				(arc
					(start 108.161328 -10.999978)
					(mid 107.599988 -10.438638)
					(end 107.038648 -10.999978)
				)
				(xy 107.038648 -11.485118) (xy 107.044236 -11.48461) (xy 107.044744 -11.484102)
				(arc
					(start 107.420664 -11.484102)
					(mid 107.495131 -11.456991)
					(end 107.53471 -11.388344)
				)
				(arc
					(start 107.53471 -11.388344)
					(mid 107.600886 -10.606165)
					(end 107.663488 -11.388598)
				)
				(xy 107.663488 -11.394694)
				(arc
					(start 107.661964 -11.396218)
					(mid 107.592429 -11.540043)
					(end 107.448604 -11.609578)
				)
				(xy 107.44708 -11.611102) (xy 107.07116 -11.611102) (xy 107.038648 -11.612372) (xy 107.038648 -11.79068)
				(xy 107.043474 -11.790172) (xy 107.044744 -11.788902) (xy 107.44708 -11.788902)
				(arc
					(start 107.448604 -11.790426)
					(mid 107.592429 -11.859961)
					(end 107.661964 -12.003786)
				)
				(xy 107.663488 -12.00531)
				(arc
					(start 107.663488 -12.011406)
					(mid 107.600886 -12.793799)
					(end 107.53471 -12.01166)
				)
				(arc
					(start 107.53471 -12.01166)
					(mid 107.495114 -11.943033)
					(end 107.420664 -11.915902)
				)
				(arc
					(start 107.07116 -11.915902)
					(mid 107.05481 -11.91682)
					(end 107.038648 -11.919458)
				)
				(arc
					(start 107.038648 -12.399772)
					(mid 107.599861 -12.961366)
					(end 108.161328 -12.400026)
				)
			)
		)
	)
	(zone
		(layer "In5.Cu")
		(hatch none 0.5)
		(connect_pads
			(clearance 0)
		)
		(min_thickness 0.25)
		(keepout
			(tracks not_allowed)
			(vias allowed)
			(pads allowed)
			(copperpour not_allowed)
			(footprints allowed)
		)
		(placement
			(enabled no)
			(sheetname "")
		)
		(fill
			(thermal_gap 0.5)
			(thermal_bridge_width 0.5)
			(island_removal_mode 0)
		)
		(polygon
			(pts
				(arc
					(start 129.00025 -64.641984)
					(mid 128.641856 -64.999997)
					(end 128.999996 -65.358264)
				)
				(arc
					(start 129.357628 -65.358264)
					(mid 129.351629 -65.32709)
					(end 129.34823 -65.295526)
				)
				(xy 129.347468 -65.294764)
				(arc
					(start 129.347468 -65.089024)
					(mid 129.338169 -65.066573)
					(end 129.315718 -65.057274)
				)
				(arc
					(start 129.234438 -65.057274)
					(mid 128.758689 -65.000124)
					(end 129.234438 -64.942974)
				)
				(xy 129.33934 -64.942974)
				(arc
					(start 129.341626 -64.94526)
					(mid 129.419012 -64.98573)
					(end 129.459482 -65.063116)
				)
				(xy 129.461768 -65.065402)
				(arc
					(start 129.461768 -65.271142)
					(mid 129.4654 -65.315301)
					(end 129.476246 -65.358264)
				)
				(arc
					(start 129.55905 -65.358264)
					(mid 129.54679 -65.328221)
					(end 129.539746 -65.296542)
				)
				(xy 129.537968 -65.294764) (xy 129.537968 -65.065402)
				(arc
					(start 129.540254 -65.063116)
					(mid 129.580724 -64.98573)
					(end 129.65811 -64.94526)
				)
				(xy 129.660396 -64.942974)
				(arc
					(start 129.765552 -64.942974)
					(mid 130.241301 -65.000124)
					(end 129.765552 -65.057274)
				)
				(arc
					(start 129.684018 -65.057274)
					(mid 129.661567 -65.066573)
					(end 129.652268 -65.089024)
				)
				(arc
					(start 129.652268 -65.271142)
					(mid 129.658141 -65.30058)
					(end 129.674874 -65.325498)
				)
				(arc
					(start 129.674874 -65.325498)
					(mid 129.69971 -65.34203)
					(end 129.728976 -65.34785)
				)
				(arc
					(start 130.085846 -65.34785)
					(mid 130.355542 -64.956882)
					(end 129.999994 -64.641984)
				)
			)
		)
	)
	(zone
		(layer "In5.Cu")
		(hatch none 0.5)
		(connect_pads
			(clearance 0)
		)
		(min_thickness 0.25)
		(keepout
			(tracks not_allowed)
			(vias allowed)
			(pads allowed)
			(copperpour not_allowed)
			(footprints allowed)
		)
		(placement
			(enabled no)
			(sheetname "")
		)
		(fill
			(thermal_gap 0.5)
			(thermal_bridge_width 0.5)
			(island_removal_mode 0)
		)
		(polygon
			(pts
				(arc
					(start 135.161528 -9.800082)
					(mid 134.600188 -9.238742)
					(end 134.038848 -9.800082)
				)
				(xy 134.038848 -10.285222) (xy 134.044436 -10.284714) (xy 134.044944 -10.284206)
				(arc
					(start 134.420864 -10.284206)
					(mid 134.495331 -10.257095)
					(end 134.53491 -10.188448)
				)
				(arc
					(start 134.53491 -10.188448)
					(mid 134.601086 -9.406269)
					(end 134.663688 -10.188702)
				)
				(xy 134.663688 -10.194798)
				(arc
					(start 134.662164 -10.196322)
					(mid 134.592629 -10.340147)
					(end 134.448804 -10.409682)
				)
				(xy 134.44728 -10.411206) (xy 134.07136 -10.411206) (xy 134.038848 -10.412476) (xy 134.038848 -10.590784)
				(xy 134.043674 -10.590276) (xy 134.044944 -10.589006) (xy 134.44728 -10.589006)
				(arc
					(start 134.448804 -10.59053)
					(mid 134.592629 -10.660065)
					(end 134.662164 -10.80389)
				)
				(xy 134.663688 -10.805414)
				(arc
					(start 134.663688 -10.81151)
					(mid 134.601086 -11.593903)
					(end 134.53491 -10.811764)
				)
				(arc
					(start 134.53491 -10.811764)
					(mid 134.495314 -10.743137)
					(end 134.420864 -10.716006)
				)
				(arc
					(start 134.07136 -10.716006)
					(mid 134.055009 -10.716922)
					(end 134.038848 -10.719562)
				)
				(arc
					(start 134.038848 -11.199876)
					(mid 134.600061 -11.76147)
					(end 135.161528 -11.20013)
				)
			)
		)
	)
	(zone
		(layer "In5.Cu")
		(hatch none 0.5)
		(connect_pads
			(clearance 0)
		)
		(min_thickness 0.25)
		(keepout
			(tracks not_allowed)
			(vias allowed)
			(pads allowed)
			(copperpour not_allowed)
			(footprints allowed)
		)
		(placement
			(enabled no)
			(sheetname "")
		)
		(fill
			(thermal_gap 0.5)
			(thermal_bridge_width 0.5)
			(island_removal_mode 0)
		)
		(polygon
			(pts
				(arc
					(start 144.16151 -10.999978)
					(mid 143.60017 -10.438638)
					(end 143.03883 -10.999978)
				)
				(xy 143.03883 -11.485118) (xy 143.044418 -11.48461) (xy 143.044926 -11.484102)
				(arc
					(start 143.420846 -11.484102)
					(mid 143.495313 -11.456991)
					(end 143.534892 -11.388344)
				)
				(arc
					(start 143.534892 -11.388344)
					(mid 143.601068 -10.606165)
					(end 143.66367 -11.388598)
				)
				(xy 143.66367 -11.394694)
				(arc
					(start 143.662146 -11.396218)
					(mid 143.592611 -11.540043)
					(end 143.448786 -11.609578)
				)
				(xy 143.447262 -11.611102) (xy 143.071342 -11.611102) (xy 143.03883 -11.612372) (xy 143.03883 -11.79068)
				(xy 143.043656 -11.790172) (xy 143.044926 -11.788902) (xy 143.447262 -11.788902)
				(arc
					(start 143.448786 -11.790426)
					(mid 143.592611 -11.859961)
					(end 143.662146 -12.003786)
				)
				(xy 143.66367 -12.00531)
				(arc
					(start 143.66367 -12.011406)
					(mid 143.601068 -12.793799)
					(end 143.534892 -12.01166)
				)
				(arc
					(start 143.534892 -12.01166)
					(mid 143.495296 -11.943033)
					(end 143.420846 -11.915902)
				)
				(arc
					(start 143.071342 -11.915902)
					(mid 143.054992 -11.91682)
					(end 143.03883 -11.919458)
				)
				(arc
					(start 143.03883 -12.399772)
					(mid 143.600043 -12.961366)
					(end 144.16151 -12.400026)
				)
			)
		)
	)
	(zone
		(layer "In5.Cu")
		(hatch none 0.5)
		(connect_pads
			(clearance 0)
		)
		(min_thickness 0.25)
		(keepout
			(tracks not_allowed)
			(vias allowed)
			(pads allowed)
			(copperpour not_allowed)
			(footprints allowed)
		)
		(placement
			(enabled no)
			(sheetname "")
		)
		(fill
			(thermal_gap 0.5)
			(thermal_bridge_width 0.5)
			(island_removal_mode 0)
		)
		(polygon
			(pts
				(xy 138.486134 -78.044294)
				(arc
					(start 138.486134 -78.045056)
					(mid 138.103356 -78.427834)
					(end 138.486134 -78.810612)
				)
				(xy 138.486134 -78.811374) (xy 138.841988 -78.811374) (xy 138.841734 -78.81112)
				(arc
					(start 138.841734 -78.59014)
					(mid 138.834277 -78.552383)
					(end 138.813032 -78.52029)
				)
				(arc
					(start 138.812778 -78.52029)
					(mid 138.781785 -78.499293)
					(end 138.745214 -78.491334)
				)
				(arc
					(start 138.745214 -78.491334)
					(mid 138.219386 -78.427834)
					(end 138.745214 -78.364334)
				)
				(xy 138.76909 -78.364334)
				(arc
					(start 138.770614 -78.366112)
					(mid 138.829209 -78.381458)
					(end 138.881612 -78.411832)
				)
				(xy 138.884152 -78.411832) (xy 138.92149 -78.44917)
				(arc
					(start 138.92149 -78.451964)
					(mid 138.951608 -78.504034)
					(end 138.966956 -78.5622)
				)
				(xy 138.968734 -78.563724) (xy 138.968734 -78.784704) (xy 138.969242 -78.811374) (xy 139.146788 -78.811374)
				(xy 139.146534 -78.81112) (xy 139.146534 -78.57871)
				(arc
					(start 139.148312 -78.577186)
					(mid 139.165022 -78.512988)
					(end 139.198604 -78.455774)
				)
				(xy 139.198604 -78.453488) (xy 139.216892 -78.4352) (xy 139.217146 -78.434946) (xy 139.239244 -78.412848)
				(xy 139.239752 -78.41234) (xy 139.257786 -78.394306)
				(arc
					(start 139.261342 -78.394306)
					(mid 139.292736 -78.376992)
					(end 139.327128 -78.366874)
				)
				(xy 139.329668 -78.364334)
				(arc
					(start 139.370054 -78.364334)
					(mid 139.895882 -78.427834)
					(end 139.370054 -78.491334)
				)
				(arc
					(start 139.356084 -78.491334)
					(mid 139.34167 -78.494166)
					(end 139.329414 -78.502256)
				)
				(xy 139.307062 -78.524862)
				(arc
					(start 139.306808 -78.525116)
					(mid 139.282222 -78.561823)
					(end 139.273534 -78.605126)
				)
				(xy 139.273534 -78.784704) (xy 139.274804 -78.811374) (xy 139.62888 -78.811374) (xy 139.629134 -78.81112)
				(arc
					(start 139.629134 -78.810612)
					(mid 140.011912 -78.427834)
					(end 139.629134 -78.045056)
				)
				(xy 139.629134 -78.044294)
			)
		)
	)
	(zone
		(layer "In5.Cu")
		(hatch none 0.5)
		(connect_pads
			(clearance 0)
		)
		(min_thickness 0.25)
		(keepout
			(tracks not_allowed)
			(vias allowed)
			(pads allowed)
			(copperpour not_allowed)
			(footprints allowed)
		)
		(placement
			(enabled no)
			(sheetname "")
		)
		(fill
			(thermal_gap 0.5)
			(thermal_bridge_width 0.5)
			(island_removal_mode 0)
		)
		(polygon
			(pts
				(arc
					(start 103.93807 -103.684832)
					(mid 103.734616 -103.011986)
					(end 103.06177 -103.21544)
				)
				(xy 103.061008 -103.215186)
				(arc
					(start 102.85984 -103.590598)
					(mid 102.943973 -103.735598)
					(end 103.051864 -103.863902)
				)
				(xy 103.051864 -103.864156) (xy 103.060754 -103.87076)
				(arc
					(start 103.137462 -103.911654)
					(mid 103.166378 -103.914406)
					(end 103.18877 -103.895906)
				)
				(arc
					(start 103.26624 -103.751126)
					(mid 103.679726 -103.114486)
					(end 103.378 -103.81107)
				)
				(arc
					(start 103.301038 -103.95585)
					(mid 103.216883 -104.031277)
					(end 103.103934 -104.034844)
				)
				(xy 103.100378 -104.03586) (xy 103.077772 -104.023668) (xy 103.077264 -104.023414) (xy 102.977696 -103.970328)
				(xy 102.97668 -103.966772)
				(arc
					(start 102.961948 -103.953818)
					(mid 102.867207 -103.845637)
					(end 102.78745 -103.72598)
				)
				(arc
					(start 102.69093 -103.906066)
					(mid 102.759599 -103.995902)
					(end 102.835964 -104.079294)
				)
				(arc
					(start 102.835964 -104.079294)
					(mid 102.874015 -104.112233)
					(end 102.916482 -104.139238)
				)
				(xy 102.916736 -104.139492) (xy 102.969822 -104.167686) (xy 102.99319 -104.180132) (xy 103.016304 -104.192578)
				(arc
					(start 103.01732 -104.196134)
					(mid 103.073349 -104.278035)
					(end 103.072184 -104.377236)
				)
				(xy 103.0732 -104.380792) (xy 103.061008 -104.403398) (xy 103.060754 -104.403906)
				(arc
					(start 102.983284 -104.548686)
					(mid 102.569798 -105.185326)
					(end 102.871524 -104.488742)
				)
				(arc
					(start 102.948994 -104.343708)
					(mid 102.951746 -104.314792)
					(end 102.933246 -104.2924)
				)
				(xy 102.933246 -104.292146) (xy 102.932992 -104.292146) (xy 102.909878 -104.279954) (xy 102.886764 -104.267508)
				(xy 102.856792 -104.251252) (xy 102.856538 -104.251252) (xy 102.833678 -104.238806)
				(arc
					(start 102.83317 -104.23779)
					(mid 102.787588 -104.206068)
					(end 102.746048 -104.16921)
				)
				(arc
					(start 102.746048 -104.16921)
					(mid 102.682926 -104.101746)
					(end 102.624382 -104.030272)
				)
				(xy 102.311454 -104.614726) (xy 102.311454 -104.61498)
				(arc
					(start 102.311962 -104.615234)
					(mid 102.515416 -105.28808)
					(end 103.188262 -105.084626)
				)
				(xy 103.189024 -105.08488) (xy 103.673656 -104.180132) (xy 103.6955 -104.139492) (xy 103.938832 -103.685086)
			)
		)
	)
	(zone
		(layer "In5.Cu")
		(hatch none 0.5)
		(connect_pads
			(clearance 0)
		)
		(min_thickness 0.25)
		(keepout
			(tracks not_allowed)
			(vias allowed)
			(pads allowed)
			(copperpour not_allowed)
			(footprints allowed)
		)
		(placement
			(enabled no)
			(sheetname "")
		)
		(fill
			(thermal_gap 0.5)
			(thermal_bridge_width 0.5)
			(island_removal_mode 0)
		)
		(polygon
			(pts
				(arc
					(start 129.00025 -69.641974)
					(mid 128.641856 -69.999987)
					(end 128.999996 -70.358254)
				)
				(arc
					(start 129.359914 -70.358254)
					(mid 129.352306 -70.321449)
					(end 129.34823 -70.284086)
				)
				(xy 129.347468 -70.283324)
				(arc
					(start 129.347468 -70.089014)
					(mid 129.338169 -70.066563)
					(end 129.315718 -70.057264)
				)
				(arc
					(start 129.234438 -70.057264)
					(mid 128.758689 -70.000114)
					(end 129.234438 -69.942964)
				)
				(xy 129.33934 -69.942964)
				(arc
					(start 129.341626 -69.94525)
					(mid 129.419012 -69.98572)
					(end 129.459482 -70.063106)
				)
				(xy 129.461768 -70.065392)
				(arc
					(start 129.461768 -70.259702)
					(mid 129.466312 -70.309797)
					(end 129.479802 -70.358254)
				)
				(arc
					(start 129.563622 -70.358254)
					(mid 129.548025 -70.322713)
					(end 129.539492 -70.284848)
				)
				(xy 129.537968 -70.283324) (xy 129.537968 -70.065392)
				(arc
					(start 129.540254 -70.063106)
					(mid 129.580724 -69.98572)
					(end 129.65811 -69.94525)
				)
				(xy 129.660396 -69.942964)
				(arc
					(start 129.765552 -69.942964)
					(mid 130.241301 -70.000114)
					(end 129.765552 -70.057264)
				)
				(arc
					(start 129.684018 -70.057264)
					(mid 129.661567 -70.066563)
					(end 129.652268 -70.089014)
				)
				(arc
					(start 129.652268 -70.259702)
					(mid 129.658938 -70.293237)
					(end 129.677922 -70.321678)
				)
				(arc
					(start 129.677922 -70.321678)
					(mid 129.706138 -70.340468)
					(end 129.73939 -70.347078)
				)
				(arc
					(start 130.08864 -70.347078)
					(mid 130.355306 -69.955442)
					(end 129.999994 -69.641974)
				)
			)
		)
	)
	(zone
		(layer "In5.Cu")
		(hatch none 0.5)
		(connect_pads
			(clearance 0)
		)
		(min_thickness 0.25)
		(keepout
			(tracks not_allowed)
			(vias allowed)
			(pads allowed)
			(copperpour not_allowed)
			(footprints allowed)
		)
		(placement
			(enabled no)
			(sheetname "")
		)
		(fill
			(thermal_gap 0.5)
			(thermal_bridge_width 0.5)
			(island_removal_mode 0)
		)
		(polygon
			(pts
				(arc
					(start 113.347246 -51.912266)
					(mid 112.955746 -51.64473)
					(end 112.641888 -52.00015)
				)
				(arc
					(start 112.641888 -52.999894)
					(mid 112.999901 -53.358288)
					(end 113.358168 -53.000148)
				)
				(arc
					(start 113.358168 -52.637182)
					(mid 113.315381 -52.646764)
					(end 113.271808 -52.65166)
				)
				(xy 113.271046 -52.652422)
				(arc
					(start 113.088928 -52.652422)
					(mid 113.066477 -52.661721)
					(end 113.057178 -52.684172)
				)
				(arc
					(start 113.057178 -52.765706)
					(mid 113.000028 -53.241455)
					(end 112.942878 -52.765706)
				)
				(xy 112.942878 -52.66055)
				(arc
					(start 112.945164 -52.658264)
					(mid 112.985634 -52.580878)
					(end 113.06302 -52.540408)
				)
				(xy 113.065306 -52.538122)
				(arc
					(start 113.247932 -52.538122)
					(mid 113.304117 -52.532583)
					(end 113.358168 -52.516278)
				)
				(arc
					(start 113.358168 -52.431188)
					(mid 113.316935 -52.45039)
					(end 113.27257 -52.460398)
				)
				(xy 113.271046 -52.461922) (xy 113.065306 -52.461922)
				(arc
					(start 113.06302 -52.459636)
					(mid 112.985634 -52.419166)
					(end 112.945164 -52.34178)
				)
				(xy 112.942878 -52.339494)
				(arc
					(start 112.942878 -52.234592)
					(mid 113.000028 -51.758843)
					(end 113.057178 -52.234592)
				)
				(arc
					(start 113.057178 -52.315872)
					(mid 113.066477 -52.338323)
					(end 113.088928 -52.347622)
				)
				(arc
					(start 113.247424 -52.347622)
					(mid 113.285638 -52.340039)
					(end 113.318036 -52.318412)
				)
				(arc
					(start 113.318036 -52.318412)
					(mid 113.339629 -52.286001)
					(end 113.347246 -52.2478)
				)
			)
		)
	)
	(zone
		(layer "In5.Cu")
		(hatch none 0.5)
		(connect_pads
			(clearance 0)
		)
		(min_thickness 0.25)
		(keepout
			(tracks not_allowed)
			(vias allowed)
			(pads allowed)
			(copperpour not_allowed)
			(footprints allowed)
		)
		(placement
			(enabled no)
			(sheetname "")
		)
		(fill
			(thermal_gap 0.5)
			(thermal_bridge_width 0.5)
			(island_removal_mode 0)
		)
		(polygon
			(pts
				(arc
					(start 140.561314 -10.999978)
					(mid 139.999974 -10.438638)
					(end 139.438634 -10.999978)
				)
				(xy 139.438634 -11.485118) (xy 139.444222 -11.48461) (xy 139.44473 -11.484102)
				(arc
					(start 139.82065 -11.484102)
					(mid 139.895117 -11.456991)
					(end 139.934696 -11.388344)
				)
				(arc
					(start 139.934696 -11.388344)
					(mid 140.000872 -10.606165)
					(end 140.063474 -11.388598)
				)
				(xy 140.063474 -11.394694)
				(arc
					(start 140.06195 -11.396218)
					(mid 139.992415 -11.540043)
					(end 139.84859 -11.609578)
				)
				(xy 139.847066 -11.611102) (xy 139.471146 -11.611102) (xy 139.438634 -11.612372) (xy 139.438634 -11.79068)
				(xy 139.44346 -11.790172) (xy 139.44473 -11.788902) (xy 139.847066 -11.788902)
				(arc
					(start 139.84859 -11.790426)
					(mid 139.992415 -11.859961)
					(end 140.06195 -12.003786)
				)
				(xy 140.063474 -12.00531)
				(arc
					(start 140.063474 -12.011406)
					(mid 140.000872 -12.793799)
					(end 139.934696 -12.01166)
				)
				(arc
					(start 139.934696 -12.01166)
					(mid 139.8951 -11.943033)
					(end 139.82065 -11.915902)
				)
				(arc
					(start 139.471146 -11.915902)
					(mid 139.454796 -11.91682)
					(end 139.438634 -11.919458)
				)
				(arc
					(start 139.438634 -12.399772)
					(mid 139.999847 -12.961366)
					(end 140.561314 -12.400026)
				)
			)
		)
	)
	(zone
		(layer "In5.Cu")
		(hatch none 0.5)
		(connect_pads
			(clearance 0)
		)
		(min_thickness 0.25)
		(keepout
			(tracks not_allowed)
			(vias allowed)
			(pads allowed)
			(copperpour not_allowed)
			(footprints allowed)
		)
		(placement
			(enabled no)
			(sheetname "")
		)
		(fill
			(thermal_gap 0.5)
			(thermal_bridge_width 0.5)
			(island_removal_mode 0)
		)
		(polygon
			(pts
				(arc
					(start 97.361502 -10.999978)
					(mid 96.800162 -10.438638)
					(end 96.238822 -10.999978)
				)
				(xy 96.238822 -11.485118) (xy 96.24441 -11.48461) (xy 96.244918 -11.484102)
				(arc
					(start 96.620838 -11.484102)
					(mid 96.695305 -11.456991)
					(end 96.734884 -11.388344)
				)
				(arc
					(start 96.734884 -11.388344)
					(mid 96.80106 -10.606165)
					(end 96.863662 -11.388598)
				)
				(xy 96.863662 -11.394694)
				(arc
					(start 96.862138 -11.396218)
					(mid 96.792603 -11.540043)
					(end 96.648778 -11.609578)
				)
				(xy 96.647254 -11.611102) (xy 96.271334 -11.611102) (xy 96.238822 -11.612372) (xy 96.238822 -11.79068)
				(xy 96.243648 -11.790172) (xy 96.244918 -11.788902) (xy 96.647254 -11.788902)
				(arc
					(start 96.648778 -11.790426)
					(mid 96.792603 -11.859961)
					(end 96.862138 -12.003786)
				)
				(xy 96.863662 -12.00531)
				(arc
					(start 96.863662 -12.011406)
					(mid 96.80106 -12.793799)
					(end 96.734884 -12.01166)
				)
				(arc
					(start 96.734884 -12.01166)
					(mid 96.695288 -11.943033)
					(end 96.620838 -11.915902)
				)
				(arc
					(start 96.271334 -11.915902)
					(mid 96.254984 -11.91682)
					(end 96.238822 -11.919458)
				)
				(arc
					(start 96.238822 -12.399772)
					(mid 96.800035 -12.961366)
					(end 97.361502 -12.400026)
				)
			)
		)
	)
	(zone
		(layer "In5.Cu")
		(hatch none 0.5)
		(connect_pads
			(clearance 0)
		)
		(min_thickness 0.25)
		(keepout
			(tracks not_allowed)
			(vias allowed)
			(pads allowed)
			(copperpour not_allowed)
			(footprints allowed)
		)
		(placement
			(enabled no)
			(sheetname "")
		)
		(fill
			(thermal_gap 0.5)
			(thermal_bridge_width 0.5)
			(island_removal_mode 0)
		)
		(polygon
			(pts
				(arc
					(start 123.358148 -51.000152)
					(mid 123.000008 -50.642012)
					(end 122.641868 -51.000152)
				)
				(arc
					(start 122.641868 -51.999896)
					(mid 122.999881 -52.35829)
					(end 123.358148 -52.00015)
				)
				(xy 123.358148 -51.652424)
				(arc
					(start 123.088908 -51.652424)
					(mid 123.066457 -51.661723)
					(end 123.057158 -51.684174)
				)
				(arc
					(start 123.057158 -51.765708)
					(mid 123.000008 -52.241457)
					(end 122.942858 -51.765708)
				)
				(xy 122.942858 -51.660552)
				(arc
					(start 122.945144 -51.658266)
					(mid 122.985614 -51.58088)
					(end 123.063 -51.54041)
				)
				(xy 123.065286 -51.538124) (xy 123.358148 -51.538124) (xy 123.358148 -51.461924) (xy 123.065286 -51.461924)
				(arc
					(start 123.063 -51.459638)
					(mid 122.985614 -51.419168)
					(end 122.945144 -51.341782)
				)
				(xy 122.942858 -51.339496)
				(arc
					(start 122.942858 -51.234594)
					(mid 123.000008 -50.758845)
					(end 123.057158 -51.234594)
				)
				(arc
					(start 123.057158 -51.315874)
					(mid 123.066457 -51.338325)
					(end 123.088908 -51.347624)
				)
				(xy 123.358148 -51.347624)
			)
		)
	)
	(zone
		(layer "In5.Cu")
		(hatch none 0.5)
		(connect_pads
			(clearance 0)
		)
		(min_thickness 0.25)
		(keepout
			(tracks not_allowed)
			(vias allowed)
			(pads allowed)
			(copperpour not_allowed)
			(footprints allowed)
		)
		(placement
			(enabled no)
			(sheetname "")
		)
		(fill
			(thermal_gap 0.5)
			(thermal_bridge_width 0.5)
			(island_removal_mode 0)
		)
		(polygon
			(pts
				(arc
					(start 113.561368 -9.800082)
					(mid 113.000028 -9.238742)
					(end 112.438688 -9.800082)
				)
				(xy 112.438688 -10.285222) (xy 112.444276 -10.284714) (xy 112.444784 -10.284206)
				(arc
					(start 112.820704 -10.284206)
					(mid 112.895171 -10.257095)
					(end 112.93475 -10.188448)
				)
				(arc
					(start 112.93475 -10.188448)
					(mid 113.000926 -9.406269)
					(end 113.063528 -10.188702)
				)
				(xy 113.063528 -10.194798)
				(arc
					(start 113.062004 -10.196322)
					(mid 112.992469 -10.340147)
					(end 112.848644 -10.409682)
				)
				(xy 112.84712 -10.411206) (xy 112.4712 -10.411206) (xy 112.438688 -10.412476) (xy 112.438688 -10.590784)
				(xy 112.443514 -10.590276) (xy 112.444784 -10.589006) (xy 112.84712 -10.589006)
				(arc
					(start 112.848644 -10.59053)
					(mid 112.992469 -10.660065)
					(end 113.062004 -10.80389)
				)
				(xy 113.063528 -10.805414)
				(arc
					(start 113.063528 -10.81151)
					(mid 113.000926 -11.593903)
					(end 112.93475 -10.811764)
				)
				(arc
					(start 112.93475 -10.811764)
					(mid 112.895154 -10.743137)
					(end 112.820704 -10.716006)
				)
				(arc
					(start 112.4712 -10.716006)
					(mid 112.45485 -10.716924)
					(end 112.438688 -10.719562)
				)
				(arc
					(start 112.438688 -11.199876)
					(mid 112.999901 -11.76147)
					(end 113.561368 -11.20013)
				)
			)
		)
	)
	(zone
		(layer "In5.Cu")
		(hatch none 0.5)
		(connect_pads
			(clearance 0)
		)
		(min_thickness 0.25)
		(keepout
			(tracks not_allowed)
			(vias allowed)
			(pads allowed)
			(copperpour not_allowed)
			(footprints allowed)
		)
		(placement
			(enabled no)
			(sheetname "")
		)
		(fill
			(thermal_gap 0.5)
			(thermal_bridge_width 0.5)
			(island_removal_mode 0)
		)
		(polygon
			(pts
				(arc
					(start 109.347254 -51.912266)
					(mid 108.955754 -51.64473)
					(end 108.641896 -52.00015)
				)
				(arc
					(start 108.641896 -52.999894)
					(mid 108.999909 -53.358288)
					(end 109.358176 -53.000148)
				)
				(xy 109.358176 -52.648612) (xy 109.33176 -52.65166) (xy 109.330744 -52.652422)
				(arc
					(start 109.088936 -52.652422)
					(mid 109.066485 -52.661721)
					(end 109.057186 -52.684172)
				)
				(arc
					(start 109.057186 -52.765706)
					(mid 109.000036 -53.241455)
					(end 108.942886 -52.765706)
				)
				(xy 108.942886 -52.66055)
				(arc
					(start 108.945172 -52.658264)
					(mid 108.985642 -52.580878)
					(end 109.063028 -52.540408)
				)
				(xy 109.065314 -52.538122)
				(arc
					(start 109.307122 -52.538122)
					(mid 109.332812 -52.536628)
					(end 109.358176 -52.53228)
				)
				(arc
					(start 109.358176 -52.453286)
					(mid 109.345736 -52.456984)
					(end 109.33303 -52.459636)
				)
				(xy 109.330744 -52.461922) (xy 109.065314 -52.461922)
				(arc
					(start 109.063028 -52.459636)
					(mid 108.985642 -52.419166)
					(end 108.945172 -52.34178)
				)
				(xy 108.942886 -52.339494)
				(arc
					(start 108.942886 -52.234592)
					(mid 109.000036 -51.758843)
					(end 109.057186 -52.234592)
				)
				(arc
					(start 109.057186 -52.315872)
					(mid 109.066485 -52.338323)
					(end 109.088936 -52.347622)
				)
				(arc
					(start 109.307122 -52.347622)
					(mid 109.322383 -52.344586)
					(end 109.335316 -52.335938)
				)
				(arc
					(start 109.335316 -52.335938)
					(mid 109.344169 -52.322784)
					(end 109.347254 -52.307236)
				)
			)
		)
	)
	(zone
		(layer "In5.Cu")
		(hatch none 0.5)
		(connect_pads
			(clearance 0)
		)
		(min_thickness 0.25)
		(keepout
			(tracks not_allowed)
			(vias allowed)
			(pads allowed)
			(copperpour not_allowed)
			(footprints allowed)
		)
		(placement
			(enabled no)
			(sheetname "")
		)
		(fill
			(thermal_gap 0.5)
			(thermal_bridge_width 0.5)
			(island_removal_mode 0)
		)
		(polygon
			(pts
				(arc
					(start 180.561234 -3.800094)
					(mid 179.999894 -3.238754)
					(end 179.438554 -3.800094)
				)
				(xy 179.438554 -4.252722)
				(arc
					(start 179.83327 -4.252722)
					(mid 179.886764 -4.233508)
					(end 179.91582 -4.18465)
				)
				(arc
					(start 179.91582 -4.18465)
					(mid 180.001697 -3.406348)
					(end 180.082444 -4.185158)
				)
				(xy 180.082444 -4.202938)
				(arc
					(start 180.07965 -4.205478)
					(mid 180.009423 -4.344801)
					(end 179.8701 -4.415028)
				)
				(xy 179.86756 -4.417822) (xy 179.438554 -4.417822) (xy 179.438554 -4.582922) (xy 179.867814 -4.582922)
				(arc
					(start 179.870354 -4.585716)
					(mid 180.009499 -4.655867)
					(end 180.07965 -4.795012)
				)
				(xy 180.082444 -4.797552)
				(arc
					(start 180.082444 -4.815078)
					(mid 180.001697 -5.593847)
					(end 179.91582 -4.815586)
				)
				(arc
					(start 179.91582 -4.815586)
					(mid 179.886784 -4.767032)
					(end 179.833524 -4.748022)
				)
				(xy 179.438554 -4.748022)
				(arc
					(start 179.438554 -5.199888)
					(mid 179.999767 -5.761482)
					(end 180.561234 -5.200142)
				)
			)
		)
	)
	(zone
		(layer "In5.Cu")
		(hatch none 0.5)
		(connect_pads
			(clearance 0)
		)
		(min_thickness 0.25)
		(keepout
			(tracks not_allowed)
			(vias allowed)
			(pads allowed)
			(copperpour not_allowed)
			(footprints allowed)
		)
		(placement
			(enabled no)
			(sheetname "")
		)
		(fill
			(thermal_gap 0.5)
			(thermal_bridge_width 0.5)
			(island_removal_mode 0)
		)
		(polygon
			(pts
				(arc
					(start 184.161176 -3.800094)
					(mid 183.599836 -3.238754)
					(end 183.038496 -3.800094)
				)
				(xy 183.038496 -4.255262) (xy 183.063388 -4.253484) (xy 183.06415 -4.252468)
				(arc
					(start 183.433212 -4.252468)
					(mid 183.48661 -4.233333)
					(end 183.515762 -4.18465)
				)
				(arc
					(start 183.515762 -4.18465)
					(mid 183.601639 -3.406348)
					(end 183.682386 -4.185158)
				)
				(xy 183.682386 -4.202684)
				(arc
					(start 183.679592 -4.205224)
					(mid 183.609365 -4.344547)
					(end 183.470042 -4.414774)
				)
				(xy 183.467502 -4.417568)
				(arc
					(start 183.09844 -4.417568)
					(mid 183.068409 -4.418538)
					(end 183.038496 -4.421378)
				)
				(xy 183.038496 -4.58851) (xy 183.062118 -4.5847) (xy 183.06415 -4.582668) (xy 183.467502 -4.582668)
				(arc
					(start 183.470042 -4.585462)
					(mid 183.609365 -4.655689)
					(end 183.679592 -4.795012)
				)
				(xy 183.682386 -4.797552)
				(arc
					(start 183.682386 -4.815078)
					(mid 183.601639 -5.593847)
					(end 183.515762 -4.815586)
				)
				(arc
					(start 183.515762 -4.815586)
					(mid 183.486649 -4.766856)
					(end 183.433212 -4.747768)
				)
				(arc
					(start 183.09844 -4.747768)
					(mid 183.067828 -4.750911)
					(end 183.038496 -4.760214)
				)
				(arc
					(start 183.038496 -5.199888)
					(mid 183.599709 -5.761482)
					(end 184.161176 -5.200142)
				)
			)
		)
	)
	(zone
		(layer "In5.Cu")
		(hatch none 0.5)
		(connect_pads
			(clearance 0)
		)
		(min_thickness 0.25)
		(keepout
			(tracks not_allowed)
			(vias allowed)
			(pads allowed)
			(copperpour not_allowed)
			(footprints allowed)
		)
		(placement
			(enabled no)
			(sheetname "")
		)
		(fill
			(thermal_gap 0.5)
			(thermal_bridge_width 0.5)
			(island_removal_mode 0)
		)
		(polygon
			(pts
				(arc
					(start 103.347266 -51.912266)
					(mid 102.955766 -51.64473)
					(end 102.641908 -52.00015)
				)
				(arc
					(start 102.641908 -52.999894)
					(mid 102.999921 -53.358288)
					(end 103.358188 -53.000148)
				)
				(arc
					(start 103.358188 -52.63896)
					(mid 103.319265 -52.647288)
					(end 103.279702 -52.65166)
				)
				(xy 103.27894 -52.652422) (xy 103.088694 -52.652422)
				(arc
					(start 103.082598 -52.65293)
					(mid 103.064397 -52.664062)
					(end 103.057198 -52.684172)
				)
				(arc
					(start 103.057198 -52.765706)
					(mid 103.000048 -53.241455)
					(end 102.942898 -52.765706)
				)
				(xy 102.942898 -52.66055)
				(arc
					(start 102.945184 -52.658264)
					(mid 102.984463 -52.582083)
					(end 103.059738 -52.54117)
				)
				(xy 103.059738 -52.540916) (xy 103.06304 -52.540408) (xy 103.065326 -52.538122)
				(arc
					(start 103.255826 -52.538122)
					(mid 103.307905 -52.533232)
					(end 103.358188 -52.518818)
				)
				(arc
					(start 103.358188 -52.43449)
					(mid 103.320629 -52.451357)
					(end 103.280464 -52.460398)
				)
				(xy 103.27894 -52.461922) (xy 103.065326 -52.461922) (xy 103.06304 -52.459636)
				(arc
					(start 103.054404 -52.457858)
					(mid 102.982549 -52.416035)
					(end 102.945184 -52.34178)
				)
				(xy 102.942898 -52.339494)
				(arc
					(start 102.942898 -52.234592)
					(mid 103.000048 -51.758843)
					(end 103.057198 -52.234592)
				)
				(arc
					(start 103.057198 -52.315872)
					(mid 103.063941 -52.335436)
					(end 103.081328 -52.346606)
				)
				(xy 103.088948 -52.347622)
				(arc
					(start 103.255318 -52.347622)
					(mid 103.290505 -52.340623)
					(end 103.320342 -52.320698)
				)
				(arc
					(start 103.320342 -52.320698)
					(mid 103.340276 -52.290865)
					(end 103.347266 -52.255674)
				)
			)
		)
	)
	(zone
		(layer "In5.Cu")
		(hatch none 0.5)
		(connect_pads
			(clearance 0)
		)
		(min_thickness 0.25)
		(keepout
			(tracks not_allowed)
			(vias allowed)
			(pads allowed)
			(copperpour not_allowed)
			(footprints allowed)
		)
		(placement
			(enabled no)
			(sheetname "")
		)
		(fill
			(thermal_gap 0.5)
			(thermal_bridge_width 0.5)
			(island_removal_mode 0)
		)
		(polygon
			(pts
				(arc
					(start 129.00025 -71.64197)
					(mid 128.641856 -71.999983)
					(end 128.999996 -72.35825)
				)
				(arc
					(start 129.356612 -72.35825)
					(mid 129.351315 -72.331243)
					(end 129.34823 -72.303894)
				)
				(xy 129.347468 -72.303132) (xy 129.347468 -72.281288) (xy 129.347468 -72.27951)
				(arc
					(start 129.347468 -72.08901)
					(mid 129.338169 -72.066559)
					(end 129.315718 -72.05726)
				)
				(arc
					(start 129.234438 -72.05726)
					(mid 128.758689 -72.00011)
					(end 129.234438 -71.94296)
				)
				(xy 129.33934 -71.94296)
				(arc
					(start 129.341626 -71.945246)
					(mid 129.419012 -71.985716)
					(end 129.459482 -72.063102)
				)
				(xy 129.461768 -72.065388)
				(arc
					(start 129.461768 -72.281034)
					(mid 129.465442 -72.320275)
					(end 129.475992 -72.35825)
				)
				(arc
					(start 129.560574 -72.35825)
					(mid 129.547843 -72.332954)
					(end 129.540254 -72.305672)
				)
				(xy 129.537968 -72.303386) (xy 129.537968 -72.280272) (xy 129.537968 -72.279764) (xy 129.537968 -72.065388)
				(arc
					(start 129.540254 -72.063102)
					(mid 129.580724 -71.985716)
					(end 129.65811 -71.945246)
				)
				(xy 129.660396 -71.94296)
				(arc
					(start 129.765552 -71.94296)
					(mid 130.241301 -72.00011)
					(end 129.765552 -72.05726)
				)
				(arc
					(start 129.684018 -72.05726)
					(mid 129.661567 -72.066559)
					(end 129.652268 -72.08901)
				)
				(arc
					(start 129.652268 -72.280272)
					(mid 129.654698 -72.292203)
					(end 129.661412 -72.30237)
				)
				(arc
					(start 129.680208 -72.320912)
					(mid 129.709115 -72.339702)
					(end 129.742946 -72.346312)
				)
				(arc
					(start 130.091688 -72.346312)
					(mid 130.355136 -71.953876)
					(end 129.999994 -71.64197)
				)
			)
		)
	)
	(zone
		(layer "In5.Cu")
		(hatch none 0.5)
		(connect_pads
			(clearance 0)
		)
		(min_thickness 0.25)
		(keepout
			(tracks not_allowed)
			(vias allowed)
			(pads allowed)
			(copperpour not_allowed)
			(footprints allowed)
		)
		(placement
			(enabled no)
			(sheetname "")
		)
		(fill
			(thermal_gap 0.5)
			(thermal_bridge_width 0.5)
			(island_removal_mode 0)
		)
		(polygon
			(pts
				(arc
					(start 120.347232 -51.912266)
					(mid 119.955732 -51.64473)
					(end 119.641874 -52.00015)
				)
				(arc
					(start 119.641874 -52.999894)
					(mid 119.999887 -53.358288)
					(end 120.358154 -53.000148)
				)
				(arc
					(start 120.358154 -52.643532)
					(mid 120.330241 -52.64866)
					(end 120.30202 -52.65166)
				)
				(xy 120.301258 -52.652422)
				(arc
					(start 120.088914 -52.652422)
					(mid 120.066463 -52.661721)
					(end 120.057164 -52.684172)
				)
				(arc
					(start 120.057164 -52.765706)
					(mid 120.000014 -53.241455)
					(end 119.942864 -52.765706)
				)
				(xy 119.942864 -52.66055)
				(arc
					(start 119.94515 -52.658264)
					(mid 119.98562 -52.580878)
					(end 120.063006 -52.540408)
				)
				(xy 120.065292 -52.538122)
				(arc
					(start 120.277636 -52.538122)
					(mid 120.318395 -52.534946)
					(end 120.358154 -52.525422)
				)
				(arc
					(start 120.358154 -52.44338)
					(mid 120.331255 -52.453929)
					(end 120.303036 -52.460144)
				)
				(xy 120.301258 -52.461922) (xy 120.065292 -52.461922)
				(arc
					(start 120.063006 -52.459636)
					(mid 119.98562 -52.419166)
					(end 119.94515 -52.34178)
				)
				(xy 119.942864 -52.339494)
				(arc
					(start 119.942864 -52.234592)
					(mid 120.000014 -51.758843)
					(end 120.057164 -52.234592)
				)
				(arc
					(start 120.057164 -52.315872)
					(mid 120.066463 -52.338323)
					(end 120.088914 -52.347622)
				)
				(arc
					(start 120.277636 -52.347622)
					(mid 120.304172 -52.342344)
					(end 120.326658 -52.327302)
				)
				(arc
					(start 120.326658 -52.327302)
					(mid 120.341896 -52.304592)
					(end 120.347232 -52.277772)
				)
			)
		)
	)
	(zone
		(layer "In5.Cu")
		(hatch none 0.5)
		(connect_pads
			(clearance 0)
		)
		(min_thickness 0.25)
		(keepout
			(tracks not_allowed)
			(vias allowed)
			(pads allowed)
			(copperpour not_allowed)
			(footprints allowed)
		)
		(placement
			(enabled no)
			(sheetname "")
		)
		(fill
			(thermal_gap 0.5)
			(thermal_bridge_width 0.5)
			(island_removal_mode 0)
		)
		(polygon
			(pts
				(xy 138.843512 -81.924906) (xy 138.843258 -81.92516)
				(arc
					(start 138.843258 -81.925668)
					(mid 138.46048 -82.308446)
					(end 138.843258 -82.691224)
				)
				(xy 138.843258 -82.691986) (xy 139.199112 -82.691986) (xy 139.198858 -82.691732)
				(arc
					(start 139.198858 -82.470752)
					(mid 139.191401 -82.432995)
					(end 139.170156 -82.400902)
				)
				(arc
					(start 139.169902 -82.400902)
					(mid 139.138909 -82.379905)
					(end 139.102338 -82.371946)
				)
				(arc
					(start 139.102338 -82.371946)
					(mid 138.57651 -82.308446)
					(end 139.102338 -82.244946)
				)
				(xy 139.126214 -82.244946)
				(arc
					(start 139.127738 -82.246724)
					(mid 139.186333 -82.26207)
					(end 139.238736 -82.292444)
				)
				(xy 139.241276 -82.292444) (xy 139.278614 -82.329782)
				(arc
					(start 139.278614 -82.332576)
					(mid 139.308732 -82.384646)
					(end 139.32408 -82.442812)
				)
				(xy 139.325858 -82.444336) (xy 139.325858 -82.665824) (xy 139.32662 -82.691986) (xy 139.503912 -82.691986)
				(xy 139.503658 -82.691732) (xy 139.503658 -82.459322)
				(arc
					(start 139.505436 -82.457798)
					(mid 139.522146 -82.3936)
					(end 139.555728 -82.336386)
				)
				(xy 139.555728 -82.3341) (xy 139.574016 -82.315812) (xy 139.57427 -82.315558) (xy 139.596368 -82.29346)
				(xy 139.596876 -82.292952) (xy 139.61491 -82.274918)
				(arc
					(start 139.618466 -82.274918)
					(mid 139.64986 -82.257604)
					(end 139.684252 -82.247486)
				)
				(xy 139.686792 -82.244946)
				(arc
					(start 139.727178 -82.244946)
					(mid 140.253006 -82.308446)
					(end 139.727178 -82.371946)
				)
				(arc
					(start 139.713208 -82.371946)
					(mid 139.698794 -82.374778)
					(end 139.686538 -82.382868)
				)
				(xy 139.664186 -82.405474)
				(arc
					(start 139.663932 -82.405728)
					(mid 139.639346 -82.442435)
					(end 139.630658 -82.485738)
				)
				(arc
					(start 139.630658 -82.665316)
					(mid 139.631265 -82.678697)
					(end 139.632944 -82.691986)
				)
				(xy 139.986258 -82.691986)
				(arc
					(start 139.986258 -82.691224)
					(mid 140.369036 -82.308446)
					(end 139.986258 -81.925668)
				)
				(xy 139.986258 -81.924906)
			)
		)
	)
	(zone
		(layer "In5.Cu")
		(hatch none 0.5)
		(connect_pads
			(clearance 0)
		)
		(min_thickness 0.25)
		(keepout
			(tracks not_allowed)
			(vias allowed)
			(pads allowed)
			(copperpour not_allowed)
			(footprints allowed)
		)
		(placement
			(enabled no)
			(sheetname "")
		)
		(fill
			(thermal_gap 0.5)
			(thermal_bridge_width 0.5)
			(island_removal_mode 0)
		)
		(polygon
			(pts
				(arc
					(start 172.65269 -23.112984)
					(mid 172.26915 -22.729444)
					(end 171.88561 -23.112984)
				)
				(arc
					(start 171.88561 -24.00173)
					(mid 172.269023 -24.385524)
					(end 172.65269 -24.001984)
				)
				(xy 172.65269 -23.805134)
				(arc
					(start 172.54855 -23.805134)
					(mid 172.5067 -23.809628)
					(end 172.466762 -23.822914)
				)
				(arc
					(start 172.466762 -23.822914)
					(mid 172.146381 -24.238721)
					(end 172.301662 -23.737316)
				)
				(arc
					(start 172.301662 -23.737316)
					(mid 172.399237 -23.672274)
					(end 172.512482 -23.641812)
				)
				(xy 172.51426 -23.640034) (xy 172.65269 -23.640034) (xy 172.65269 -23.474934) (xy 172.51426 -23.474934)
				(arc
					(start 172.512482 -23.473156)
					(mid 172.399224 -23.442721)
					(end 172.301662 -23.377652)
				)
				(arc
					(start 172.301662 -23.377652)
					(mid 172.14639 -22.876264)
					(end 172.466762 -23.292054)
				)
				(arc
					(start 172.466762 -23.292054)
					(mid 172.506702 -23.305331)
					(end 172.54855 -23.309834)
				)
				(xy 172.65269 -23.309834)
			)
		)
	)
	(zone
		(layer "In5.Cu")
		(hatch none 0.5)
		(connect_pads
			(clearance 0)
		)
		(min_thickness 0.25)
		(keepout
			(tracks not_allowed)
			(vias allowed)
			(pads allowed)
			(copperpour not_allowed)
			(footprints allowed)
		)
		(placement
			(enabled no)
			(sheetname "")
		)
		(fill
			(thermal_gap 0.5)
			(thermal_bridge_width 0.5)
			(island_removal_mode 0)
		)
		(polygon
			(pts
				(xy 138.500866 -79.813912) (xy 138.500612 -79.814166)
				(arc
					(start 138.500612 -79.814674)
					(mid 138.117834 -80.197452)
					(end 138.500612 -80.58023)
				)
				(xy 138.500612 -80.580992) (xy 138.856212 -80.580992)
				(arc
					(start 138.856212 -80.359758)
					(mid 138.848755 -80.322001)
					(end 138.82751 -80.289908)
				)
				(arc
					(start 138.827256 -80.289908)
					(mid 138.796263 -80.268911)
					(end 138.759692 -80.260952)
				)
				(arc
					(start 138.759692 -80.260952)
					(mid 138.233864 -80.197452)
					(end 138.759692 -80.133952)
				)
				(xy 138.783568 -80.133952)
				(arc
					(start 138.785092 -80.13573)
					(mid 138.843687 -80.151076)
					(end 138.89609 -80.18145)
				)
				(xy 138.89863 -80.18145) (xy 138.935968 -80.218788)
				(arc
					(start 138.935968 -80.221582)
					(mid 138.966086 -80.273652)
					(end 138.981434 -80.331818)
				)
				(xy 138.983212 -80.333342) (xy 138.983212 -80.580992) (xy 139.161012 -80.580992) (xy 139.161012 -80.348328)
				(arc
					(start 139.16279 -80.346804)
					(mid 139.1795 -80.282606)
					(end 139.213082 -80.225392)
				)
				(xy 139.213082 -80.223106) (xy 139.23137 -80.204818) (xy 139.231624 -80.204564) (xy 139.253722 -80.182466)
				(xy 139.25423 -80.181958) (xy 139.272264 -80.163924)
				(arc
					(start 139.27582 -80.163924)
					(mid 139.307214 -80.14661)
					(end 139.341606 -80.136492)
				)
				(xy 139.344146 -80.133952)
				(arc
					(start 139.384532 -80.133952)
					(mid 139.91036 -80.197452)
					(end 139.384532 -80.260952)
				)
				(arc
					(start 139.370562 -80.260952)
					(mid 139.356148 -80.263784)
					(end 139.343892 -80.271874)
				)
				(xy 139.32154 -80.29448)
				(arc
					(start 139.321286 -80.294734)
					(mid 139.2967 -80.331441)
					(end 139.288012 -80.374744)
				)
				(xy 139.288012 -80.580992) (xy 139.643612 -80.580992)
				(arc
					(start 139.643612 -80.58023)
					(mid 140.02639 -80.197452)
					(end 139.643612 -79.814674)
				)
				(xy 139.643612 -79.813912)
			)
		)
	)
	(zone
		(layer "In5.Cu")
		(hatch none 0.5)
		(connect_pads
			(clearance 0)
		)
		(min_thickness 0.25)
		(keepout
			(tracks not_allowed)
			(vias allowed)
			(pads allowed)
			(copperpour not_allowed)
			(footprints allowed)
		)
		(placement
			(enabled no)
			(sheetname "")
		)
		(fill
			(thermal_gap 0.5)
			(thermal_bridge_width 0.5)
			(island_removal_mode 0)
		)
		(polygon
			(pts
				(arc
					(start 105.227628 -107.769406)
					(mid 105.11019 -107.678056)
					(end 105.01884 -107.560618)
				)
				(arc
					(start 104.924352 -107.736894)
					(mid 105.034563 -107.850169)
					(end 105.165398 -107.938824)
				)
				(xy 105.198164 -107.95635) (xy 105.200196 -107.955842) (xy 105.20299 -107.95762) (xy 105.204768 -107.957366)
				(xy 105.20934 -107.960414) (xy 105.216452 -107.960414) (xy 105.228136 -107.972352) (xy 105.245916 -107.981242)
				(xy 105.24617 -107.982004) (xy 105.266236 -107.992418)
				(arc
					(start 105.267252 -107.995974)
					(mid 105.323525 -108.077946)
					(end 105.32237 -108.17733)
				)
				(xy 105.323386 -108.180886) (xy 105.311194 -108.203746) (xy 105.31094 -108.204)
				(arc
					(start 105.23347 -108.34878)
					(mid 104.820621 -108.985931)
					(end 105.121456 -108.288836)
				)
				(arc
					(start 105.19918 -108.143802)
					(mid 105.201965 -108.114993)
					(end 105.183686 -108.092494)
				)
				(xy 105.183178 -108.09224) (xy 105.182924 -108.09224) (xy 105.181146 -108.092748) (xy 105.180638 -108.09224)
				(xy 105.178606 -108.092494) (xy 105.170986 -108.087414) (xy 105.163366 -108.087414) (xy 105.152444 -108.076238)
				(xy 105.140252 -108.070142) (xy 105.139744 -108.069126) (xy 105.10774 -108.051854) (xy 105.1052 -108.050584)
				(xy 105.084626 -108.039408)
				(arc
					(start 105.084372 -108.0389)
					(mid 104.964819 -107.957103)
					(end 104.859836 -107.85729)
				)
				(xy 104.561386 -108.41482) (xy 104.561386 -108.415074)
				(arc
					(start 104.561894 -108.415328)
					(mid 104.765348 -109.088174)
					(end 105.438194 -108.88472)
				)
				(xy 105.438956 -108.885228) (xy 106.189018 -107.48518)
				(arc
					(start 106.188256 -107.484672)
					(mid 105.984802 -106.811826)
					(end 105.311956 -107.01528)
				)
				(xy 105.311194 -107.014772)
				(arc
					(start 105.092754 -107.42295)
					(mid 105.179525 -107.56654)
					(end 105.31094 -107.670854)
				)
				(xy 105.343706 -107.688126) (xy 105.347262 -107.687618) (xy 105.366312 -107.700318) (xy 105.36682 -107.700572)
				(xy 105.387394 -107.710986)
				(arc
					(start 105.387902 -107.712002)
					(mid 105.416652 -107.714585)
					(end 105.438956 -107.696254)
				)
				(arc
					(start 105.51668 -107.55122)
					(mid 105.929529 -106.914069)
					(end 105.628694 -107.611164)
				)
				(xy 105.55097 -107.755944) (xy 105.55097 -107.756452) (xy 105.538524 -107.779058)
				(arc
					(start 105.535222 -107.780074)
					(mid 105.453321 -107.836103)
					(end 105.35412 -107.834938)
				)
				(xy 105.350564 -107.835954) (xy 105.327958 -107.823762) (xy 105.32745 -107.823508) (xy 105.324656 -107.822238)
				(xy 105.3211 -107.822746) (xy 105.302558 -107.810554) (xy 105.282746 -107.800394) (xy 105.282238 -107.799378)
				(xy 105.250996 -107.782868) (xy 105.227882 -107.770422)
			)
		)
	)
	(zone
		(layer "In5.Cu")
		(hatch none 0.5)
		(connect_pads
			(clearance 0)
		)
		(min_thickness 0.25)
		(keepout
			(tracks not_allowed)
			(vias allowed)
			(pads allowed)
			(copperpour not_allowed)
			(footprints allowed)
		)
		(placement
			(enabled no)
			(sheetname "")
		)
		(fill
			(thermal_gap 0.5)
			(thermal_bridge_width 0.5)
			(island_removal_mode 0)
		)
		(polygon
			(pts
				(arc
					(start 111.761524 -10.999978)
					(mid 111.200184 -10.438638)
					(end 110.638844 -10.999978)
				)
				(xy 110.638844 -11.485118) (xy 110.644432 -11.48461) (xy 110.64494 -11.484102)
				(arc
					(start 111.02086 -11.484102)
					(mid 111.095327 -11.456991)
					(end 111.134906 -11.388344)
				)
				(arc
					(start 111.134906 -11.388344)
					(mid 111.201082 -10.606165)
					(end 111.263684 -11.388598)
				)
				(xy 111.263684 -11.394694)
				(arc
					(start 111.26216 -11.396218)
					(mid 111.192625 -11.540043)
					(end 111.0488 -11.609578)
				)
				(xy 111.047276 -11.611102) (xy 110.671356 -11.611102) (xy 110.638844 -11.612372) (xy 110.638844 -11.79068)
				(xy 110.64367 -11.790172) (xy 110.64494 -11.788902) (xy 111.047276 -11.788902)
				(arc
					(start 111.0488 -11.790426)
					(mid 111.192625 -11.859961)
					(end 111.26216 -12.003786)
				)
				(xy 111.263684 -12.00531)
				(arc
					(start 111.263684 -12.011406)
					(mid 111.201082 -12.793799)
					(end 111.134906 -12.01166)
				)
				(arc
					(start 111.134906 -12.01166)
					(mid 111.09531 -11.943033)
					(end 111.02086 -11.915902)
				)
				(arc
					(start 110.671356 -11.915902)
					(mid 110.655006 -11.91682)
					(end 110.638844 -11.919458)
				)
				(arc
					(start 110.638844 -12.399772)
					(mid 111.200057 -12.961366)
					(end 111.761524 -12.400026)
				)
			)
		)
	)
	(zone
		(layer "In5.Cu")
		(hatch none 0.5)
		(connect_pads
			(clearance 0)
		)
		(min_thickness 0.25)
		(keepout
			(tracks not_allowed)
			(vias allowed)
			(pads allowed)
			(copperpour not_allowed)
			(footprints allowed)
		)
		(placement
			(enabled no)
			(sheetname "")
		)
		(fill
			(thermal_gap 0.5)
			(thermal_bridge_width 0.5)
			(island_removal_mode 0)
		)
		(polygon
			(pts
				(arc
					(start 145.961354 -9.800082)
					(mid 145.400014 -9.238742)
					(end 144.838674 -9.800082)
				)
				(xy 144.838674 -10.285222) (xy 144.844262 -10.284714) (xy 144.84477 -10.284206)
				(arc
					(start 145.22069 -10.284206)
					(mid 145.295157 -10.257095)
					(end 145.334736 -10.188448)
				)
				(arc
					(start 145.334736 -10.188448)
					(mid 145.400912 -9.406269)
					(end 145.463514 -10.188702)
				)
				(xy 145.463514 -10.194798)
				(arc
					(start 145.46199 -10.196322)
					(mid 145.392455 -10.340147)
					(end 145.24863 -10.409682)
				)
				(xy 145.247106 -10.411206) (xy 144.871186 -10.411206) (xy 144.838674 -10.412476) (xy 144.838674 -10.590784)
				(xy 144.8435 -10.590276) (xy 144.84477 -10.589006) (xy 145.247106 -10.589006)
				(arc
					(start 145.24863 -10.59053)
					(mid 145.392455 -10.660065)
					(end 145.46199 -10.80389)
				)
				(xy 145.463514 -10.805414)
				(arc
					(start 145.463514 -10.81151)
					(mid 145.400912 -11.593903)
					(end 145.334736 -10.811764)
				)
				(arc
					(start 145.334736 -10.811764)
					(mid 145.29514 -10.743137)
					(end 145.22069 -10.716006)
				)
				(arc
					(start 144.871186 -10.716006)
					(mid 144.854836 -10.716924)
					(end 144.838674 -10.719562)
				)
				(arc
					(start 144.838674 -11.199876)
					(mid 145.399887 -11.76147)
					(end 145.961354 -11.20013)
				)
			)
		)
	)
	(zone
		(layer "In5.Cu")
		(hatch none 0.5)
		(connect_pads
			(clearance 0)
		)
		(min_thickness 0.25)
		(keepout
			(tracks not_allowed)
			(vias allowed)
			(pads allowed)
			(copperpour not_allowed)
			(footprints allowed)
		)
		(placement
			(enabled no)
			(sheetname "")
		)
		(fill
			(thermal_gap 0.5)
			(thermal_bridge_width 0.5)
			(island_removal_mode 0)
		)
		(polygon
			(pts
				(arc
					(start 178.790854 -23.11654)
					(mid 178.407314 -22.733)
					(end 178.023774 -23.11654)
				)
				(arc
					(start 178.023774 -24.005286)
					(mid 178.407187 -24.38908)
					(end 178.790854 -24.00554)
				)
				(xy 178.790854 -23.80869)
				(arc
					(start 178.686714 -23.80869)
					(mid 178.644864 -23.813184)
					(end 178.604926 -23.82647)
				)
				(arc
					(start 178.604926 -23.82647)
					(mid 178.284545 -24.242277)
					(end 178.439826 -23.740872)
				)
				(arc
					(start 178.439826 -23.740872)
					(mid 178.537401 -23.67583)
					(end 178.650646 -23.645368)
				)
				(xy 178.652424 -23.64359) (xy 178.790854 -23.64359) (xy 178.790854 -23.47849) (xy 178.652424 -23.47849)
				(arc
					(start 178.650646 -23.476712)
					(mid 178.537388 -23.446277)
					(end 178.439826 -23.381208)
				)
				(arc
					(start 178.439826 -23.381208)
					(mid 178.284554 -22.87982)
					(end 178.604926 -23.29561)
				)
				(arc
					(start 178.604926 -23.29561)
					(mid 178.644866 -23.308887)
					(end 178.686714 -23.31339)
				)
				(xy 178.790854 -23.31339)
			)
		)
	)
	(zone
		(layer "In5.Cu")
		(hatch none 0.5)
		(connect_pads
			(clearance 0)
		)
		(min_thickness 0.25)
		(keepout
			(tracks not_allowed)
			(vias allowed)
			(pads allowed)
			(copperpour not_allowed)
			(footprints allowed)
		)
		(placement
			(enabled no)
			(sheetname "")
		)
		(fill
			(thermal_gap 0.5)
			(thermal_bridge_width 0.5)
			(island_removal_mode 0)
		)
		(polygon
			(pts
				(arc
					(start 124.361448 -9.800082)
					(mid 123.800108 -9.238742)
					(end 123.238768 -9.800082)
				)
				(xy 123.238768 -10.285222) (xy 123.244356 -10.284714) (xy 123.244864 -10.284206)
				(arc
					(start 123.620784 -10.284206)
					(mid 123.695251 -10.257095)
					(end 123.73483 -10.188448)
				)
				(arc
					(start 123.73483 -10.188448)
					(mid 123.801006 -9.406269)
					(end 123.863608 -10.188702)
				)
				(xy 123.863608 -10.194798)
				(arc
					(start 123.862084 -10.196322)
					(mid 123.792549 -10.340147)
					(end 123.648724 -10.409682)
				)
				(xy 123.6472 -10.411206) (xy 123.27128 -10.411206) (xy 123.238768 -10.412476) (xy 123.238768 -10.590784)
				(xy 123.243594 -10.590276) (xy 123.244864 -10.589006) (xy 123.6472 -10.589006)
				(arc
					(start 123.648724 -10.59053)
					(mid 123.792549 -10.660065)
					(end 123.862084 -10.80389)
				)
				(xy 123.863608 -10.805414)
				(arc
					(start 123.863608 -10.81151)
					(mid 123.801006 -11.593903)
					(end 123.73483 -10.811764)
				)
				(arc
					(start 123.73483 -10.811764)
					(mid 123.695234 -10.743137)
					(end 123.620784 -10.716006)
				)
				(arc
					(start 123.27128 -10.716006)
					(mid 123.254929 -10.716922)
					(end 123.238768 -10.719562)
				)
				(arc
					(start 123.238768 -11.199876)
					(mid 123.799981 -11.76147)
					(end 124.361448 -11.20013)
				)
			)
		)
	)
	(zone
		(layer "In5.Cu")
		(hatch none 0.5)
		(connect_pads
			(clearance 0)
		)
		(min_thickness 0.25)
		(keepout
			(tracks not_allowed)
			(vias allowed)
			(pads allowed)
			(copperpour not_allowed)
			(footprints allowed)
		)
		(placement
			(enabled no)
			(sheetname "")
		)
		(fill
			(thermal_gap 0.5)
			(thermal_bridge_width 0.5)
			(island_removal_mode 0)
		)
		(polygon
			(pts
				(arc
					(start 170.600624 -23.11527)
					(mid 170.217084 -22.73173)
					(end 169.833544 -23.11527)
				)
				(arc
					(start 169.833544 -24.004016)
					(mid 170.216957 -24.38781)
					(end 170.600624 -24.00427)
				)
				(xy 170.600624 -23.80742)
				(arc
					(start 170.496484 -23.80742)
					(mid 170.454634 -23.811914)
					(end 170.414696 -23.8252)
				)
				(arc
					(start 170.414696 -23.8252)
					(mid 170.094315 -24.241007)
					(end 170.249596 -23.739602)
				)
				(arc
					(start 170.249596 -23.739602)
					(mid 170.347171 -23.67456)
					(end 170.460416 -23.644098)
				)
				(xy 170.462194 -23.64232) (xy 170.600624 -23.64232) (xy 170.600624 -23.47722) (xy 170.462194 -23.47722)
				(arc
					(start 170.460416 -23.475442)
					(mid 170.347158 -23.445007)
					(end 170.249596 -23.379938)
				)
				(arc
					(start 170.249596 -23.379938)
					(mid 170.094324 -22.87855)
					(end 170.414696 -23.29434)
				)
				(arc
					(start 170.414696 -23.29434)
					(mid 170.454636 -23.307617)
					(end 170.496484 -23.31212)
				)
				(xy 170.600624 -23.31212)
			)
		)
	)
	(zone
		(layer "In5.Cu")
		(hatch none 0.5)
		(connect_pads
			(clearance 0)
		)
		(min_thickness 0.25)
		(keepout
			(tracks not_allowed)
			(vias allowed)
			(pads allowed)
			(copperpour not_allowed)
			(footprints allowed)
		)
		(placement
			(enabled no)
			(sheetname "")
		)
		(fill
			(thermal_gap 0.5)
			(thermal_bridge_width 0.5)
			(island_removal_mode 0)
		)
		(polygon
			(pts
				(arc
					(start 182.361332 -2.600198)
					(mid 181.799992 -2.038858)
					(end 181.238652 -2.600198)
				)
				(arc
					(start 181.238652 -3.061462)
					(mid 181.276387 -3.056359)
					(end 181.314344 -3.053334)
				)
				(xy 181.315106 -3.052572)
				(arc
					(start 181.633368 -3.052572)
					(mid 181.686766 -3.033437)
					(end 181.715918 -2.984754)
				)
				(arc
					(start 181.715918 -2.984754)
					(mid 181.801795 -2.206452)
					(end 181.882542 -2.985262)
				)
				(xy 181.882542 -3.002788)
				(arc
					(start 181.879748 -3.005328)
					(mid 181.809521 -3.144651)
					(end 181.670198 -3.214878)
				)
				(xy 181.667658 -3.217672)
				(arc
					(start 181.349396 -3.217672)
					(mid 181.293719 -3.220619)
					(end 181.238652 -3.229356)
				)
				(arc
					(start 181.238652 -3.39979)
					(mid 181.275595 -3.390235)
					(end 181.313328 -3.38455)
				)
				(xy 181.315106 -3.382772) (xy 181.667912 -3.382772)
				(arc
					(start 181.670452 -3.385566)
					(mid 181.809597 -3.455717)
					(end 181.879748 -3.594862)
				)
				(xy 181.882542 -3.597402)
				(arc
					(start 181.882542 -3.614928)
					(mid 181.801795 -4.393697)
					(end 181.715918 -3.615436)
				)
				(arc
					(start 181.715918 -3.615436)
					(mid 181.686882 -3.566882)
					(end 181.633622 -3.547872)
				)
				(arc
					(start 181.349396 -3.547872)
					(mid 181.291616 -3.556304)
					(end 181.238652 -3.580892)
				)
				(arc
					(start 181.238652 -3.999738)
					(mid 181.799865 -4.561332)
					(end 182.361332 -3.999992)
				)
			)
		)
	)
	(zone
		(net "SAS0_VDDH")
		(layer "In5.Cu")
		(hatch none 0.5)
		(connect_pads
			(clearance 0.5)
		)
		(min_thickness 0.25)
		(fill yes
			(thermal_gap 0.5)
			(thermal_bridge_width 0.5)
			(island_removal_mode 0)
		)
		(polygon
			(pts
				(xy 166.6748 -33.2994) (xy 167.386 -33.2994) (xy 169.418 -35.3314) (xy 169.418 -36.5252) (xy 169.915586 -37.022786)
				(xy 169.915586 -41.006014) (xy 167.951404 -42.970196) (xy 163.289996 -42.970196) (xy 161.2646 -40.9448)
				(xy 161.2646 -27.94) (xy 161.6329 -27.5717) (xy 163.9443 -27.5717) (xy 164.1856 -27.813) (xy 164.1856 -38.9128)
				(xy 163.3982 -39.7002) (xy 163.3982 -40.1574) (xy 163.6522 -40.4114) (xy 166.116 -40.4114) (xy 166.431468 -40.4114)
				(xy 167.30726 -39.535608) (xy 167.333168 -39.5097) (xy 167.39362 -39.449248) (xy 167.39362 -38.18382)
				(xy 166.5986 -37.3888) (xy 166.5986 -33.3756)
			)
		)
	)
	(zone
		(layer "In5.Cu")
		(hatch none 0.5)
		(connect_pads
			(clearance 0)
		)
		(min_thickness 0.25)
		(keepout
			(tracks not_allowed)
			(vias allowed)
			(pads allowed)
			(copperpour not_allowed)
			(footprints allowed)
		)
		(placement
			(enabled no)
			(sheetname "")
		)
		(fill
			(thermal_gap 0.5)
			(thermal_bridge_width 0.5)
			(island_removal_mode 0)
		)
		(polygon
			(pts
				(arc
					(start 93.761306 -10.999978)
					(mid 93.199966 -10.438638)
					(end 92.638626 -10.999978)
				)
				(xy 92.638626 -11.485118) (xy 92.644214 -11.48461) (xy 92.644722 -11.484102)
				(arc
					(start 93.020642 -11.484102)
					(mid 93.095109 -11.456991)
					(end 93.134688 -11.388344)
				)
				(arc
					(start 93.134688 -11.388344)
					(mid 93.200864 -10.606165)
					(end 93.263466 -11.388598)
				)
				(xy 93.263466 -11.394694)
				(arc
					(start 93.261942 -11.396218)
					(mid 93.192407 -11.540043)
					(end 93.048582 -11.609578)
				)
				(xy 93.047058 -11.611102) (xy 92.671138 -11.611102) (xy 92.638626 -11.612372) (xy 92.638626 -11.79068)
				(xy 92.643452 -11.790172) (xy 92.644722 -11.788902) (xy 93.047058 -11.788902)
				(arc
					(start 93.048582 -11.790426)
					(mid 93.192407 -11.859961)
					(end 93.261942 -12.003786)
				)
				(xy 93.263466 -12.00531)
				(arc
					(start 93.263466 -12.011406)
					(mid 93.200864 -12.793799)
					(end 93.134688 -12.01166)
				)
				(arc
					(start 93.134688 -12.01166)
					(mid 93.095092 -11.943033)
					(end 93.020642 -11.915902)
				)
				(arc
					(start 92.671138 -11.915902)
					(mid 92.654788 -11.91682)
					(end 92.638626 -11.919458)
				)
				(arc
					(start 92.638626 -12.399772)
					(mid 93.199839 -12.961366)
					(end 93.761306 -12.400026)
				)
			)
		)
	)
	(zone
		(layer "In5.Cu")
		(hatch none 0.5)
		(connect_pads
			(clearance 0)
		)
		(min_thickness 0.25)
		(keepout
			(tracks not_allowed)
			(vias allowed)
			(pads allowed)
			(copperpour not_allowed)
			(footprints allowed)
		)
		(placement
			(enabled no)
			(sheetname "")
		)
		(fill
			(thermal_gap 0.5)
			(thermal_bridge_width 0.5)
			(island_removal_mode 0)
		)
		(polygon
			(pts
				(arc
					(start 118.961408 -10.999978)
					(mid 118.400068 -10.438638)
					(end 117.838728 -10.999978)
				)
				(xy 117.838728 -11.485118) (xy 117.844316 -11.48461) (xy 117.844824 -11.484102)
				(arc
					(start 118.220744 -11.484102)
					(mid 118.295211 -11.456991)
					(end 118.33479 -11.388344)
				)
				(arc
					(start 118.33479 -11.388344)
					(mid 118.400966 -10.606165)
					(end 118.463568 -11.388598)
				)
				(xy 118.463568 -11.394694)
				(arc
					(start 118.462044 -11.396218)
					(mid 118.392509 -11.540043)
					(end 118.248684 -11.609578)
				)
				(xy 118.24716 -11.611102) (xy 117.87124 -11.611102) (xy 117.838728 -11.612372) (xy 117.838728 -11.79068)
				(xy 117.843554 -11.790172) (xy 117.844824 -11.788902) (xy 118.24716 -11.788902)
				(arc
					(start 118.248684 -11.790426)
					(mid 118.392509 -11.859961)
					(end 118.462044 -12.003786)
				)
				(xy 118.463568 -12.00531)
				(arc
					(start 118.463568 -12.011406)
					(mid 118.400966 -12.793799)
					(end 118.33479 -12.01166)
				)
				(arc
					(start 118.33479 -12.01166)
					(mid 118.295194 -11.943033)
					(end 118.220744 -11.915902)
				)
				(arc
					(start 117.87124 -11.915902)
					(mid 117.85489 -11.91682)
					(end 117.838728 -11.919458)
				)
				(arc
					(start 117.838728 -12.399772)
					(mid 118.399941 -12.961366)
					(end 118.961408 -12.400026)
				)
			)
		)
	)
	(zone
		(layer "In5.Cu")
		(hatch none 0.5)
		(connect_pads
			(clearance 0)
		)
		(min_thickness 0.25)
		(keepout
			(tracks not_allowed)
			(vias allowed)
			(pads allowed)
			(copperpour not_allowed)
			(footprints allowed)
		)
		(placement
			(enabled no)
			(sheetname "")
		)
		(fill
			(thermal_gap 0.5)
			(thermal_bridge_width 0.5)
			(island_removal_mode 0)
		)
		(polygon
			(pts
				(arc
					(start 130.000248 -72.641968)
					(mid 129.641854 -72.999981)
					(end 129.999994 -73.358248)
				)
				(xy 130.347466 -73.358248)
				(arc
					(start 130.347466 -73.089008)
					(mid 130.338167 -73.066557)
					(end 130.315716 -73.057258)
				)
				(arc
					(start 130.234436 -73.057258)
					(mid 129.758687 -73.000108)
					(end 130.234436 -72.942958)
				)
				(xy 130.339338 -72.942958)
				(arc
					(start 130.341624 -72.945244)
					(mid 130.41901 -72.985714)
					(end 130.45948 -73.0631)
				)
				(xy 130.461766 -73.065386) (xy 130.461766 -73.358248) (xy 130.537966 -73.358248) (xy 130.537966 -73.065386)
				(arc
					(start 130.540252 -73.0631)
					(mid 130.580722 -72.985714)
					(end 130.658108 -72.945244)
				)
				(xy 130.660394 -72.942958)
				(arc
					(start 130.76555 -72.942958)
					(mid 131.241299 -73.000108)
					(end 130.76555 -73.057258)
				)
				(arc
					(start 130.684016 -73.057258)
					(mid 130.661565 -73.066557)
					(end 130.652266 -73.089008)
				)
				(xy 130.652266 -73.358248)
				(arc
					(start 130.999992 -73.358248)
					(mid 131.358132 -73.000108)
					(end 130.999992 -72.641968)
				)
			)
		)
	)
	(zone
		(layer "In5.Cu")
		(hatch none 0.5)
		(connect_pads
			(clearance 0)
		)
		(min_thickness 0.25)
		(keepout
			(tracks not_allowed)
			(vias allowed)
			(pads allowed)
			(copperpour not_allowed)
			(footprints allowed)
		)
		(placement
			(enabled no)
			(sheetname "")
		)
		(fill
			(thermal_gap 0.5)
			(thermal_bridge_width 0.5)
			(island_removal_mode 0)
		)
		(polygon
			(pts
				(arc
					(start 118.347236 -51.912266)
					(mid 117.955736 -51.64473)
					(end 117.641878 -52.00015)
				)
				(arc
					(start 117.641878 -52.999894)
					(mid 117.999891 -53.358288)
					(end 118.358158 -53.000148)
				)
				(arc
					(start 118.358158 -52.645818)
					(mid 118.335897 -52.649436)
					(end 118.313454 -52.65166)
				)
				(xy 118.312692 -52.652422)
				(arc
					(start 118.088918 -52.652422)
					(mid 118.066467 -52.661721)
					(end 118.057168 -52.684172)
				)
				(arc
					(start 118.057168 -52.765706)
					(mid 118.000018 -53.241455)
					(end 117.942868 -52.765706)
				)
				(xy 117.942868 -52.66055)
				(arc
					(start 117.945154 -52.658264)
					(mid 117.985624 -52.580878)
					(end 118.06301 -52.540408)
				)
				(xy 118.065296 -52.538122)
				(arc
					(start 118.289578 -52.538122)
					(mid 118.324206 -52.535699)
					(end 118.358158 -52.52847)
				)
				(arc
					(start 118.358158 -52.447444)
					(mid 118.336852 -52.455104)
					(end 118.314724 -52.45989)
				)
				(xy 118.312692 -52.461922) (xy 118.065296 -52.461922)
				(arc
					(start 118.06301 -52.459636)
					(mid 117.985624 -52.419166)
					(end 117.945154 -52.34178)
				)
				(xy 117.942868 -52.339494)
				(arc
					(start 117.942868 -52.234592)
					(mid 118.000018 -51.758843)
					(end 118.057168 -52.234592)
				)
				(arc
					(start 118.057168 -52.315872)
					(mid 118.066467 -52.338323)
					(end 118.088918 -52.347622)
				)
				(arc
					(start 118.28907 -52.347622)
					(mid 118.311329 -52.343194)
					(end 118.330218 -52.330604)
				)
				(arc
					(start 118.330218 -52.330604)
					(mid 118.342832 -52.311725)
					(end 118.347236 -52.289456)
				)
			)
		)
	)
	(zone
		(layer "In5.Cu")
		(hatch none 0.5)
		(connect_pads
			(clearance 0)
		)
		(min_thickness 0.25)
		(keepout
			(tracks not_allowed)
			(vias allowed)
			(pads allowed)
			(copperpour not_allowed)
			(footprints allowed)
		)
		(placement
			(enabled no)
			(sheetname "")
		)
		(fill
			(thermal_gap 0.5)
			(thermal_bridge_width 0.5)
			(island_removal_mode 0)
		)
		(polygon
			(pts
				(arc
					(start 100.961444 -10.999978)
					(mid 100.400104 -10.438638)
					(end 99.838764 -10.999978)
				)
				(xy 99.838764 -11.485118) (xy 99.844352 -11.48461) (xy 99.84486 -11.484102)
				(arc
					(start 100.22078 -11.484102)
					(mid 100.295247 -11.456991)
					(end 100.334826 -11.388344)
				)
				(arc
					(start 100.334826 -11.388344)
					(mid 100.401002 -10.606165)
					(end 100.463604 -11.388598)
				)
				(xy 100.463604 -11.394694)
				(arc
					(start 100.46208 -11.396218)
					(mid 100.392545 -11.540043)
					(end 100.24872 -11.609578)
				)
				(xy 100.247196 -11.611102) (xy 99.871276 -11.611102) (xy 99.838764 -11.612372) (xy 99.838764 -11.79068)
				(xy 99.84359 -11.790172) (xy 99.84486 -11.788902) (xy 100.247196 -11.788902)
				(arc
					(start 100.24872 -11.790426)
					(mid 100.392545 -11.859961)
					(end 100.46208 -12.003786)
				)
				(xy 100.463604 -12.00531)
				(arc
					(start 100.463604 -12.011406)
					(mid 100.401002 -12.793799)
					(end 100.334826 -12.01166)
				)
				(arc
					(start 100.334826 -12.01166)
					(mid 100.29523 -11.943033)
					(end 100.22078 -11.915902)
				)
				(arc
					(start 99.871276 -11.915902)
					(mid 99.854926 -11.91682)
					(end 99.838764 -11.919458)
				)
				(arc
					(start 99.838764 -12.399772)
					(mid 100.399977 -12.961366)
					(end 100.961444 -12.400026)
				)
			)
		)
	)
	(zone
		(layer "In5.Cu")
		(hatch none 0.5)
		(connect_pads
			(clearance 0)
		)
		(min_thickness 0.25)
		(keepout
			(tracks not_allowed)
			(vias allowed)
			(pads allowed)
			(copperpour not_allowed)
			(footprints allowed)
		)
		(placement
			(enabled no)
			(sheetname "")
		)
		(fill
			(thermal_gap 0.5)
			(thermal_bridge_width 0.5)
			(island_removal_mode 0)
		)
		(polygon
			(pts
				(arc
					(start 191.361314 -3.800094)
					(mid 190.799974 -3.238754)
					(end 190.238634 -3.800094)
				)
				(xy 190.238634 -4.255262) (xy 190.263526 -4.253484) (xy 190.264288 -4.252468)
				(arc
					(start 190.63335 -4.252468)
					(mid 190.686748 -4.233333)
					(end 190.7159 -4.18465)
				)
				(arc
					(start 190.7159 -4.18465)
					(mid 190.801777 -3.406348)
					(end 190.882524 -4.185158)
				)
				(xy 190.882524 -4.202684)
				(arc
					(start 190.87973 -4.205224)
					(mid 190.809503 -4.344547)
					(end 190.67018 -4.414774)
				)
				(xy 190.66764 -4.417568)
				(arc
					(start 190.298578 -4.417568)
					(mid 190.268547 -4.418538)
					(end 190.238634 -4.421378)
				)
				(xy 190.238634 -4.58851) (xy 190.262256 -4.5847) (xy 190.264288 -4.582668) (xy 190.66764 -4.582668)
				(arc
					(start 190.67018 -4.585462)
					(mid 190.809503 -4.655689)
					(end 190.87973 -4.795012)
				)
				(xy 190.882524 -4.797552)
				(arc
					(start 190.882524 -4.815078)
					(mid 190.801777 -5.593847)
					(end 190.7159 -4.815586)
				)
				(arc
					(start 190.7159 -4.815586)
					(mid 190.686787 -4.766856)
					(end 190.63335 -4.747768)
				)
				(arc
					(start 190.298578 -4.747768)
					(mid 190.267966 -4.750911)
					(end 190.238634 -4.760214)
				)
				(arc
					(start 190.238634 -5.199888)
					(mid 190.799847 -5.761482)
					(end 191.361314 -5.200142)
				)
			)
		)
	)
	(zone
		(layer "In5.Cu")
		(hatch none 0.5)
		(connect_pads
			(clearance 0)
		)
		(min_thickness 0.25)
		(keepout
			(tracks not_allowed)
			(vias allowed)
			(pads allowed)
			(copperpour not_allowed)
			(footprints allowed)
		)
		(placement
			(enabled no)
			(sheetname "")
		)
		(fill
			(thermal_gap 0.5)
			(thermal_bridge_width 0.5)
			(island_removal_mode 0)
		)
		(polygon
			(pts
				(xy 157.506924 -46.653958) (xy 157.506924 -42.996358) (xy 160.250124 -42.996358) (xy 160.250124 -46.653958)
			)
		)
	)
	(zone
		(layer "In5.Cu")
		(hatch none 0.5)
		(connect_pads
			(clearance 0)
		)
		(min_thickness 0.25)
		(keepout
			(tracks not_allowed)
			(vias allowed)
			(pads allowed)
			(copperpour not_allowed)
			(footprints allowed)
		)
		(placement
			(enabled no)
			(sheetname "")
		)
		(fill
			(thermal_gap 0.5)
			(thermal_bridge_width 0.5)
			(island_removal_mode 0)
		)
		(polygon
			(pts
				(arc
					(start 108.351574 -50.931572)
					(mid 107.965588 -50.64365)
					(end 107.641898 -51.000152)
				)
				(arc
					(start 107.641898 -51.999896)
					(mid 107.999911 -52.35829)
					(end 108.358178 -52.00015)
				)
				(arc
					(start 108.358178 -51.641502)
					(mid 108.324493 -51.648081)
					(end 108.29036 -51.651662)
				)
				(xy 108.289598 -51.652424)
				(arc
					(start 108.088938 -51.652424)
					(mid 108.066487 -51.661723)
					(end 108.057188 -51.684174)
				)
				(arc
					(start 108.057188 -51.765708)
					(mid 108.000038 -52.241457)
					(end 107.942888 -51.765708)
				)
				(xy 107.942888 -51.660552)
				(arc
					(start 107.945174 -51.658266)
					(mid 107.985644 -51.58088)
					(end 108.06303 -51.54041)
				)
				(xy 108.065316 -51.538124)
				(arc
					(start 108.265976 -51.538124)
					(mid 108.312748 -51.534181)
					(end 108.358178 -51.522376)
				)
				(arc
					(start 108.358178 -51.439318)
					(mid 108.325708 -51.452811)
					(end 108.291376 -51.4604)
				)
				(xy 108.289598 -51.461924) (xy 108.065316 -51.461924)
				(arc
					(start 108.06303 -51.459638)
					(mid 107.985644 -51.419168)
					(end 107.945174 -51.341782)
				)
				(xy 107.942888 -51.339496)
				(arc
					(start 107.942888 -51.234594)
					(mid 108.000038 -50.758845)
					(end 108.057188 -51.234594)
				)
				(arc
					(start 108.057188 -51.315874)
					(mid 108.066487 -51.338325)
					(end 108.088938 -51.347624)
				)
				(arc
					(start 108.265976 -51.347624)
					(mid 108.29883 -51.341089)
					(end 108.326682 -51.322478)
				)
				(arc
					(start 108.326682 -51.322478)
					(mid 108.345083 -51.294845)
					(end 108.351574 -51.26228)
				)
			)
		)
	)
	(zone
		(net "P3V3")
		(layer "In5.Cu")
		(hatch none 0.5)
		(connect_pads
			(clearance 0.5)
		)
		(min_thickness 0.25)
		(fill yes
			(thermal_gap 0.5)
			(thermal_bridge_width 0.5)
			(island_removal_mode 0)
		)
		(polygon
			(pts
				(xy 167.843454 -101.160834) (xy 165.146228 -98.463608) (xy 165.146228 -74.061828) (xy 163.7284 -72.644)
				(xy 163.1188 -72.0344) (xy 158.3436 -72.0344) (xy 156.72308 -73.65492) (xy 156.72308 -101.34092)
				(xy 162.689794 -107.30738) (xy 163.193476 -107.811062) (xy 163.584382 -108.201968) (xy 164.907214 -109.5248)
				(xy 167.6654 -109.5248) (xy 167.843454 -109.346746) (xy 167.843454 -107.924854)
			)
		)
	)
	(zone
		(layer "In5.Cu")
		(hatch none 0.5)
		(connect_pads
			(clearance 0)
		)
		(min_thickness 0.25)
		(keepout
			(tracks not_allowed)
			(vias allowed)
			(pads allowed)
			(copperpour not_allowed)
			(footprints allowed)
		)
		(placement
			(enabled no)
			(sheetname "")
		)
		(fill
			(thermal_gap 0.5)
			(thermal_bridge_width 0.5)
			(island_removal_mode 0)
		)
		(polygon
			(pts
				(arc
					(start 90.161364 -10.999978)
					(mid 89.600024 -10.438638)
					(end 89.038684 -10.999978)
				)
				(xy 89.038684 -11.485118) (xy 89.044272 -11.48461) (xy 89.04478 -11.484102)
				(arc
					(start 89.4207 -11.484102)
					(mid 89.495167 -11.456991)
					(end 89.534746 -11.388344)
				)
				(arc
					(start 89.534746 -11.388344)
					(mid 89.600922 -10.606165)
					(end 89.663524 -11.388598)
				)
				(xy 89.663524 -11.394694)
				(arc
					(start 89.662 -11.396218)
					(mid 89.592465 -11.540043)
					(end 89.44864 -11.609578)
				)
				(xy 89.447116 -11.611102) (xy 89.071196 -11.611102) (xy 89.038684 -11.612372) (xy 89.038684 -11.79068)
				(xy 89.04351 -11.790172) (xy 89.04478 -11.788902) (xy 89.447116 -11.788902)
				(arc
					(start 89.44864 -11.790426)
					(mid 89.592465 -11.859961)
					(end 89.662 -12.003786)
				)
				(xy 89.663524 -12.00531)
				(arc
					(start 89.663524 -12.011406)
					(mid 89.600922 -12.793799)
					(end 89.534746 -12.01166)
				)
				(arc
					(start 89.534746 -12.01166)
					(mid 89.49515 -11.943033)
					(end 89.4207 -11.915902)
				)
				(arc
					(start 89.071196 -11.915902)
					(mid 89.054846 -11.91682)
					(end 89.038684 -11.919458)
				)
				(arc
					(start 89.038684 -12.399772)
					(mid 89.599897 -12.961366)
					(end 90.161364 -12.400026)
				)
			)
		)
	)
	(zone
		(layer "In5.Cu")
		(hatch none 0.5)
		(connect_pads
			(clearance 0)
		)
		(min_thickness 0.25)
		(keepout
			(tracks not_allowed)
			(vias allowed)
			(pads allowed)
			(copperpour not_allowed)
			(footprints allowed)
		)
		(placement
			(enabled no)
			(sheetname "")
		)
		(fill
			(thermal_gap 0.5)
			(thermal_bridge_width 0.5)
			(island_removal_mode 0)
		)
		(polygon
			(pts
				(arc
					(start 130.000248 -68.641976)
					(mid 129.641854 -68.999989)
					(end 129.999994 -69.358256)
				)
				(arc
					(start 130.342894 -69.358256)
					(mid 130.329401 -69.305053)
					(end 130.322828 -69.25056)
				)
				(xy 130.322066 -69.249798)
				(arc
					(start 130.322066 -69.089016)
					(mid 130.312767 -69.066565)
					(end 130.290316 -69.057266)
				)
				(arc
					(start 130.234436 -69.057266)
					(mid 129.758687 -69.000116)
					(end 130.234436 -68.942966)
				)
				(xy 130.313938 -68.942966)
				(arc
					(start 130.316224 -68.945252)
					(mid 130.39361 -68.985722)
					(end 130.43408 -69.063108)
				)
				(xy 130.436366 -69.065394)
				(arc
					(start 130.436366 -69.226684)
					(mid 130.443684 -69.294047)
					(end 130.465322 -69.358256)
				)
				(arc
					(start 130.552698 -69.358256)
					(mid 130.526765 -69.307023)
					(end 130.513836 -69.251068)
				)
				(xy 130.512566 -69.249798) (xy 130.512566 -69.065394)
				(arc
					(start 130.514852 -69.063108)
					(mid 130.555322 -68.985722)
					(end 130.632708 -68.945252)
				)
				(xy 130.634994 -68.942966)
				(arc
					(start 130.76555 -68.942966)
					(mid 131.241299 -69.000116)
					(end 130.76555 -69.057266)
				)
				(arc
					(start 130.658616 -69.057266)
					(mid 130.636165 -69.066565)
					(end 130.626866 -69.089016)
				)
				(arc
					(start 130.626866 -69.226176)
					(mid 130.636243 -69.273319)
					(end 130.662934 -69.313298)
				)
				(arc
					(start 130.662934 -69.313298)
					(mid 130.702906 -69.340006)
					(end 130.750056 -69.349366)
				)
				(arc
					(start 131.07924 -69.349366)
					(mid 131.355894 -68.960244)
					(end 130.999992 -68.641976)
				)
			)
		)
	)
	(zone
		(net "P3V3")
		(layer "In5.Cu")
		(hatch none 0.5)
		(connect_pads
			(clearance 0.5)
		)
		(min_thickness 0.25)
		(fill yes
			(thermal_gap 0.5)
			(thermal_bridge_width 0.5)
			(island_removal_mode 0)
		)
		(polygon
			(pts
				(xy 48.387 -90.6526) (xy 48.387 -81.153) (xy 53.2638 -76.2762) (xy 69.5452 -76.2762) (xy 70.2818 -75.5396)
				(xy 70.2818 -69.7738) (xy 69.5452 -69.0372) (xy 42.6466 -69.0372) (xy 41.5544 -70.1294) (xy 41.5544 -91.6178)
				(xy 41.6814 -91.7448) (xy 47.2948 -91.7448) (xy 47.5996 -91.7448) (xy 48.387 -90.9574)
			)
		)
	)
	(zone
		(layer "In5.Cu")
		(hatch none 0.5)
		(connect_pads
			(clearance 0)
		)
		(min_thickness 0.25)
		(keepout
			(tracks not_allowed)
			(vias allowed)
			(pads allowed)
			(copperpour not_allowed)
			(footprints allowed)
		)
		(placement
			(enabled no)
			(sheetname "")
		)
		(fill
			(thermal_gap 0.5)
			(thermal_bridge_width 0.5)
			(island_removal_mode 0)
		)
		(polygon
			(pts
				(arc
					(start 149.561296 -9.800082)
					(mid 148.999956 -9.238742)
					(end 148.438616 -9.800082)
				)
				(xy 148.438616 -10.285222) (xy 148.444204 -10.284714) (xy 148.444712 -10.284206)
				(arc
					(start 148.820632 -10.284206)
					(mid 148.895099 -10.257095)
					(end 148.934678 -10.188448)
				)
				(arc
					(start 148.934678 -10.188448)
					(mid 149.000854 -9.406269)
					(end 149.063456 -10.188702)
				)
				(xy 149.063456 -10.194798)
				(arc
					(start 149.061932 -10.196322)
					(mid 148.992397 -10.340147)
					(end 148.848572 -10.409682)
				)
				(xy 148.847048 -10.411206) (xy 148.471128 -10.411206) (xy 148.438616 -10.412476) (xy 148.438616 -10.590784)
				(xy 148.443442 -10.590276) (xy 148.444712 -10.589006) (xy 148.847048 -10.589006)
				(arc
					(start 148.848572 -10.59053)
					(mid 148.992397 -10.660065)
					(end 149.061932 -10.80389)
				)
				(xy 149.063456 -10.805414)
				(arc
					(start 149.063456 -10.81151)
					(mid 149.000854 -11.593903)
					(end 148.934678 -10.811764)
				)
				(arc
					(start 148.934678 -10.811764)
					(mid 148.895082 -10.743137)
					(end 148.820632 -10.716006)
				)
				(arc
					(start 148.471128 -10.716006)
					(mid 148.454778 -10.716924)
					(end 148.438616 -10.719562)
				)
				(arc
					(start 148.438616 -11.199876)
					(mid 148.999829 -11.76147)
					(end 149.561296 -11.20013)
				)
			)
		)
	)
	(zone
		(layer "In5.Cu")
		(hatch none 0.5)
		(connect_pads
			(clearance 0)
		)
		(min_thickness 0.25)
		(keepout
			(tracks not_allowed)
			(vias allowed)
			(pads allowed)
			(copperpour not_allowed)
			(footprints allowed)
		)
		(placement
			(enabled no)
			(sheetname "")
		)
		(fill
			(thermal_gap 0.5)
			(thermal_bridge_width 0.5)
			(island_removal_mode 0)
		)
		(polygon
			(pts
				(arc
					(start 116.34724 -51.912266)
					(mid 115.95574 -51.64473)
					(end 115.641882 -52.00015)
				)
				(arc
					(start 115.641882 -52.999894)
					(mid 115.999895 -53.358288)
					(end 116.358162 -53.000148)
				)
				(arc
					(start 116.358162 -52.639468)
					(mid 116.320359 -52.647418)
					(end 116.281962 -52.65166)
				)
				(xy 116.2812 -52.652422)
				(arc
					(start 116.088922 -52.652422)
					(mid 116.066471 -52.661721)
					(end 116.057172 -52.684172)
				)
				(arc
					(start 116.057172 -52.765706)
					(mid 116.000022 -53.241455)
					(end 115.942872 -52.765706)
				)
				(xy 115.942872 -52.66055)
				(arc
					(start 115.945158 -52.658264)
					(mid 115.985628 -52.580878)
					(end 116.063014 -52.540408)
				)
				(xy 116.0653 -52.538122)
				(arc
					(start 116.258086 -52.538122)
					(mid 116.308971 -52.533424)
					(end 116.358162 -52.51958)
				)
				(arc
					(start 116.358162 -52.435506)
					(mid 116.321668 -52.451671)
					(end 116.282724 -52.460398)
				)
				(xy 116.2812 -52.461922) (xy 116.0653 -52.461922)
				(arc
					(start 116.063014 -52.459636)
					(mid 115.985628 -52.419166)
					(end 115.945158 -52.34178)
				)
				(xy 115.942872 -52.339494)
				(arc
					(start 115.942872 -52.234592)
					(mid 116.000022 -51.758843)
					(end 116.057172 -52.234592)
				)
				(arc
					(start 116.057172 -52.315872)
					(mid 116.066471 -52.338323)
					(end 116.088922 -52.347622)
				)
				(arc
					(start 116.257578 -52.347622)
					(mid 116.291752 -52.340895)
					(end 116.320824 -52.321714)
				)
				(arc
					(start 116.321078 -52.32146)
					(mid 116.340443 -52.292429)
					(end 116.34724 -52.258214)
				)
			)
		)
	)
	(zone
		(layer "In5.Cu")
		(hatch none 0.5)
		(connect_pads
			(clearance 0)
		)
		(min_thickness 0.25)
		(keepout
			(tracks not_allowed)
			(vias allowed)
			(pads allowed)
			(copperpour not_allowed)
			(footprints allowed)
		)
		(placement
			(enabled no)
			(sheetname "")
		)
		(fill
			(thermal_gap 0.5)
			(thermal_bridge_width 0.5)
			(island_removal_mode 0)
		)
		(polygon
			(pts
				(arc
					(start 104.561386 -10.999978)
					(mid 104.000046 -10.438638)
					(end 103.438706 -10.999978)
				)
				(xy 103.438706 -11.485118) (xy 103.444294 -11.48461) (xy 103.444802 -11.484102)
				(arc
					(start 103.820722 -11.484102)
					(mid 103.895189 -11.456991)
					(end 103.934768 -11.388344)
				)
				(arc
					(start 103.934768 -11.388344)
					(mid 104.000944 -10.606165)
					(end 104.063546 -11.388598)
				)
				(xy 104.063546 -11.394694)
				(arc
					(start 104.062022 -11.396218)
					(mid 103.992487 -11.540043)
					(end 103.848662 -11.609578)
				)
				(xy 103.847138 -11.611102) (xy 103.471218 -11.611102) (xy 103.438706 -11.612372) (xy 103.438706 -11.79068)
				(xy 103.443532 -11.790172) (xy 103.444802 -11.788902) (xy 103.847138 -11.788902)
				(arc
					(start 103.848662 -11.790426)
					(mid 103.992487 -11.859961)
					(end 104.062022 -12.003786)
				)
				(xy 104.063546 -12.00531)
				(arc
					(start 104.063546 -12.011406)
					(mid 104.000944 -12.793799)
					(end 103.934768 -12.01166)
				)
				(arc
					(start 103.934768 -12.01166)
					(mid 103.895172 -11.943033)
					(end 103.820722 -11.915902)
				)
				(arc
					(start 103.471218 -11.915902)
					(mid 103.454868 -11.91682)
					(end 103.438706 -11.919458)
				)
				(arc
					(start 103.438706 -12.399772)
					(mid 103.999919 -12.961366)
					(end 104.561386 -12.400026)
				)
			)
		)
	)
	(zone
		(layer "In5.Cu")
		(hatch none 0.5)
		(connect_pads
			(clearance 0)
		)
		(min_thickness 0.25)
		(keepout
			(tracks not_allowed)
			(vias allowed)
			(pads allowed)
			(copperpour not_allowed)
			(footprints allowed)
		)
		(placement
			(enabled no)
			(sheetname "")
		)
		(fill
			(thermal_gap 0.5)
			(thermal_bridge_width 0.5)
			(island_removal_mode 0)
		)
		(polygon
			(pts
				(arc
					(start 117.351556 -50.931572)
					(mid 116.96557 -50.64365)
					(end 116.64188 -51.000152)
				)
				(arc
					(start 116.64188 -51.999896)
					(mid 116.999893 -52.35829)
					(end 117.35816 -52.00015)
				)
				(arc
					(start 117.35816 -51.643534)
					(mid 117.329487 -51.648706)
					(end 117.300502 -51.651662)
				)
				(xy 117.29974 -51.652424)
				(arc
					(start 117.08892 -51.652424)
					(mid 117.066469 -51.661723)
					(end 117.05717 -51.684174)
				)
				(arc
					(start 117.05717 -51.765708)
					(mid 117.00002 -52.241457)
					(end 116.94287 -51.765708)
				)
				(xy 116.94287 -51.660552)
				(arc
					(start 116.945156 -51.658266)
					(mid 116.985626 -51.58088)
					(end 117.063012 -51.54041)
				)
				(xy 117.065298 -51.538124)
				(arc
					(start 117.276626 -51.538124)
					(mid 117.317897 -51.534822)
					(end 117.35816 -51.52517)
				)
				(arc
					(start 117.35816 -51.443128)
					(mid 117.330511 -51.453881)
					(end 117.301518 -51.460146)
				)
				(xy 117.29974 -51.461924) (xy 117.065298 -51.461924)
				(arc
					(start 117.063012 -51.459638)
					(mid 116.985626 -51.419168)
					(end 116.945156 -51.341782)
				)
				(xy 116.94287 -51.339496)
				(arc
					(start 116.94287 -51.234594)
					(mid 117.00002 -50.758845)
					(end 117.05717 -51.234594)
				)
				(arc
					(start 117.05717 -51.315874)
					(mid 117.066469 -51.338325)
					(end 117.08892 -51.347624)
				)
				(arc
					(start 117.276118 -51.347624)
					(mid 117.304987 -51.341882)
					(end 117.329458 -51.325526)
				)
				(arc
					(start 117.329458 -51.325526)
					(mid 117.34581 -51.301053)
					(end 117.351556 -51.272186)
				)
			)
		)
	)
	(zone
		(layer "In5.Cu")
		(hatch none 0.5)
		(connect_pads
			(clearance 0)
		)
		(min_thickness 0.25)
		(keepout
			(tracks not_allowed)
			(vias allowed)
			(pads allowed)
			(copperpour not_allowed)
			(footprints allowed)
		)
		(placement
			(enabled no)
			(sheetname "")
		)
		(fill
			(thermal_gap 0.5)
			(thermal_bridge_width 0.5)
			(island_removal_mode 0)
		)
		(polygon
			(pts
				(arc
					(start 115.361466 -10.999978)
					(mid 114.800126 -10.438638)
					(end 114.238786 -10.999978)
				)
				(xy 114.238786 -11.485118) (xy 114.244374 -11.48461) (xy 114.244882 -11.484102)
				(arc
					(start 114.620802 -11.484102)
					(mid 114.695269 -11.456991)
					(end 114.734848 -11.388344)
				)
				(arc
					(start 114.734848 -11.388344)
					(mid 114.801024 -10.606165)
					(end 114.863626 -11.388598)
				)
				(xy 114.863626 -11.394694)
				(arc
					(start 114.862102 -11.396218)
					(mid 114.792567 -11.540043)
					(end 114.648742 -11.609578)
				)
				(xy 114.647218 -11.611102) (xy 114.271298 -11.611102) (xy 114.238786 -11.612372) (xy 114.238786 -11.79068)
				(xy 114.243612 -11.790172) (xy 114.244882 -11.788902) (xy 114.647218 -11.788902)
				(arc
					(start 114.648742 -11.790426)
					(mid 114.792567 -11.859961)
					(end 114.862102 -12.003786)
				)
				(xy 114.863626 -12.00531)
				(arc
					(start 114.863626 -12.011406)
					(mid 114.801024 -12.793799)
					(end 114.734848 -12.01166)
				)
				(arc
					(start 114.734848 -12.01166)
					(mid 114.695252 -11.943033)
					(end 114.620802 -11.915902)
				)
				(arc
					(start 114.271298 -11.915902)
					(mid 114.254948 -11.91682)
					(end 114.238786 -11.919458)
				)
				(arc
					(start 114.238786 -12.399772)
					(mid 114.799999 -12.961366)
					(end 115.361466 -12.400026)
				)
			)
		)
	)
	(zone
		(layer "In5.Cu")
		(hatch none 0.5)
		(connect_pads
			(clearance 0)
		)
		(min_thickness 0.25)
		(keepout
			(tracks not_allowed)
			(vias allowed)
			(pads allowed)
			(copperpour not_allowed)
			(footprints allowed)
		)
		(placement
			(enabled no)
			(sheetname "")
		)
		(fill
			(thermal_gap 0.5)
			(thermal_bridge_width 0.5)
			(island_removal_mode 0)
		)
		(polygon
			(pts
				(arc
					(start 104.351582 -50.931572)
					(mid 103.965596 -50.64365)
					(end 103.641906 -51.000152)
				)
				(arc
					(start 103.641906 -51.999896)
					(mid 103.999919 -52.35829)
					(end 104.358186 -52.00015)
				)
				(arc
					(start 104.358186 -51.6382)
					(mid 104.317763 -51.647013)
					(end 104.276652 -51.651662)
				)
				(xy 104.27589 -51.652424)
				(arc
					(start 104.088946 -51.652424)
					(mid 104.066495 -51.661723)
					(end 104.057196 -51.684174)
				)
				(arc
					(start 104.057196 -51.765708)
					(mid 104.000046 -52.241457)
					(end 103.942896 -51.765708)
				)
				(xy 103.942896 -51.660552)
				(arc
					(start 103.945182 -51.658266)
					(mid 103.985652 -51.58088)
					(end 104.063038 -51.54041)
				)
				(xy 104.065324 -51.538124)
				(arc
					(start 104.252268 -51.538124)
					(mid 104.306169 -51.533063)
					(end 104.358186 -51.518058)
				)
				(arc
					(start 104.358186 -51.43373)
					(mid 104.319137 -51.45111)
					(end 104.277414 -51.4604)
				)
				(xy 104.27589 -51.461924) (xy 104.065324 -51.461924)
				(arc
					(start 104.063038 -51.459638)
					(mid 103.985652 -51.419168)
					(end 103.945182 -51.341782)
				)
				(xy 103.942896 -51.339496)
				(arc
					(start 103.942896 -51.234594)
					(mid 104.000046 -50.758845)
					(end 104.057196 -51.234594)
				)
				(arc
					(start 104.057196 -51.315874)
					(mid 104.066495 -51.338325)
					(end 104.088946 -51.347624)
				)
				(arc
					(start 104.252268 -51.347624)
					(mid 104.290191 -51.340098)
					(end 104.322372 -51.318668)
				)
				(arc
					(start 104.322372 -51.318668)
					(mid 104.343995 -51.286402)
					(end 104.351582 -51.24831)
				)
			)
		)
	)
	(zone
		(layer "In5.Cu")
		(hatch none 0.5)
		(connect_pads
			(clearance 0)
		)
		(min_thickness 0.25)
		(keepout
			(tracks not_allowed)
			(vias allowed)
			(pads allowed)
			(copperpour not_allowed)
			(footprints allowed)
		)
		(placement
			(enabled no)
			(sheetname "")
		)
		(fill
			(thermal_gap 0.5)
			(thermal_bridge_width 0.5)
			(island_removal_mode 0)
		)
		(polygon
			(pts
				(arc
					(start 174.698406 -23.112476)
					(mid 174.314866 -22.728936)
					(end 173.931326 -23.112476)
				)
				(arc
					(start 173.931326 -24.001222)
					(mid 174.314739 -24.385016)
					(end 174.698406 -24.001476)
				)
				(xy 174.698406 -23.804626)
				(arc
					(start 174.594266 -23.804626)
					(mid 174.552416 -23.80912)
					(end 174.512478 -23.822406)
				)
				(arc
					(start 174.512478 -23.822406)
					(mid 174.192097 -24.238213)
					(end 174.347378 -23.736808)
				)
				(arc
					(start 174.347378 -23.736808)
					(mid 174.444953 -23.671766)
					(end 174.558198 -23.641304)
				)
				(xy 174.559976 -23.639526) (xy 174.698406 -23.639526) (xy 174.698406 -23.474426) (xy 174.559976 -23.474426)
				(arc
					(start 174.558198 -23.472648)
					(mid 174.44494 -23.442213)
					(end 174.347378 -23.377144)
				)
				(arc
					(start 174.347378 -23.377144)
					(mid 174.192106 -22.875756)
					(end 174.512478 -23.291546)
				)
				(arc
					(start 174.512478 -23.291546)
					(mid 174.552418 -23.304823)
					(end 174.594266 -23.309326)
				)
				(xy 174.698406 -23.309326)
			)
		)
	)
	(zone
		(layer "In5.Cu")
		(hatch none 0.5)
		(connect_pads
			(clearance 0)
		)
		(min_thickness 0.25)
		(keepout
			(tracks not_allowed)
			(vias allowed)
			(pads allowed)
			(copperpour not_allowed)
			(footprints allowed)
		)
		(placement
			(enabled no)
			(sheetname "")
		)
		(fill
			(thermal_gap 0.5)
			(thermal_bridge_width 0.5)
			(island_removal_mode 0)
		)
		(polygon
			(pts
				(arc
					(start 187.761118 -3.800094)
					(mid 187.199778 -3.238754)
					(end 186.638438 -3.800094)
				)
				(xy 186.638438 -4.255262) (xy 186.66333 -4.253484) (xy 186.664092 -4.252468)
				(arc
					(start 187.033154 -4.252468)
					(mid 187.086552 -4.233333)
					(end 187.115704 -4.18465)
				)
				(arc
					(start 187.115704 -4.18465)
					(mid 187.201581 -3.406348)
					(end 187.282328 -4.185158)
				)
				(xy 187.282328 -4.202684)
				(arc
					(start 187.279534 -4.205224)
					(mid 187.209307 -4.344547)
					(end 187.069984 -4.414774)
				)
				(xy 187.067444 -4.417568)
				(arc
					(start 186.698382 -4.417568)
					(mid 186.668351 -4.418538)
					(end 186.638438 -4.421378)
				)
				(xy 186.638438 -4.58851) (xy 186.66206 -4.5847) (xy 186.664092 -4.582668) (xy 187.067444 -4.582668)
				(arc
					(start 187.069984 -4.585462)
					(mid 187.209307 -4.655689)
					(end 187.279534 -4.795012)
				)
				(xy 187.282328 -4.797552)
				(arc
					(start 187.282328 -4.815078)
					(mid 187.201581 -5.593847)
					(end 187.115704 -4.815586)
				)
				(arc
					(start 187.115704 -4.815586)
					(mid 187.086591 -4.766856)
					(end 187.033154 -4.747768)
				)
				(arc
					(start 186.698382 -4.747768)
					(mid 186.66777 -4.750911)
					(end 186.638438 -4.760214)
				)
				(arc
					(start 186.638438 -5.199888)
					(mid 187.199651 -5.761482)
					(end 187.761118 -5.200142)
				)
			)
		)
	)
	(zone
		(layer "In5.Cu")
		(hatch none 0.5)
		(connect_pads
			(clearance 0)
		)
		(min_thickness 0.25)
		(keepout
			(tracks not_allowed)
			(vias allowed)
			(pads allowed)
			(copperpour not_allowed)
			(footprints allowed)
		)
		(placement
			(enabled no)
			(sheetname "")
		)
		(fill
			(thermal_gap 0.5)
			(thermal_bridge_width 0.5)
			(island_removal_mode 0)
		)
		(polygon
			(pts
				(arc
					(start 109.961426 -9.800082)
					(mid 109.400086 -9.238742)
					(end 108.838746 -9.800082)
				)
				(xy 108.838746 -10.285222) (xy 108.844334 -10.284714) (xy 108.844842 -10.284206)
				(arc
					(start 109.220762 -10.284206)
					(mid 109.295229 -10.257095)
					(end 109.334808 -10.188448)
				)
				(arc
					(start 109.334808 -10.188448)
					(mid 109.400984 -9.406269)
					(end 109.463586 -10.188702)
				)
				(xy 109.463586 -10.194798)
				(arc
					(start 109.462062 -10.196322)
					(mid 109.392527 -10.340147)
					(end 109.248702 -10.409682)
				)
				(xy 109.247178 -10.411206) (xy 108.871258 -10.411206) (xy 108.838746 -10.412476) (xy 108.838746 -10.590784)
				(xy 108.843572 -10.590276) (xy 108.844842 -10.589006) (xy 109.247178 -10.589006)
				(arc
					(start 109.248702 -10.59053)
					(mid 109.392527 -10.660065)
					(end 109.462062 -10.80389)
				)
				(xy 109.463586 -10.805414)
				(arc
					(start 109.463586 -10.81151)
					(mid 109.400984 -11.593903)
					(end 109.334808 -10.811764)
				)
				(arc
					(start 109.334808 -10.811764)
					(mid 109.295212 -10.743137)
					(end 109.220762 -10.716006)
				)
				(arc
					(start 108.871258 -10.716006)
					(mid 108.854907 -10.716922)
					(end 108.838746 -10.719562)
				)
				(arc
					(start 108.838746 -11.199876)
					(mid 109.399959 -11.76147)
					(end 109.961426 -11.20013)
				)
			)
		)
	)
	(zone
		(layer "In5.Cu")
		(hatch none 0.5)
		(connect_pads
			(clearance 0)
		)
		(min_thickness 0.25)
		(keepout
			(tracks not_allowed)
			(vias allowed)
			(pads allowed)
			(copperpour not_allowed)
			(footprints allowed)
		)
		(placement
			(enabled no)
			(sheetname "")
		)
		(fill
			(thermal_gap 0.5)
			(thermal_bridge_width 0.5)
			(island_removal_mode 0)
		)
		(polygon
			(pts
				(arc
					(start 106.351578 -50.931572)
					(mid 105.965592 -50.64365)
					(end 105.641902 -51.000152)
				)
				(arc
					(start 105.641902 -51.999896)
					(mid 105.999915 -52.35829)
					(end 106.358182 -52.00015)
				)
				(arc
					(start 106.358182 -51.623468)
					(mid 106.290941 -51.642901)
					(end 106.22153 -51.651916)
				)
				(xy 106.220768 -51.652424)
				(arc
					(start 106.088942 -51.652424)
					(mid 106.066491 -51.661723)
					(end 106.057192 -51.684174)
				)
				(arc
					(start 106.057192 -51.765708)
					(mid 106.000042 -52.241457)
					(end 105.942892 -51.765708)
				)
				(xy 105.942892 -51.660552)
				(arc
					(start 105.945178 -51.658266)
					(mid 105.985648 -51.58088)
					(end 106.063034 -51.54041)
				)
				(xy 106.06532 -51.538124)
				(arc
					(start 106.197654 -51.538124)
					(mid 106.28033 -51.528077)
					(end 106.358182 -51.4985)
				)
				(arc
					(start 106.358182 -51.40833)
					(mid 106.293728 -51.443903)
					(end 106.222038 -51.460654)
				)
				(xy 106.220768 -51.461924) (xy 106.06532 -51.461924)
				(arc
					(start 106.063034 -51.459638)
					(mid 105.985648 -51.419168)
					(end 105.945178 -51.341782)
				)
				(xy 105.942892 -51.339496)
				(arc
					(start 105.942892 -51.234594)
					(mid 106.000042 -50.758845)
					(end 106.057192 -51.234594)
				)
				(arc
					(start 106.057192 -51.315874)
					(mid 106.066491 -51.338325)
					(end 106.088942 -51.347624)
				)
				(arc
					(start 106.197146 -51.347624)
					(mid 106.256245 -51.335869)
					(end 106.306366 -51.302412)
				)
				(arc
					(start 106.306366 -51.302412)
					(mid 106.339849 -51.252301)
					(end 106.351578 -51.193192)
				)
			)
		)
	)
	(zone
		(layer "In5.Cu")
		(hatch none 0.5)
		(connect_pads
			(clearance 0)
		)
		(min_thickness 0.25)
		(keepout
			(tracks not_allowed)
			(vias allowed)
			(pads allowed)
			(copperpour not_allowed)
			(footprints allowed)
		)
		(placement
			(enabled no)
			(sheetname "")
		)
		(fill
			(thermal_gap 0.5)
			(thermal_bridge_width 0.5)
			(island_removal_mode 0)
		)
		(polygon
			(pts
				(arc
					(start 129.00025 -67.641978)
					(mid 128.641856 -67.999991)
					(end 128.999996 -68.358258)
				)
				(arc
					(start 129.3749 -68.358258)
					(mid 129.355812 -68.292012)
					(end 129.34696 -68.223638)
				)
				(xy 129.346198 -68.222876)
				(arc
					(start 129.346198 -68.089018)
					(mid 129.336899 -68.066567)
					(end 129.314448 -68.057268)
				)
				(arc
					(start 129.234438 -68.057268)
					(mid 128.758689 -68.000118)
					(end 129.234438 -67.942968)
				)
				(xy 129.33807 -67.942968)
				(arc
					(start 129.340356 -67.945254)
					(mid 129.417742 -67.985724)
					(end 129.458212 -68.06311)
				)
				(xy 129.460498 -68.065396)
				(arc
					(start 129.460498 -68.199762)
					(mid 129.470485 -68.28142)
					(end 129.499868 -68.358258)
				)
				(arc
					(start 129.590292 -68.358258)
					(mid 129.554775 -68.294855)
					(end 129.537968 -68.224146)
				)
				(xy 129.536698 -68.222876) (xy 129.536698 -68.065396)
				(arc
					(start 129.538984 -68.06311)
					(mid 129.579454 -67.985724)
					(end 129.65684 -67.945254)
				)
				(xy 129.659126 -67.942968)
				(arc
					(start 129.765552 -67.942968)
					(mid 130.241301 -68.000118)
					(end 129.765552 -68.057268)
				)
				(arc
					(start 129.682748 -68.057268)
					(mid 129.660297 -68.066567)
					(end 129.650998 -68.089018)
				)
				(arc
					(start 129.650998 -68.199254)
					(mid 129.662289 -68.25602)
					(end 129.694432 -68.304156)
				)
				(arc
					(start 129.694432 -68.304156)
					(mid 129.742561 -68.336315)
					(end 129.799334 -68.34759)
				)
				(arc
					(start 130.086862 -68.34759)
					(mid 130.355476 -67.956356)
					(end 129.999994 -67.641978)
				)
			)
		)
	)
	(zone
		(layer "In5.Cu")
		(hatch none 0.5)
		(connect_pads
			(clearance 0)
		)
		(min_thickness 0.25)
		(keepout
			(tracks not_allowed)
			(vias allowed)
			(pads allowed)
			(copperpour not_allowed)
			(footprints allowed)
		)
		(placement
			(enabled no)
			(sheetname "")
		)
		(fill
			(thermal_gap 0.5)
			(thermal_bridge_width 0.5)
			(island_removal_mode 0)
		)
		(polygon
			(pts
				(arc
					(start 101.34727 -51.912266)
					(mid 100.95577 -51.64473)
					(end 100.641912 -52.00015)
				)
				(arc
					(start 100.641912 -52.999894)
					(mid 100.999925 -53.358288)
					(end 101.358192 -53.000148)
				)
				(arc
					(start 101.358192 -52.637182)
					(mid 101.315782 -52.646719)
					(end 101.272594 -52.65166)
				)
				(xy 101.271832 -52.652422)
				(arc
					(start 101.088952 -52.652422)
					(mid 101.066501 -52.661721)
					(end 101.057202 -52.684172)
				)
				(arc
					(start 101.057202 -52.765706)
					(mid 101.000052 -53.241455)
					(end 100.942902 -52.765706)
				)
				(xy 100.942902 -52.66055)
				(arc
					(start 100.945188 -52.658264)
					(mid 100.985658 -52.580878)
					(end 101.063044 -52.540408)
				)
				(xy 101.06533 -52.538122)
				(arc
					(start 101.248718 -52.538122)
					(mid 101.304506 -52.532652)
					(end 101.358192 -52.516532)
				)
				(arc
					(start 101.358192 -52.431442)
					(mid 101.317305 -52.450395)
					(end 101.273356 -52.460398)
				)
				(xy 101.271832 -52.461922) (xy 101.06533 -52.461922)
				(arc
					(start 101.063044 -52.459636)
					(mid 100.985658 -52.419166)
					(end 100.945188 -52.34178)
				)
				(xy 100.942902 -52.339494)
				(arc
					(start 100.942902 -52.234592)
					(mid 101.000052 -51.758843)
					(end 101.057202 -52.234592)
				)
				(arc
					(start 101.057202 -52.315872)
					(mid 101.066501 -52.338323)
					(end 101.088952 -52.347622)
				)
				(arc
					(start 101.24821 -52.347622)
					(mid 101.286133 -52.340096)
					(end 101.318314 -52.318666)
				)
				(arc
					(start 101.318314 -52.318666)
					(mid 101.339752 -52.286488)
					(end 101.34727 -52.248562)
				)
			)
		)
	)
	(zone
		(layer "In5.Cu")
		(hatch none 0.5)
		(connect_pads
			(clearance 0)
		)
		(min_thickness 0.25)
		(keepout
			(tracks not_allowed)
			(vias allowed)
			(pads allowed)
			(copperpour not_allowed)
			(footprints allowed)
		)
		(placement
			(enabled no)
			(sheetname "")
		)
		(fill
			(thermal_gap 0.5)
			(thermal_bridge_width 0.5)
			(island_removal_mode 0)
		)
		(polygon
			(pts
				(arc
					(start 189.561216 -2.600198)
					(mid 188.999876 -2.038858)
					(end 188.438536 -2.600198)
				)
				(arc
					(start 188.438536 -3.061462)
					(mid 188.47627 -3.056357)
					(end 188.514228 -3.053334)
				)
				(xy 188.51499 -3.052572)
				(arc
					(start 188.833252 -3.052572)
					(mid 188.88665 -3.033437)
					(end 188.915802 -2.984754)
				)
				(arc
					(start 188.915802 -2.984754)
					(mid 189.001679 -2.206452)
					(end 189.082426 -2.985262)
				)
				(xy 189.082426 -3.002788)
				(arc
					(start 189.079632 -3.005328)
					(mid 189.009405 -3.144651)
					(end 188.870082 -3.214878)
				)
				(xy 188.867542 -3.217672)
				(arc
					(start 188.54928 -3.217672)
					(mid 188.493599 -3.220595)
					(end 188.438536 -3.229356)
				)
				(arc
					(start 188.438536 -3.39979)
					(mid 188.475478 -3.390228)
					(end 188.513212 -3.38455)
				)
				(xy 188.51499 -3.382772) (xy 188.867796 -3.382772)
				(arc
					(start 188.870336 -3.385566)
					(mid 189.009481 -3.455717)
					(end 189.079632 -3.594862)
				)
				(xy 189.082426 -3.597402)
				(arc
					(start 189.082426 -3.614928)
					(mid 189.001679 -4.393697)
					(end 188.915802 -3.615436)
				)
				(arc
					(start 188.915802 -3.615436)
					(mid 188.886766 -3.566882)
					(end 188.833506 -3.547872)
				)
				(arc
					(start 188.54928 -3.547872)
					(mid 188.491481 -3.556256)
					(end 188.438536 -3.580892)
				)
				(arc
					(start 188.438536 -3.999738)
					(mid 188.999749 -4.561332)
					(end 189.561216 -3.999992)
				)
			)
		)
	)
	(zone
		(layer "In5.Cu")
		(hatch none 0.5)
		(connect_pads
			(clearance 0)
		)
		(min_thickness 0.25)
		(keepout
			(tracks not_allowed)
			(vias allowed)
			(pads allowed)
			(copperpour not_allowed)
			(footprints allowed)
		)
		(placement
			(enabled no)
			(sheetname "")
		)
		(fill
			(thermal_gap 0.5)
			(thermal_bridge_width 0.5)
			(island_removal_mode 0)
		)
		(polygon
			(pts
				(arc
					(start 176.75225 -23.103332)
					(mid 176.36871 -22.719792)
					(end 175.98517 -23.103332)
				)
				(arc
					(start 175.98517 -23.992078)
					(mid 176.368583 -24.375872)
					(end 176.75225 -23.992332)
				)
				(xy 176.75225 -23.795482)
				(arc
					(start 176.64811 -23.795482)
					(mid 176.60626 -23.799976)
					(end 176.566322 -23.813262)
				)
				(arc
					(start 176.566322 -23.813262)
					(mid 176.245941 -24.229069)
					(end 176.401222 -23.727664)
				)
				(arc
					(start 176.401222 -23.727664)
					(mid 176.498797 -23.662622)
					(end 176.612042 -23.63216)
				)
				(xy 176.61382 -23.630382) (xy 176.75225 -23.630382) (xy 176.75225 -23.465282) (xy 176.61382 -23.465282)
				(arc
					(start 176.612042 -23.463504)
					(mid 176.498784 -23.433069)
					(end 176.401222 -23.368)
				)
				(arc
					(start 176.401222 -23.368)
					(mid 176.24595 -22.866612)
					(end 176.566322 -23.282402)
				)
				(arc
					(start 176.566322 -23.282402)
					(mid 176.606262 -23.295679)
					(end 176.64811 -23.300182)
				)
				(xy 176.75225 -23.300182)
			)
		)
	)
	(zone
		(layer "In5.Cu")
		(hatch none 0.5)
		(connect_pads
			(clearance 0)
		)
		(min_thickness 0.25)
		(keepout
			(tracks not_allowed)
			(vias allowed)
			(pads allowed)
			(copperpour not_allowed)
			(footprints allowed)
		)
		(placement
			(enabled no)
			(sheetname "")
		)
		(fill
			(thermal_gap 0.5)
			(thermal_bridge_width 0.5)
			(island_removal_mode 0)
		)
		(polygon
			(pts
				(arc
					(start 86.561422 -10.999978)
					(mid 86.000082 -10.438638)
					(end 85.438742 -10.999978)
				)
				(xy 85.438742 -11.484864) (xy 85.44433 -11.48461) (xy 85.444838 -11.484102)
				(arc
					(start 85.820758 -11.484102)
					(mid 85.895225 -11.456991)
					(end 85.934804 -11.388344)
				)
				(arc
					(start 85.934804 -11.388344)
					(mid 86.00098 -10.606165)
					(end 86.063582 -11.388598)
				)
				(xy 86.063582 -11.394694)
				(arc
					(start 86.062058 -11.396218)
					(mid 85.992523 -11.540043)
					(end 85.848698 -11.609578)
				)
				(xy 85.847174 -11.611102) (xy 85.471254 -11.611102) (xy 85.438742 -11.612118) (xy 85.438742 -11.79068)
				(xy 85.443822 -11.790172) (xy 85.444838 -11.788902) (xy 85.847174 -11.788902)
				(arc
					(start 85.848698 -11.790426)
					(mid 85.992523 -11.859961)
					(end 86.062058 -12.003786)
				)
				(xy 86.063582 -12.00531)
				(arc
					(start 86.063582 -12.011406)
					(mid 86.00098 -12.793799)
					(end 85.934804 -12.01166)
				)
				(arc
					(start 85.934804 -12.01166)
					(mid 85.895208 -11.943033)
					(end 85.820758 -11.915902)
				)
				(arc
					(start 85.471254 -11.915902)
					(mid 85.454938 -11.916602)
					(end 85.438742 -11.918696)
				)
				(arc
					(start 85.438742 -12.399772)
					(mid 85.999955 -12.961366)
					(end 86.561422 -12.400026)
				)
			)
		)
	)
	(zone
		(layer "In5.Cu")
		(hatch none 0.5)
		(connect_pads
			(clearance 0)
		)
		(min_thickness 0.25)
		(keepout
			(tracks not_allowed)
			(vias allowed)
			(pads allowed)
			(copperpour not_allowed)
			(footprints allowed)
		)
		(placement
			(enabled no)
			(sheetname "")
		)
		(fill
			(thermal_gap 0.5)
			(thermal_bridge_width 0.5)
			(island_removal_mode 0)
		)
		(polygon
			(pts
				(arc
					(start 147.761452 -10.999978)
					(mid 147.200112 -10.438638)
					(end 146.638772 -10.999978)
				)
				(xy 146.638772 -11.485118) (xy 146.64436 -11.48461) (xy 146.644868 -11.484102)
				(arc
					(start 147.020788 -11.484102)
					(mid 147.095255 -11.456991)
					(end 147.134834 -11.388344)
				)
				(arc
					(start 147.134834 -11.388344)
					(mid 147.20101 -10.606165)
					(end 147.263612 -11.388598)
				)
				(xy 147.263612 -11.394694)
				(arc
					(start 147.262088 -11.396218)
					(mid 147.192553 -11.540043)
					(end 147.048728 -11.609578)
				)
				(xy 147.047204 -11.611102) (xy 146.671284 -11.611102) (xy 146.638772 -11.612372) (xy 146.638772 -11.79068)
				(xy 146.643598 -11.790172) (xy 146.644868 -11.788902) (xy 147.047204 -11.788902)
				(arc
					(start 147.048728 -11.790426)
					(mid 147.192553 -11.859961)
					(end 147.262088 -12.003786)
				)
				(xy 147.263612 -12.00531)
				(arc
					(start 147.263612 -12.011406)
					(mid 147.20101 -12.793799)
					(end 147.134834 -12.01166)
				)
				(arc
					(start 147.134834 -12.01166)
					(mid 147.095238 -11.943033)
					(end 147.020788 -11.915902)
				)
				(arc
					(start 146.671284 -11.915902)
					(mid 146.654934 -11.91682)
					(end 146.638772 -11.919458)
				)
				(arc
					(start 146.638772 -12.399772)
					(mid 147.199985 -12.961366)
					(end 147.761452 -12.400026)
				)
			)
		)
	)
	(zone
		(layer "In5.Cu")
		(hatch none 0.5)
		(connect_pads
			(clearance 0)
		)
		(min_thickness 0.25)
		(keepout
			(tracks not_allowed)
			(vias allowed)
			(pads allowed)
			(copperpour not_allowed)
			(footprints allowed)
		)
		(placement
			(enabled no)
			(sheetname "")
		)
		(fill
			(thermal_gap 0.5)
			(thermal_bridge_width 0.5)
			(island_removal_mode 0)
		)
		(polygon
			(pts
				(xy 138.479276 -76.14158) (xy 138.479022 -76.141834)
				(arc
					(start 138.479022 -76.142342)
					(mid 138.096244 -76.52512)
					(end 138.479022 -76.907898)
				)
				(xy 138.479022 -76.90866) (xy 138.834876 -76.90866) (xy 138.834622 -76.908406)
				(arc
					(start 138.834622 -76.687426)
					(mid 138.827165 -76.649669)
					(end 138.80592 -76.617576)
				)
				(arc
					(start 138.805666 -76.617576)
					(mid 138.774673 -76.596579)
					(end 138.738102 -76.58862)
				)
				(arc
					(start 138.738102 -76.58862)
					(mid 138.212274 -76.52512)
					(end 138.738102 -76.46162)
				)
				(xy 138.761978 -76.46162)
				(arc
					(start 138.763502 -76.463398)
					(mid 138.822097 -76.478744)
					(end 138.8745 -76.509118)
				)
				(xy 138.87704 -76.509118) (xy 138.914378 -76.546456)
				(arc
					(start 138.914378 -76.54925)
					(mid 138.944496 -76.60132)
					(end 138.959844 -76.659486)
				)
				(xy 138.961622 -76.66101) (xy 138.961622 -76.88199) (xy 138.96213 -76.90866) (xy 139.139676 -76.90866)
				(xy 139.139422 -76.908406) (xy 139.139422 -76.675996)
				(arc
					(start 139.1412 -76.674472)
					(mid 139.15791 -76.610274)
					(end 139.191492 -76.55306)
				)
				(xy 139.191492 -76.550774) (xy 139.20978 -76.532486) (xy 139.210034 -76.532232) (xy 139.232132 -76.510134)
				(xy 139.23264 -76.509626) (xy 139.250674 -76.491592)
				(arc
					(start 139.25423 -76.491592)
					(mid 139.285624 -76.474278)
					(end 139.320016 -76.46416)
				)
				(xy 139.322556 -76.46162)
				(arc
					(start 139.362942 -76.46162)
					(mid 139.88877 -76.52512)
					(end 139.362942 -76.58862)
				)
				(arc
					(start 139.348972 -76.58862)
					(mid 139.334558 -76.591452)
					(end 139.322302 -76.599542)
				)
				(xy 139.29995 -76.622148)
				(arc
					(start 139.299696 -76.622402)
					(mid 139.27511 -76.659109)
					(end 139.266422 -76.702412)
				)
				(xy 139.266422 -76.88199) (xy 139.267184 -76.90866) (xy 139.622022 -76.90866)
				(arc
					(start 139.622022 -76.907898)
					(mid 140.0048 -76.52512)
					(end 139.622022 -76.142342)
				)
				(xy 139.622022 -76.14158)
			)
		)
	)
	(zone
		(layer "In5.Cu")
		(hatch none 0.5)
		(connect_pads
			(clearance 0)
		)
		(min_thickness 0.25)
		(keepout
			(tracks not_allowed)
			(vias allowed)
			(pads allowed)
			(copperpour not_allowed)
			(footprints allowed)
		)
		(placement
			(enabled no)
			(sheetname "")
		)
		(fill
			(thermal_gap 0.5)
			(thermal_bridge_width 0.5)
			(island_removal_mode 0)
		)
		(polygon
			(pts
				(arc
					(start 107.347258 -51.912266)
					(mid 106.955758 -51.64473)
					(end 106.6419 -52.00015)
				)
				(arc
					(start 106.6419 -52.999894)
					(mid 106.999913 -53.358288)
					(end 107.35818 -53.000148)
				)
				(arc
					(start 107.35818 -52.628038)
					(mid 107.298936 -52.644052)
					(end 107.238038 -52.65166)
				)
				(xy 107.237276 -52.652422)
				(arc
					(start 107.08894 -52.652422)
					(mid 107.066489 -52.661721)
					(end 107.05719 -52.684172)
				)
				(arc
					(start 107.05719 -52.765706)
					(mid 107.00004 -53.241455)
					(end 106.94289 -52.765706)
				)
				(xy 106.94289 -52.66055)
				(arc
					(start 106.945176 -52.658264)
					(mid 106.985646 -52.580878)
					(end 107.063032 -52.540408)
				)
				(xy 107.065318 -52.538122)
				(arc
					(start 107.214162 -52.538122)
					(mid 107.288128 -52.529569)
					(end 107.35818 -52.50434)
				)
				(arc
					(start 107.35818 -52.41544)
					(mid 107.301331 -52.445904)
					(end 107.238546 -52.460652)
				)
				(xy 107.237276 -52.461922) (xy 107.065318 -52.461922)
				(arc
					(start 107.063032 -52.459636)
					(mid 106.985646 -52.419166)
					(end 106.945176 -52.34178)
				)
				(xy 106.94289 -52.339494)
				(arc
					(start 106.94289 -52.234592)
					(mid 107.00004 -51.758843)
					(end 107.05719 -52.234592)
				)
				(arc
					(start 107.05719 -52.315872)
					(mid 107.066489 -52.338323)
					(end 107.08894 -52.347622)
				)
				(arc
					(start 107.213654 -52.347622)
					(mid 107.264782 -52.337452)
					(end 107.308142 -52.308506)
				)
				(arc
					(start 107.308142 -52.308506)
					(mid 107.337109 -52.265155)
					(end 107.347258 -52.214018)
				)
			)
		)
	)
	(zone
		(layer "In5.Cu")
		(hatch none 0.5)
		(connect_pads
			(clearance 0)
		)
		(min_thickness 0.25)
		(keepout
			(tracks not_allowed)
			(vias allowed)
			(pads allowed)
			(copperpour not_allowed)
			(footprints allowed)
		)
		(placement
			(enabled no)
			(sheetname "")
		)
		(fill
			(thermal_gap 0.5)
			(thermal_bridge_width 0.5)
			(island_removal_mode 0)
		)
		(polygon
			(pts
				(arc
					(start 133.36143 -10.999978)
					(mid 132.80009 -10.438638)
					(end 132.23875 -10.999978)
				)
				(xy 132.23875 -11.485118) (xy 132.244338 -11.48461) (xy 132.244846 -11.484102)
				(arc
					(start 132.620766 -11.484102)
					(mid 132.695233 -11.456991)
					(end 132.734812 -11.388344)
				)
				(arc
					(start 132.734812 -11.388344)
					(mid 132.800988 -10.606165)
					(end 132.86359 -11.388598)
				)
				(xy 132.86359 -11.394694)
				(arc
					(start 132.862066 -11.396218)
					(mid 132.792531 -11.540043)
					(end 132.648706 -11.609578)
				)
				(xy 132.647182 -11.611102) (xy 132.271262 -11.611102) (xy 132.23875 -11.612372) (xy 132.23875 -11.79068)
				(xy 132.243576 -11.790172) (xy 132.244846 -11.788902) (xy 132.647182 -11.788902)
				(arc
					(start 132.648706 -11.790426)
					(mid 132.792531 -11.859961)
					(end 132.862066 -12.003786)
				)
				(xy 132.86359 -12.00531)
				(arc
					(start 132.86359 -12.011406)
					(mid 132.800988 -12.793799)
					(end 132.734812 -12.01166)
				)
				(arc
					(start 132.734812 -12.01166)
					(mid 132.695216 -11.943033)
					(end 132.620766 -11.915902)
				)
				(arc
					(start 132.271262 -11.915902)
					(mid 132.254912 -11.91682)
					(end 132.23875 -11.919458)
				)
				(arc
					(start 132.23875 -12.399772)
					(mid 132.799963 -12.961366)
					(end 133.36143 -12.400026)
				)
			)
		)
	)
	(zone
		(layer "In5.Cu")
		(hatch none 0.5)
		(connect_pads
			(clearance 0)
		)
		(min_thickness 0.25)
		(keepout
			(tracks not_allowed)
			(vias allowed)
			(pads allowed)
			(copperpour not_allowed)
			(footprints allowed)
		)
		(placement
			(enabled no)
			(sheetname "")
		)
		(fill
			(thermal_gap 0.5)
			(thermal_bridge_width 0.5)
			(island_removal_mode 0)
		)
		(polygon
			(pts
				(arc
					(start 100.350066 -50.924206)
					(mid 99.961863 -50.644037)
					(end 99.641914 -51.000152)
				)
				(arc
					(start 99.641914 -51.999896)
					(mid 99.999927 -52.35829)
					(end 100.358194 -52.00015)
				)
				(arc
					(start 100.358194 -51.643026)
					(mid 100.330939 -51.648469)
					(end 100.30333 -51.651662)
				)
				(xy 100.302314 -51.652424) (xy 100.279962 -51.652424) (xy 100.278692 -51.652424)
				(arc
					(start 100.088954 -51.652424)
					(mid 100.066503 -51.661723)
					(end 100.057204 -51.684174)
				)
				(arc
					(start 100.057204 -51.765708)
					(mid 100.000054 -52.241457)
					(end 99.942904 -51.765708)
				)
				(xy 99.942904 -51.660552)
				(arc
					(start 99.94519 -51.658266)
					(mid 99.98566 -51.58088)
					(end 100.063046 -51.54041)
				)
				(xy 100.065332 -51.538124)
				(arc
					(start 100.279708 -51.538124)
					(mid 100.319602 -51.534421)
					(end 100.358194 -51.523646)
				)
				(arc
					(start 100.358194 -51.43881)
					(mid 100.332555 -51.451865)
					(end 100.304854 -51.459638)
				)
				(xy 100.302568 -51.461924) (xy 100.279454 -51.461924) (xy 100.278946 -51.461924) (xy 100.065332 -51.461924)
				(arc
					(start 100.063046 -51.459638)
					(mid 99.98566 -51.419168)
					(end 99.94519 -51.341782)
				)
				(xy 99.942904 -51.339496)
				(arc
					(start 99.942904 -51.234594)
					(mid 100.000054 -50.758845)
					(end 100.057204 -51.234594)
				)
				(arc
					(start 100.057204 -51.315874)
					(mid 100.066503 -51.338325)
					(end 100.088954 -51.347624)
				)
				(arc
					(start 100.279454 -51.347624)
					(mid 100.291415 -51.345078)
					(end 100.301552 -51.338226)
				)
				(arc
					(start 100.32238 -51.317398)
					(mid 100.342882 -51.285927)
					(end 100.350066 -51.249072)
				)
			)
		)
	)
	(zone
		(layer "In5.Cu")
		(hatch none 0.5)
		(connect_pads
			(clearance 0)
		)
		(min_thickness 0.25)
		(keepout
			(tracks not_allowed)
			(vias allowed)
			(pads allowed)
			(copperpour not_allowed)
			(footprints allowed)
		)
		(placement
			(enabled no)
			(sheetname "")
		)
		(fill
			(thermal_gap 0.5)
			(thermal_bridge_width 0.5)
			(island_removal_mode 0)
		)
		(polygon
			(pts
				(arc
					(start 130.000248 -61.64199)
					(mid 129.641854 -62.000003)
					(end 129.999994 -62.35827)
				)
				(arc
					(start 130.355086 -62.35827)
					(mid 130.350807 -62.333368)
					(end 130.348228 -62.308232)
				)
				(xy 130.347466 -62.30747)
				(arc
					(start 130.347466 -62.08903)
					(mid 130.338167 -62.066579)
					(end 130.315716 -62.05728)
				)
				(arc
					(start 130.234436 -62.05728)
					(mid 129.758687 -62.00013)
					(end 130.234436 -61.94298)
				)
				(xy 130.339338 -61.94298)
				(arc
					(start 130.341624 -61.945266)
					(mid 130.41901 -61.985736)
					(end 130.45948 -62.063122)
				)
				(xy 130.461766 -62.065408)
				(arc
					(start 130.461766 -62.284356)
					(mid 130.464517 -62.321713)
					(end 130.472688 -62.35827)
				)
				(arc
					(start 130.554222 -62.35827)
					(mid 130.545208 -62.334282)
					(end 130.539744 -62.309248)
				)
				(xy 130.537966 -62.30747) (xy 130.537966 -62.065408)
				(arc
					(start 130.540252 -62.063122)
					(mid 130.580722 -61.985736)
					(end 130.658108 -61.945266)
				)
				(xy 130.660394 -61.94298)
				(arc
					(start 130.76555 -61.94298)
					(mid 131.241299 -62.00013)
					(end 130.76555 -62.05728)
				)
				(arc
					(start 130.684016 -62.05728)
					(mid 130.661565 -62.066579)
					(end 130.652266 -62.08903)
				)
				(arc
					(start 130.652266 -62.283848)
					(mid 130.657158 -62.30844)
					(end 130.671062 -62.329314)
				)
				(arc
					(start 130.671062 -62.329314)
					(mid 130.691922 -62.343252)
					(end 130.716528 -62.34811)
				)
				(arc
					(start 131.084574 -62.34811)
					(mid 131.355562 -61.957537)
					(end 130.999992 -61.64199)
				)
			)
		)
	)
	(zone
		(layer "In5.Cu")
		(hatch none 0.5)
		(connect_pads
			(clearance 0)
		)
		(min_thickness 0.25)
		(keepout
			(tracks not_allowed)
			(vias allowed)
			(pads allowed)
			(copperpour not_allowed)
			(footprints allowed)
		)
		(placement
			(enabled no)
			(sheetname "")
		)
		(fill
			(thermal_gap 0.5)
			(thermal_bridge_width 0.5)
			(island_removal_mode 0)
		)
		(polygon
			(pts
				(arc
					(start 129.00025 -62.641988)
					(mid 128.641856 -63.000001)
					(end 128.999996 -63.358268)
				)
				(arc
					(start 129.369058 -63.358268)
					(mid 129.355024 -63.303962)
					(end 129.34823 -63.248286)
				)
				(xy 129.347468 -63.247524)
				(arc
					(start 129.347468 -63.089028)
					(mid 129.338169 -63.066577)
					(end 129.315718 -63.057278)
				)
				(arc
					(start 129.234438 -63.057278)
					(mid 128.758689 -63.000128)
					(end 129.234438 -62.942978)
				)
				(xy 129.33934 -62.942978)
				(arc
					(start 129.341626 -62.945264)
					(mid 129.419012 -62.985734)
					(end 129.459482 -63.06312)
				)
				(xy 129.461768 -63.065406)
				(arc
					(start 129.461768 -63.22441)
					(mid 129.469434 -63.293024)
					(end 129.491994 -63.358268)
				)
				(arc
					(start 129.579878 -63.358268)
					(mid 129.5527 -63.306076)
					(end 129.539238 -63.248794)
				)
				(xy 129.537968 -63.247524) (xy 129.537968 -63.065406)
				(arc
					(start 129.540254 -63.06312)
					(mid 129.580724 -62.985734)
					(end 129.65811 -62.945264)
				)
				(xy 129.660396 -62.942978)
				(arc
					(start 129.765552 -62.942978)
					(mid 130.241301 -63.000128)
					(end 129.765552 -63.057278)
				)
				(arc
					(start 129.684018 -63.057278)
					(mid 129.661567 -63.066577)
					(end 129.652268 -63.089028)
				)
				(arc
					(start 129.652268 -63.223902)
					(mid 129.661572 -63.270767)
					(end 129.688082 -63.310516)
				)
				(arc
					(start 129.688082 -63.310516)
					(mid 129.727835 -63.337015)
					(end 129.774696 -63.34633)
				)
				(arc
					(start 130.091688 -63.34633)
					(mid 130.355136 -62.953894)
					(end 129.999994 -62.641988)
				)
			)
		)
	)
	(zone
		(layer "In5.Cu")
		(hatch none 0.5)
		(connect_pads
			(clearance 0)
		)
		(min_thickness 0.25)
		(keepout
			(tracks not_allowed)
			(vias allowed)
			(pads allowed)
			(copperpour not_allowed)
			(footprints allowed)
		)
		(placement
			(enabled no)
			(sheetname "")
		)
		(fill
			(thermal_gap 0.5)
			(thermal_bridge_width 0.5)
			(island_removal_mode 0)
		)
		(polygon
			(pts
				(arc
					(start 124.358146 -52.00015)
					(mid 124.000006 -51.64201)
					(end 123.641866 -52.00015)
				)
				(arc
					(start 123.641866 -52.999894)
					(mid 123.999879 -53.358288)
					(end 124.358146 -53.000148)
				)
				(xy 124.358146 -52.652422)
				(arc
					(start 124.088906 -52.652422)
					(mid 124.066455 -52.661721)
					(end 124.057156 -52.684172)
				)
				(arc
					(start 124.057156 -52.765706)
					(mid 124.000006 -53.241455)
					(end 123.942856 -52.765706)
				)
				(xy 123.942856 -52.66055)
				(arc
					(start 123.945142 -52.658264)
					(mid 123.985612 -52.580878)
					(end 124.062998 -52.540408)
				)
				(xy 124.065284 -52.538122) (xy 124.358146 -52.538122) (xy 124.358146 -52.461922) (xy 124.065284 -52.461922)
				(arc
					(start 124.062998 -52.459636)
					(mid 123.985612 -52.419166)
					(end 123.945142 -52.34178)
				)
				(xy 123.942856 -52.339494)
				(arc
					(start 123.942856 -52.234592)
					(mid 124.000006 -51.758843)
					(end 124.057156 -52.234592)
				)
				(arc
					(start 124.057156 -52.315872)
					(mid 124.066455 -52.338323)
					(end 124.088906 -52.347622)
				)
				(xy 124.358146 -52.347622)
			)
		)
	)
	(zone
		(net "PCE_AVDD")
		(layer "In5.Cu")
		(hatch none 0.5)
		(connect_pads
			(clearance 0.5)
		)
		(min_thickness 0.25)
		(fill yes
			(thermal_gap 0.5)
			(thermal_bridge_width 0.5)
			(island_removal_mode 0)
		)
		(polygon
			(pts
				(xy 177.7238 -27.04846) (xy 167.594534 -27.04846) (xy 167.03294 -27.04846) (xy 166.6748 -27.4066)
				(xy 166.6748 -28.97632) (xy 166.86784 -29.16936) (xy 174.35576 -29.16936) (xy 174.5488 -29.3624)
				(xy 175.4124 -29.3624) (xy 176.149 -30.099) (xy 176.2252 -30.1752) (xy 176.2252 -32.258) (xy 176.2125 -32.2707)
				(xy 176.2125 -32.9819) (xy 175.9966 -33.1978) (xy 175.514 -33.1978) (xy 174.6758 -32.3596) (xy 169.2656 -32.3596)
				(xy 169.0624 -32.5628) (xy 169.0624 -33.935924) (xy 169.2656 -34.139124) (xy 176.170844 -34.139124)
				(xy 176.948084 -33.361884) (xy 176.948084 -29.503116) (xy 178.0794 -28.3718) (xy 178.0794 -27.40406)
			)
		)
	)
	(zone
		(layer "In5.Cu")
		(hatch none 0.5)
		(connect_pads
			(clearance 0)
		)
		(min_thickness 0.25)
		(keepout
			(tracks not_allowed)
			(vias allowed)
			(pads allowed)
			(copperpour not_allowed)
			(footprints allowed)
		)
		(placement
			(enabled no)
			(sheetname "")
		)
		(fill
			(thermal_gap 0.5)
			(thermal_bridge_width 0.5)
			(island_removal_mode 0)
		)
		(polygon
			(pts
				(arc
					(start 138.76147 -9.800082)
					(mid 138.20013 -9.238742)
					(end 137.63879 -9.800082)
				)
				(xy 137.63879 -10.285222) (xy 137.644378 -10.284714) (xy 137.644886 -10.284206)
				(arc
					(start 138.020806 -10.284206)
					(mid 138.095273 -10.257095)
					(end 138.134852 -10.188448)
				)
				(arc
					(start 138.134852 -10.188448)
					(mid 138.201028 -9.406269)
					(end 138.26363 -10.188702)
				)
				(xy 138.26363 -10.194798)
				(arc
					(start 138.262106 -10.196322)
					(mid 138.192571 -10.340147)
					(end 138.048746 -10.409682)
				)
				(xy 138.047222 -10.411206) (xy 137.671302 -10.411206) (xy 137.63879 -10.412476) (xy 137.63879 -10.590784)
				(xy 137.643616 -10.590276) (xy 137.644886 -10.589006) (xy 138.047222 -10.589006)
				(arc
					(start 138.048746 -10.59053)
					(mid 138.192571 -10.660065)
					(end 138.262106 -10.80389)
				)
				(xy 138.26363 -10.805414)
				(arc
					(start 138.26363 -10.81151)
					(mid 138.201028 -11.593903)
					(end 138.134852 -10.811764)
				)
				(arc
					(start 138.134852 -10.811764)
					(mid 138.095256 -10.743137)
					(end 138.020806 -10.716006)
				)
				(arc
					(start 137.671302 -10.716006)
					(mid 137.654951 -10.716922)
					(end 137.63879 -10.719562)
				)
				(arc
					(start 137.63879 -11.199876)
					(mid 138.200003 -11.76147)
					(end 138.76147 -11.20013)
				)
			)
		)
	)
	(zone
		(layer "In5.Cu")
		(hatch none 0.5)
		(connect_pads
			(clearance 0)
		)
		(min_thickness 0.25)
		(keepout
			(tracks not_allowed)
			(vias allowed)
			(pads allowed)
			(copperpour not_allowed)
			(footprints allowed)
		)
		(placement
			(enabled no)
			(sheetname "")
		)
		(fill
			(thermal_gap 0.5)
			(thermal_bridge_width 0.5)
			(island_removal_mode 0)
		)
		(polygon
			(pts
				(arc
					(start 129.00025 -60.641992)
					(mid 128.641856 -61.000005)
					(end 128.999996 -61.358272)
				)
				(arc
					(start 129.366772 -61.358272)
					(mid 129.354341 -61.307792)
					(end 129.34823 -61.256164)
				)
				(xy 129.347468 -61.255402)
				(arc
					(start 129.347468 -61.089032)
					(mid 129.338169 -61.066581)
					(end 129.315718 -61.057282)
				)
				(arc
					(start 129.234438 -61.057282)
					(mid 128.758689 -61.000132)
					(end 129.234438 -60.942982)
				)
				(xy 129.33934 -60.942982)
				(arc
					(start 129.341626 -60.945268)
					(mid 129.419012 -60.985738)
					(end 129.459482 -61.063124)
				)
				(xy 129.461768 -61.06541)
				(arc
					(start 129.461768 -61.232288)
					(mid 129.468635 -61.296731)
					(end 129.488946 -61.358272)
				)
				(arc
					(start 129.576068 -61.358272)
					(mid 129.551643 -61.309787)
					(end 129.539238 -61.256926)
				)
				(xy 129.537968 -61.255402) (xy 129.537968 -61.06541)
				(arc
					(start 129.540254 -61.063124)
					(mid 129.580724 -60.985738)
					(end 129.65811 -60.945268)
				)
				(xy 129.660396 -60.942982)
				(arc
					(start 129.765552 -60.942982)
					(mid 130.241301 -61.000132)
					(end 129.765552 -61.057282)
				)
				(arc
					(start 129.684018 -61.057282)
					(mid 129.661567 -61.066581)
					(end 129.652268 -61.089032)
				)
				(arc
					(start 129.652268 -61.23178)
					(mid 129.661046 -61.27591)
					(end 129.68605 -61.313314)
				)
				(arc
					(start 129.68605 -61.313314)
					(mid 129.723677 -61.338519)
					(end 129.768092 -61.34735)
				)
				(arc
					(start 130.087878 -61.34735)
					(mid 130.255922 -61.250701)
					(end 130.34899 -61.08065)
				)
				(arc
					(start 130.34899 -60.919614)
					(mid 130.222977 -60.719846)
					(end 129.999994 -60.641992)
				)
			)
		)
	)
	(zone
		(layer "In5.Cu")
		(hatch none 0.5)
		(connect_pads
			(clearance 0)
		)
		(min_thickness 0.25)
		(keepout
			(tracks not_allowed)
			(vias allowed)
			(pads allowed)
			(copperpour not_allowed)
			(footprints allowed)
		)
		(placement
			(enabled no)
			(sheetname "")
		)
		(fill
			(thermal_gap 0.5)
			(thermal_bridge_width 0.5)
			(island_removal_mode 0)
		)
		(polygon
			(pts
				(arc
					(start 121.351548 -50.931572)
					(mid 120.965562 -50.64365)
					(end 120.641872 -51.000152)
				)
				(arc
					(start 120.641872 -51.999896)
					(mid 120.999885 -52.35829)
					(end 121.358152 -52.00015)
				)
				(arc
					(start 121.358152 -51.616102)
					(mid 121.281856 -51.640767)
					(end 121.20245 -51.651916)
				)
				(xy 121.201688 -51.652424)
				(arc
					(start 121.088912 -51.652424)
					(mid 121.066461 -51.661723)
					(end 121.057162 -51.684174)
				)
				(arc
					(start 121.057162 -51.765708)
					(mid 121.000012 -52.241457)
					(end 120.942862 -51.765708)
				)
				(xy 120.942862 -51.660552)
				(arc
					(start 120.945148 -51.658266)
					(mid 120.985618 -51.58088)
					(end 121.063004 -51.54041)
				)
				(xy 121.06529 -51.538124)
				(arc
					(start 121.178574 -51.538124)
					(mid 121.271758 -51.525303)
					(end 121.358152 -51.488086)
				)
				(xy 121.358152 -51.394614) (xy 121.353834 -51.398932)
				(arc
					(start 121.35231 -51.398932)
					(mid 121.282345 -51.441285)
					(end 121.202958 -51.460908)
				)
				(xy 121.201688 -51.461924) (xy 121.06529 -51.461924)
				(arc
					(start 121.063004 -51.459638)
					(mid 120.985618 -51.419168)
					(end 120.945148 -51.341782)
				)
				(xy 120.942862 -51.339496)
				(arc
					(start 120.942862 -51.234594)
					(mid 121.000012 -50.758845)
					(end 121.057162 -51.234594)
				)
				(arc
					(start 121.057162 -51.315874)
					(mid 121.066461 -51.338325)
					(end 121.088912 -51.347624)
				)
				(arc
					(start 121.178066 -51.347624)
					(mid 121.23854 -51.335613)
					(end 121.289826 -51.301396)
				)
				(arc
					(start 121.2977 -51.293522)
					(mid 121.337539 -51.233711)
					(end 121.351548 -51.16322)
				)
			)
		)
	)
	(zone
		(layer "In5.Cu")
		(hatch none 0.5)
		(connect_pads
			(clearance 0)
		)
		(min_thickness 0.25)
		(keepout
			(tracks not_allowed)
			(vias allowed)
			(pads allowed)
			(copperpour not_allowed)
			(footprints allowed)
		)
		(placement
			(enabled no)
			(sheetname "")
		)
		(fill
			(thermal_gap 0.5)
			(thermal_bridge_width 0.5)
			(island_removal_mode 0)
		)
		(polygon
			(pts
				(arc
					(start 88.36152 -9.800082)
					(mid 87.80018 -9.238742)
					(end 87.23884 -9.800082)
				)
				(xy 87.23884 -10.285222) (xy 87.244428 -10.284714) (xy 87.244936 -10.284206)
				(arc
					(start 87.620856 -10.284206)
					(mid 87.695323 -10.257095)
					(end 87.734902 -10.188448)
				)
				(arc
					(start 87.734902 -10.188448)
					(mid 87.801078 -9.406269)
					(end 87.86368 -10.188702)
				)
				(xy 87.86368 -10.194798)
				(arc
					(start 87.862156 -10.196322)
					(mid 87.792621 -10.340147)
					(end 87.648796 -10.409682)
				)
				(xy 87.647272 -10.411206) (xy 87.271352 -10.411206) (xy 87.23884 -10.412476) (xy 87.23884 -10.590784)
				(xy 87.243666 -10.590276) (xy 87.244936 -10.589006) (xy 87.647272 -10.589006)
				(arc
					(start 87.648796 -10.59053)
					(mid 87.792621 -10.660065)
					(end 87.862156 -10.80389)
				)
				(xy 87.86368 -10.805414)
				(arc
					(start 87.86368 -10.81151)
					(mid 87.801078 -11.593903)
					(end 87.734902 -10.811764)
				)
				(arc
					(start 87.734902 -10.811764)
					(mid 87.695306 -10.743137)
					(end 87.620856 -10.716006)
				)
				(arc
					(start 87.271352 -10.716006)
					(mid 87.255001 -10.716922)
					(end 87.23884 -10.719562)
				)
				(arc
					(start 87.23884 -11.199876)
					(mid 87.800053 -11.76147)
					(end 88.36152 -11.20013)
				)
			)
		)
	)
	(zone
		(layer "In5.Cu")
		(hatch none 0.5)
		(connect_pads
			(clearance 0)
		)
		(min_thickness 0.25)
		(keepout
			(tracks not_allowed)
			(vias allowed)
			(pads allowed)
			(copperpour not_allowed)
			(footprints allowed)
		)
		(placement
			(enabled no)
			(sheetname "")
		)
		(fill
			(thermal_gap 0.5)
			(thermal_bridge_width 0.5)
			(island_removal_mode 0)
		)
		(polygon
			(pts
				(arc
					(start 136.961372 -10.999978)
					(mid 136.400032 -10.438638)
					(end 135.838692 -10.999978)
				)
				(xy 135.838692 -11.485118) (xy 135.84428 -11.48461) (xy 135.844788 -11.484102)
				(arc
					(start 136.220708 -11.484102)
					(mid 136.295175 -11.456991)
					(end 136.334754 -11.388344)
				)
				(arc
					(start 136.334754 -11.388344)
					(mid 136.40093 -10.606165)
					(end 136.463532 -11.388598)
				)
				(xy 136.463532 -11.394694)
				(arc
					(start 136.462008 -11.396218)
					(mid 136.392473 -11.540043)
					(end 136.248648 -11.609578)
				)
				(xy 136.247124 -11.611102) (xy 135.871204 -11.611102) (xy 135.838692 -11.612372) (xy 135.838692 -11.79068)
				(xy 135.843518 -11.790172) (xy 135.844788 -11.788902) (xy 136.247124 -11.788902)
				(arc
					(start 136.248648 -11.790426)
					(mid 136.392473 -11.859961)
					(end 136.462008 -12.003786)
				)
				(xy 136.463532 -12.00531)
				(arc
					(start 136.463532 -12.011406)
					(mid 136.40093 -12.793799)
					(end 136.334754 -12.01166)
				)
				(arc
					(start 136.334754 -12.01166)
					(mid 136.295158 -11.943033)
					(end 136.220708 -11.915902)
				)
				(arc
					(start 135.871204 -11.915902)
					(mid 135.854854 -11.91682)
					(end 135.838692 -11.919458)
				)
				(arc
					(start 135.838692 -12.399772)
					(mid 136.399905 -12.961366)
					(end 136.961372 -12.400026)
				)
			)
		)
	)
	(zone
		(layer "In5.Cu")
		(hatch none 0.5)
		(connect_pads
			(clearance 0)
		)
		(min_thickness 0.25)
		(keepout
			(tracks not_allowed)
			(vias allowed)
			(pads allowed)
			(copperpour not_allowed)
			(footprints allowed)
		)
		(placement
			(enabled no)
			(sheetname "")
		)
		(fill
			(thermal_gap 0.5)
			(thermal_bridge_width 0.5)
			(island_removal_mode 0)
		)
		(polygon
			(pts
				(arc
					(start 120.761506 -9.800082)
					(mid 120.200166 -9.238742)
					(end 119.638826 -9.800082)
				)
				(xy 119.638826 -10.285222) (xy 119.644414 -10.284714) (xy 119.644922 -10.284206)
				(arc
					(start 120.020842 -10.284206)
					(mid 120.095309 -10.257095)
					(end 120.134888 -10.188448)
				)
				(arc
					(start 120.134888 -10.188448)
					(mid 120.201064 -9.406269)
					(end 120.263666 -10.188702)
				)
				(xy 120.263666 -10.194798)
				(arc
					(start 120.262142 -10.196322)
					(mid 120.192607 -10.340147)
					(end 120.048782 -10.409682)
				)
				(xy 120.047258 -10.411206) (xy 119.671338 -10.411206) (xy 119.638826 -10.412476) (xy 119.638826 -10.590784)
				(xy 119.643652 -10.590276) (xy 119.644922 -10.589006) (xy 120.047258 -10.589006)
				(arc
					(start 120.048782 -10.59053)
					(mid 120.192607 -10.660065)
					(end 120.262142 -10.80389)
				)
				(xy 120.263666 -10.805414)
				(arc
					(start 120.263666 -10.81151)
					(mid 120.201064 -11.593903)
					(end 120.134888 -10.811764)
				)
				(arc
					(start 120.134888 -10.811764)
					(mid 120.095292 -10.743137)
					(end 120.020842 -10.716006)
				)
				(arc
					(start 119.671338 -10.716006)
					(mid 119.654987 -10.716922)
					(end 119.638826 -10.719562)
				)
				(arc
					(start 119.638826 -11.199876)
					(mid 120.200039 -11.76147)
					(end 120.761506 -11.20013)
				)
			)
		)
	)
	(zone
		(layer "In5.Cu")
		(hatch none 0.5)
		(connect_pads
			(clearance 0)
		)
		(min_thickness 0.25)
		(keepout
			(tracks not_allowed)
			(vias allowed)
			(pads allowed)
			(copperpour not_allowed)
			(footprints allowed)
		)
		(placement
			(enabled no)
			(sheetname "")
		)
		(fill
			(thermal_gap 0.5)
			(thermal_bridge_width 0.5)
			(island_removal_mode 0)
		)
		(polygon
			(pts
				(arc
					(start 130.000248 -65.641982)
					(mid 129.641854 -65.999995)
					(end 129.999994 -66.358262)
				)
				(xy 130.347466 -66.358262)
				(arc
					(start 130.347466 -66.089022)
					(mid 130.338167 -66.066571)
					(end 130.315716 -66.057272)
				)
				(arc
					(start 130.234436 -66.057272)
					(mid 129.758687 -66.000122)
					(end 130.234436 -65.942972)
				)
				(xy 130.339338 -65.942972)
				(arc
					(start 130.341624 -65.945258)
					(mid 130.41901 -65.985728)
					(end 130.45948 -66.063114)
				)
				(xy 130.461766 -66.0654) (xy 130.461766 -66.358262) (xy 130.537966 -66.358262) (xy 130.537966 -66.0654)
				(arc
					(start 130.540252 -66.063114)
					(mid 130.580722 -65.985728)
					(end 130.658108 -65.945258)
				)
				(xy 130.660394 -65.942972)
				(arc
					(start 130.76555 -65.942972)
					(mid 131.241299 -66.000122)
					(end 130.76555 -66.057272)
				)
				(arc
					(start 130.684016 -66.057272)
					(mid 130.661565 -66.066571)
					(end 130.652266 -66.089022)
				)
				(xy 130.652266 -66.358262)
				(arc
					(start 130.999992 -66.358262)
					(mid 131.358132 -66.000122)
					(end 130.999992 -65.641982)
				)
			)
		)
	)
	(zone
		(layer "In5.Cu")
		(hatch none 0.5)
		(connect_pads
			(clearance 0)
		)
		(min_thickness 0.25)
		(keepout
			(tracks not_allowed)
			(vias allowed)
			(pads allowed)
			(copperpour not_allowed)
			(footprints allowed)
		)
		(placement
			(enabled no)
			(sheetname "")
		)
		(fill
			(thermal_gap 0.5)
			(thermal_bridge_width 0.5)
			(island_removal_mode 0)
		)
		(polygon
			(pts
				(arc
					(start 127.96139 -9.800082)
					(mid 127.40005 -9.238742)
					(end 126.83871 -9.800082)
				)
				(xy 126.83871 -10.285222) (xy 126.844298 -10.284714) (xy 126.844806 -10.284206)
				(arc
					(start 127.220726 -10.284206)
					(mid 127.295193 -10.257095)
					(end 127.334772 -10.188448)
				)
				(arc
					(start 127.334772 -10.188448)
					(mid 127.400948 -9.406269)
					(end 127.46355 -10.188702)
				)
				(xy 127.46355 -10.194798)
				(arc
					(start 127.462026 -10.196322)
					(mid 127.392491 -10.340147)
					(end 127.248666 -10.409682)
				)
				(xy 127.247142 -10.411206) (xy 126.871222 -10.411206) (xy 126.83871 -10.412476) (xy 126.83871 -10.590784)
				(xy 126.843536 -10.590276) (xy 126.844806 -10.589006) (xy 127.247142 -10.589006)
				(arc
					(start 127.248666 -10.59053)
					(mid 127.392491 -10.660065)
					(end 127.462026 -10.80389)
				)
				(xy 127.46355 -10.805414)
				(arc
					(start 127.46355 -10.81151)
					(mid 127.400948 -11.593903)
					(end 127.334772 -10.811764)
				)
				(arc
					(start 127.334772 -10.811764)
					(mid 127.295176 -10.743137)
					(end 127.220726 -10.716006)
				)
				(arc
					(start 126.871222 -10.716006)
					(mid 126.854872 -10.716924)
					(end 126.83871 -10.719562)
				)
				(arc
					(start 126.83871 -11.199876)
					(mid 127.399923 -11.76147)
					(end 127.96139 -11.20013)
				)
			)
		)
	)
	(zone
		(layer "In5.Cu")
		(hatch none 0.5)
		(connect_pads
			(clearance 0)
		)
		(min_thickness 0.25)
		(keepout
			(tracks not_allowed)
			(vias allowed)
			(pads allowed)
			(copperpour not_allowed)
			(footprints allowed)
		)
		(placement
			(enabled no)
			(sheetname "")
		)
		(fill
			(thermal_gap 0.5)
			(thermal_bridge_width 0.5)
			(island_removal_mode 0)
		)
		(polygon
			(pts
				(arc
					(start 130.000248 -63.641986)
					(mid 129.641854 -63.999999)
					(end 129.999994 -64.358266)
				)
				(arc
					(start 130.369056 -64.358266)
					(mid 130.354993 -64.303581)
					(end 130.348228 -64.247522)
				)
				(xy 130.347466 -64.24676) (xy 130.347466 -64.224408) (xy 130.347466 -64.223138)
				(arc
					(start 130.347466 -64.089026)
					(mid 130.338167 -64.066575)
					(end 130.315716 -64.057276)
				)
				(arc
					(start 130.234436 -64.057276)
					(mid 129.758687 -64.000126)
					(end 130.234436 -63.942976)
				)
				(xy 130.339338 -63.942976)
				(arc
					(start 130.341624 -63.945262)
					(mid 130.41901 -63.985732)
					(end 130.45948 -64.063118)
				)
				(xy 130.461766 -64.065404)
				(arc
					(start 130.461766 -64.224408)
					(mid 130.469461 -64.293014)
					(end 130.491992 -64.358266)
				)
				(arc
					(start 130.579622 -64.358266)
					(mid 130.55253 -64.305805)
					(end 130.539236 -64.248284)
				)
				(xy 130.537966 -64.247014) (xy 130.537966 -64.2239) (xy 130.537966 -64.223392) (xy 130.537966 -64.065404)
				(arc
					(start 130.540252 -64.063118)
					(mid 130.580722 -63.985732)
					(end 130.658108 -63.945262)
				)
				(xy 130.660394 -63.942976)
				(arc
					(start 130.76555 -63.942976)
					(mid 131.241299 -64.000126)
					(end 130.76555 -64.057276)
				)
				(arc
					(start 130.684016 -64.057276)
					(mid 130.661565 -64.066575)
					(end 130.652266 -64.089026)
				)
				(arc
					(start 130.652266 -64.2239)
					(mid 130.661696 -64.271018)
					(end 130.688334 -64.311022)
				)
				(arc
					(start 130.688588 -64.311276)
					(mid 130.728616 -64.337771)
					(end 130.77571 -64.34709)
				)
				(arc
					(start 131.088638 -64.34709)
					(mid 131.355304 -63.955454)
					(end 130.999992 -63.641986)
				)
			)
		)
	)
	(zone
		(net "GB_VDDH")
		(layer "In5.Cu")
		(hatch none 0.5)
		(connect_pads
			(clearance 0.5)
		)
		(min_thickness 0.25)
		(fill yes
			(thermal_gap 0.5)
			(thermal_bridge_width 0.5)
			(island_removal_mode 0)
		)
		(polygon
			(pts
				(xy 145.179796 -99.434396) (xy 147.443952 -99.434396) (xy 154.311604 -99.434396) (xy 155.321 -98.425)
				(xy 155.702 -98.044) (xy 155.702 -75.565) (xy 155.702 -74.549) (xy 155.32735 -74.17435) (xy 153.93035 -74.17435)
				(xy 149.842982 -74.17435) (xy 148.286724 -74.17435) (xy 145.692876 -74.17435) (xy 145.02765 -74.17435)
				(xy 144.399 -74.803) (xy 144.399 -76.4286) (xy 148.0058 -80.0354) (xy 148.0058 -81.1276) (xy 148.0058 -94.33433)
				(xy 144.906492 -97.433892) (xy 144.906492 -99.161092)
			)
		)
	)
	(zone
		(layer "In5.Cu")
		(hatch none 0.5)
		(connect_pads
			(clearance 0)
		)
		(min_thickness 0.25)
		(keepout
			(tracks not_allowed)
			(vias allowed)
			(pads allowed)
			(copperpour not_allowed)
			(footprints allowed)
		)
		(placement
			(enabled no)
			(sheetname "")
		)
		(fill
			(thermal_gap 0.5)
			(thermal_bridge_width 0.5)
			(island_removal_mode 0)
		)
		(polygon
			(pts
				(arc
					(start 105.347262 -51.912266)
					(mid 104.955762 -51.64473)
					(end 104.641904 -52.00015)
				)
				(arc
					(start 104.641904 -52.999894)
					(mid 104.999917 -53.358288)
					(end 105.358184 -53.000148)
				)
				(arc
					(start 105.358184 -52.63769)
					(mid 105.316643 -52.646891)
					(end 105.274364 -52.65166)
				)
				(xy 105.273602 -52.652422)
				(arc
					(start 105.088944 -52.652422)
					(mid 105.066493 -52.661721)
					(end 105.057194 -52.684172)
				)
				(arc
					(start 105.057194 -52.765706)
					(mid 105.000044 -53.241455)
					(end 104.942894 -52.765706)
				)
				(xy 104.942894 -52.66055)
				(arc
					(start 104.94518 -52.658264)
					(mid 104.98565 -52.580878)
					(end 105.063036 -52.540408)
				)
				(xy 105.065322 -52.538122)
				(arc
					(start 105.24998 -52.538122)
					(mid 105.3051 -52.532804)
					(end 105.358184 -52.51704)
				)
				(arc
					(start 105.358184 -52.432204)
					(mid 105.318133 -52.450661)
					(end 105.275126 -52.460398)
				)
				(xy 105.273602 -52.461922) (xy 105.065322 -52.461922)
				(arc
					(start 105.063036 -52.459636)
					(mid 104.98565 -52.419166)
					(end 104.94518 -52.34178)
				)
				(xy 104.942894 -52.339494)
				(arc
					(start 104.942894 -52.234592)
					(mid 105.000044 -51.758843)
					(end 105.057194 -52.234592)
				)
				(arc
					(start 105.057194 -52.315872)
					(mid 105.066493 -52.338323)
					(end 105.088944 -52.347622)
				)
				(arc
					(start 105.24998 -52.347622)
					(mid 105.287056 -52.3403)
					(end 105.31856 -52.319428)
				)
				(arc
					(start 105.318814 -52.319174)
					(mid 105.339887 -52.287448)
					(end 105.347262 -52.250086)
				)
			)
		)
	)
	(zone
		(layer "In5.Cu")
		(hatch none 0.5)
		(connect_pads
			(clearance 0)
		)
		(min_thickness 0.25)
		(keepout
			(tracks not_allowed)
			(vias allowed)
			(pads allowed)
			(copperpour not_allowed)
			(footprints allowed)
		)
		(placement
			(enabled no)
			(sheetname "")
		)
		(fill
			(thermal_gap 0.5)
			(thermal_bridge_width 0.5)
			(island_removal_mode 0)
		)
		(polygon
			(pts
				(arc
					(start 193.161158 -2.600198)
					(mid 192.599818 -2.038858)
					(end 192.038478 -2.600198)
				)
				(arc
					(start 192.038478 -3.061462)
					(mid 192.076212 -3.056357)
					(end 192.11417 -3.053334)
				)
				(xy 192.114932 -3.052572)
				(arc
					(start 192.433194 -3.052572)
					(mid 192.486592 -3.033437)
					(end 192.515744 -2.984754)
				)
				(arc
					(start 192.515744 -2.984754)
					(mid 192.601621 -2.206452)
					(end 192.682368 -2.985262)
				)
				(xy 192.682368 -3.002788)
				(arc
					(start 192.679574 -3.005328)
					(mid 192.609347 -3.144651)
					(end 192.470024 -3.214878)
				)
				(xy 192.467484 -3.217672)
				(arc
					(start 192.149222 -3.217672)
					(mid 192.093541 -3.220595)
					(end 192.038478 -3.229356)
				)
				(arc
					(start 192.038478 -3.39979)
					(mid 192.07542 -3.390228)
					(end 192.113154 -3.38455)
				)
				(xy 192.114932 -3.382772) (xy 192.467738 -3.382772)
				(arc
					(start 192.470278 -3.385566)
					(mid 192.609423 -3.455717)
					(end 192.679574 -3.594862)
				)
				(xy 192.682368 -3.597402)
				(arc
					(start 192.682368 -3.614928)
					(mid 192.601621 -4.393697)
					(end 192.515744 -3.615436)
				)
				(arc
					(start 192.515744 -3.615436)
					(mid 192.486708 -3.566882)
					(end 192.433448 -3.547872)
				)
				(arc
					(start 192.149222 -3.547872)
					(mid 192.091423 -3.556256)
					(end 192.038478 -3.580892)
				)
				(arc
					(start 192.038478 -3.999738)
					(mid 192.599691 -4.561332)
					(end 193.161158 -3.999992)
				)
			)
		)
	)
	(zone
		(layer "In5.Cu")
		(hatch none 0.5)
		(connect_pads
			(clearance 0)
		)
		(min_thickness 0.25)
		(keepout
			(tracks not_allowed)
			(vias allowed)
			(pads allowed)
			(copperpour not_allowed)
			(footprints allowed)
		)
		(placement
			(enabled no)
			(sheetname "")
		)
		(fill
			(thermal_gap 0.5)
			(thermal_bridge_width 0.5)
			(island_removal_mode 0)
		)
		(polygon
			(pts
				(arc
					(start 126.161546 -10.999978)
					(mid 125.600206 -10.438638)
					(end 125.038866 -10.999978)
				)
				(xy 125.038866 -11.485118) (xy 125.044454 -11.48461) (xy 125.044962 -11.484102)
				(arc
					(start 125.420882 -11.484102)
					(mid 125.495349 -11.456991)
					(end 125.534928 -11.388344)
				)
				(arc
					(start 125.534928 -11.388344)
					(mid 125.601104 -10.606165)
					(end 125.663706 -11.388598)
				)
				(xy 125.663706 -11.394694)
				(arc
					(start 125.662182 -11.396218)
					(mid 125.592647 -11.540043)
					(end 125.448822 -11.609578)
				)
				(xy 125.447298 -11.611102) (xy 125.071378 -11.611102) (xy 125.038866 -11.612372) (xy 125.038866 -11.79068)
				(xy 125.043692 -11.790172) (xy 125.044962 -11.788902) (xy 125.447298 -11.788902)
				(arc
					(start 125.448822 -11.790426)
					(mid 125.592647 -11.859961)
					(end 125.662182 -12.003786)
				)
				(xy 125.663706 -12.00531)
				(arc
					(start 125.663706 -12.011406)
					(mid 125.601104 -12.793799)
					(end 125.534928 -12.01166)
				)
				(arc
					(start 125.534928 -12.01166)
					(mid 125.495332 -11.943033)
					(end 125.420882 -11.915902)
				)
				(arc
					(start 125.071378 -11.915902)
					(mid 125.055028 -11.91682)
					(end 125.038866 -11.919458)
				)
				(arc
					(start 125.038866 -12.399772)
					(mid 125.600079 -12.961366)
					(end 126.161546 -12.400026)
				)
			)
		)
	)
	(zone
		(layer "In5.Cu")
		(hatch none 0.5)
		(connect_pads
			(clearance 0)
		)
		(min_thickness 0.25)
		(keepout
			(tracks not_allowed)
			(vias allowed)
			(pads allowed)
			(copperpour not_allowed)
			(footprints allowed)
		)
		(placement
			(enabled no)
			(sheetname "")
		)
		(fill
			(thermal_gap 0.5)
			(thermal_bridge_width 0.5)
			(island_removal_mode 0)
		)
		(polygon
			(pts
				(arc
					(start 110.35157 -50.931572)
					(mid 109.965584 -50.64365)
					(end 109.641894 -51.000152)
				)
				(arc
					(start 109.641894 -51.999896)
					(mid 109.999907 -52.35829)
					(end 110.358174 -52.00015)
				)
				(xy 110.358174 -51.64836) (xy 110.328202 -51.651662) (xy 110.32744 -51.652424)
				(arc
					(start 110.088934 -51.652424)
					(mid 110.066483 -51.661723)
					(end 110.057184 -51.684174)
				)
				(arc
					(start 110.057184 -51.765708)
					(mid 110.000034 -52.241457)
					(end 109.942884 -51.765708)
				)
				(xy 109.942884 -51.660552)
				(arc
					(start 109.94517 -51.658266)
					(mid 109.98564 -51.58088)
					(end 110.063026 -51.54041)
				)
				(xy 110.065312 -51.538124)
				(arc
					(start 110.304326 -51.538124)
					(mid 110.331423 -51.536609)
					(end 110.358174 -51.532028)
				)
				(arc
					(start 110.358174 -51.452526)
					(mid 110.34399 -51.456856)
					(end 110.329472 -51.459892)
				)
				(xy 110.32744 -51.461924) (xy 110.065312 -51.461924)
				(arc
					(start 110.063026 -51.459638)
					(mid 109.98564 -51.419168)
					(end 109.94517 -51.341782)
				)
				(xy 109.942884 -51.339496)
				(arc
					(start 109.942884 -51.234594)
					(mid 110.000034 -50.758845)
					(end 110.057184 -51.234594)
				)
				(arc
					(start 110.057184 -51.315874)
					(mid 110.066483 -51.338325)
					(end 110.088934 -51.347624)
				)
				(arc
					(start 110.303818 -51.347624)
					(mid 110.322092 -51.343989)
					(end 110.3376 -51.333654)
				)
				(arc
					(start 110.3376 -51.333654)
					(mid 110.347956 -51.318155)
					(end 110.35157 -51.299872)
				)
			)
		)
	)
	(zone
		(layer "In5.Cu")
		(hatch none 0.5)
		(connect_pads
			(clearance 0)
		)
		(min_thickness 0.25)
		(keepout
			(tracks not_allowed)
			(vias allowed)
			(pads allowed)
			(copperpour not_allowed)
			(footprints allowed)
		)
		(placement
			(enabled no)
			(sheetname "")
		)
		(fill
			(thermal_gap 0.5)
			(thermal_bridge_width 0.5)
			(island_removal_mode 0)
		)
		(polygon
			(pts
				(arc
					(start 102.761542 -9.800082)
					(mid 102.200202 -9.238742)
					(end 101.638862 -9.800082)
				)
				(xy 101.638862 -10.285222) (xy 101.64445 -10.284714) (xy 101.644958 -10.284206)
				(arc
					(start 102.020878 -10.284206)
					(mid 102.095345 -10.257095)
					(end 102.134924 -10.188448)
				)
				(arc
					(start 102.134924 -10.188448)
					(mid 102.2011 -9.406269)
					(end 102.263702 -10.188702)
				)
				(xy 102.263702 -10.194798)
				(arc
					(start 102.262178 -10.196322)
					(mid 102.192643 -10.340147)
					(end 102.048818 -10.409682)
				)
				(xy 102.047294 -10.411206) (xy 101.671374 -10.411206) (xy 101.638862 -10.412476) (xy 101.638862 -10.590784)
				(xy 101.643688 -10.590276) (xy 101.644958 -10.589006) (xy 102.047294 -10.589006)
				(arc
					(start 102.048818 -10.59053)
					(mid 102.192643 -10.660065)
					(end 102.262178 -10.80389)
				)
				(xy 102.263702 -10.805414)
				(arc
					(start 102.263702 -10.81151)
					(mid 102.2011 -11.593903)
					(end 102.134924 -10.811764)
				)
				(arc
					(start 102.134924 -10.811764)
					(mid 102.095328 -10.743137)
					(end 102.020878 -10.716006)
				)
				(arc
					(start 101.671374 -10.716006)
					(mid 101.655023 -10.716922)
					(end 101.638862 -10.719562)
				)
				(arc
					(start 101.638862 -11.199876)
					(mid 102.200075 -11.76147)
					(end 102.761542 -11.20013)
				)
			)
		)
	)
	(zone
		(layers "In5.Cu" "In6.Cu")
		(hatch none 0.5)
		(connect_pads
			(clearance 0)
		)
		(min_thickness 0.25)
		(keepout
			(tracks not_allowed)
			(vias allowed)
			(pads allowed)
			(copperpour not_allowed)
			(footprints allowed)
		)
		(placement
			(enabled no)
			(sheetname "")
		)
		(fill yes
			(thermal_gap 0.5)
			(thermal_bridge_width 0.5)
			(island_removal_mode 0)
		)
		(polygon
			(pts
				(arc
					(start 128.7018 -40.4114)
					(mid 128.665879 -40.426279)
					(end 128.651 -40.4622)
				)
				(arc
					(start 128.651 -41.275)
					(mid 128.665879 -41.310921)
					(end 128.7018 -41.3258)
				)
				(arc
					(start 128.905 -41.3258)
					(mid 128.940921 -41.310921)
					(end 128.9558 -41.275)
				)
				(arc
					(start 128.9558 -40.4622)
					(mid 128.940921 -40.426279)
					(end 128.905 -40.4114)
				)
			)
		)
	)
	(zone
		(layers "In5.Cu" "In6.Cu")
		(hatch none 0.5)
		(connect_pads
			(clearance 0)
		)
		(min_thickness 0.25)
		(keepout
			(tracks not_allowed)
			(vias allowed)
			(pads allowed)
			(copperpour not_allowed)
			(footprints allowed)
		)
		(placement
			(enabled no)
			(sheetname "")
		)
		(fill yes
			(thermal_gap 0.5)
			(thermal_bridge_width 0.5)
			(island_removal_mode 0)
		)
		(polygon
			(pts
				(arc
					(start 127.3556 -39.0144)
					(mid 127.319679 -39.029279)
					(end 127.3048 -39.0652)
				)
				(arc
					(start 127.3048 -39.878)
					(mid 127.319679 -39.913921)
					(end 127.3556 -39.9288)
				)
				(arc
					(start 127.5588 -39.9288)
					(mid 127.594721 -39.913921)
					(end 127.6096 -39.878)
				)
				(arc
					(start 127.6096 -39.0652)
					(mid 127.594721 -39.029279)
					(end 127.5588 -39.0144)
				)
			)
		)
	)
	(zone
		(layers "In5.Cu" "In6.Cu")
		(hatch none 0.5)
		(connect_pads
			(clearance 0)
		)
		(min_thickness 0.25)
		(keepout
			(tracks not_allowed)
			(vias allowed)
			(pads allowed)
			(copperpour not_allowed)
			(footprints allowed)
		)
		(placement
			(enabled no)
			(sheetname "")
		)
		(fill yes
			(thermal_gap 0.5)
			(thermal_bridge_width 0.5)
			(island_removal_mode 0)
		)
		(polygon
			(pts
				(arc
					(start 181.726586 -21.740368)
					(mid 181.711707 -21.704447)
					(end 181.675786 -21.689568)
				)
				(arc
					(start 180.862986 -21.689568)
					(mid 180.827065 -21.704447)
					(end 180.812186 -21.740368)
				)
				(arc
					(start 180.812186 -21.943568)
					(mid 180.827065 -21.979489)
					(end 180.862986 -21.994368)
				)
				(arc
					(start 181.675786 -21.994368)
					(mid 181.711707 -21.979489)
					(end 181.726586 -21.943568)
				)
			)
		)
	)
	(zone
		(layers "In5.Cu" "In6.Cu")
		(hatch none 0.5)
		(connect_pads
			(clearance 0)
		)
		(min_thickness 0.25)
		(keepout
			(tracks not_allowed)
			(vias allowed)
			(pads allowed)
			(copperpour not_allowed)
			(footprints allowed)
		)
		(placement
			(enabled no)
			(sheetname "")
		)
		(fill yes
			(thermal_gap 0.5)
			(thermal_bridge_width 0.5)
			(island_removal_mode 0)
		)
		(polygon
			(pts
				(arc
					(start 134.086854 -64.914018)
					(mid 134.050933 -64.928897)
					(end 134.036054 -64.964818)
				)
				(arc
					(start 134.036054 -65.168018)
					(mid 134.050933 -65.203939)
					(end 134.086854 -65.218818)
				)
				(arc
					(start 134.899654 -65.218818)
					(mid 134.935575 -65.203939)
					(end 134.950454 -65.168018)
				)
				(arc
					(start 134.950454 -64.964818)
					(mid 134.935575 -64.928897)
					(end 134.899654 -64.914018)
				)
			)
		)
	)
	(zone
		(layers "In5.Cu" "In6.Cu")
		(hatch none 0.5)
		(connect_pads
			(clearance 0)
		)
		(min_thickness 0.25)
		(keepout
			(tracks not_allowed)
			(vias allowed)
			(pads allowed)
			(copperpour not_allowed)
			(footprints allowed)
		)
		(placement
			(enabled no)
			(sheetname "")
		)
		(fill yes
			(thermal_gap 0.5)
			(thermal_bridge_width 0.5)
			(island_removal_mode 0)
		)
		(polygon
			(pts
				(arc
					(start 135.304022 -55.922418)
					(mid 135.268101 -55.937297)
					(end 135.253222 -55.973218)
				)
				(arc
					(start 135.253222 -56.786018)
					(mid 135.268101 -56.821939)
					(end 135.304022 -56.836818)
				)
				(arc
					(start 135.507222 -56.836818)
					(mid 135.543143 -56.821939)
					(end 135.558022 -56.786018)
				)
				(arc
					(start 135.558022 -55.973218)
					(mid 135.543143 -55.937297)
					(end 135.507222 -55.922418)
				)
			)
		)
	)
	(zone
		(layers "In5.Cu" "In6.Cu")
		(hatch none 0.5)
		(connect_pads
			(clearance 0)
		)
		(min_thickness 0.25)
		(keepout
			(tracks not_allowed)
			(vias allowed)
			(pads allowed)
			(copperpour not_allowed)
			(footprints allowed)
		)
		(placement
			(enabled no)
			(sheetname "")
		)
		(fill yes
			(thermal_gap 0.5)
			(thermal_bridge_width 0.5)
			(island_removal_mode 0)
		)
		(polygon
			(pts
				(arc
					(start 98.0694 -43.7642)
					(mid 98.033479 -43.779079)
					(end 98.0186 -43.815)
				)
				(arc
					(start 98.0186 -44.6278)
					(mid 98.033479 -44.663721)
					(end 98.0694 -44.6786)
				)
				(arc
					(start 98.2726 -44.6786)
					(mid 98.308521 -44.663721)
					(end 98.3234 -44.6278)
				)
				(arc
					(start 98.3234 -43.815)
					(mid 98.308521 -43.779079)
					(end 98.2726 -43.7642)
				)
			)
		)
	)
	(zone
		(layers "In5.Cu" "In6.Cu")
		(hatch none 0.5)
		(connect_pads
			(clearance 0)
		)
		(min_thickness 0.25)
		(keepout
			(tracks not_allowed)
			(vias allowed)
			(pads allowed)
			(copperpour not_allowed)
			(footprints allowed)
		)
		(placement
			(enabled no)
			(sheetname "")
		)
		(fill yes
			(thermal_gap 0.5)
			(thermal_bridge_width 0.5)
			(island_removal_mode 0)
		)
		(polygon
			(pts
				(arc
					(start 135.763 -75.438)
					(mid 135.727079 -75.452879)
					(end 135.7122 -75.4888)
				)
				(arc
					(start 135.7122 -75.692)
					(mid 135.727079 -75.727921)
					(end 135.763 -75.7428)
				)
				(arc
					(start 136.5758 -75.7428)
					(mid 136.611721 -75.727921)
					(end 136.6266 -75.692)
				)
				(arc
					(start 136.6266 -75.4888)
					(mid 136.611721 -75.452879)
					(end 136.5758 -75.438)
				)
			)
		)
	)
	(zone
		(layers "In5.Cu" "In6.Cu")
		(hatch none 0.5)
		(connect_pads
			(clearance 0)
		)
		(min_thickness 0.25)
		(keepout
			(tracks not_allowed)
			(vias allowed)
			(pads allowed)
			(copperpour not_allowed)
			(footprints allowed)
		)
		(placement
			(enabled no)
			(sheetname "")
		)
		(fill yes
			(thermal_gap 0.5)
			(thermal_bridge_width 0.5)
			(island_removal_mode 0)
		)
		(polygon
			(pts
				(arc
					(start 102.6414 -43.7642)
					(mid 102.605479 -43.779079)
					(end 102.5906 -43.815)
				)
				(arc
					(start 102.5906 -44.6278)
					(mid 102.605479 -44.663721)
					(end 102.6414 -44.6786)
				)
				(arc
					(start 102.8446 -44.6786)
					(mid 102.880521 -44.663721)
					(end 102.8954 -44.6278)
				)
				(arc
					(start 102.8954 -43.815)
					(mid 102.880521 -43.779079)
					(end 102.8446 -43.7642)
				)
			)
		)
	)
	(zone
		(layers "In5.Cu" "In6.Cu")
		(hatch none 0.5)
		(connect_pads
			(clearance 0)
		)
		(min_thickness 0.25)
		(keepout
			(tracks not_allowed)
			(vias allowed)
			(pads allowed)
			(copperpour not_allowed)
			(footprints allowed)
		)
		(placement
			(enabled no)
			(sheetname "")
		)
		(fill yes
			(thermal_gap 0.5)
			(thermal_bridge_width 0.5)
			(island_removal_mode 0)
		)
		(polygon
			(pts
				(arc
					(start 169.4561 -20.547076)
					(mid 169.420179 -20.561955)
					(end 169.4053 -20.597876)
				)
				(arc
					(start 169.4053 -21.410676)
					(mid 169.420179 -21.446597)
					(end 169.4561 -21.461476)
				)
				(arc
					(start 169.6593 -21.461476)
					(mid 169.695221 -21.446597)
					(end 169.7101 -21.410676)
				)
				(arc
					(start 169.7101 -20.597876)
					(mid 169.695221 -20.561955)
					(end 169.6593 -20.547076)
				)
			)
		)
	)
	(zone
		(layers "In5.Cu" "In6.Cu")
		(hatch none 0.5)
		(connect_pads
			(clearance 0)
		)
		(min_thickness 0.25)
		(keepout
			(tracks not_allowed)
			(vias allowed)
			(pads allowed)
			(copperpour not_allowed)
			(footprints allowed)
		)
		(placement
			(enabled no)
			(sheetname "")
		)
		(fill yes
			(thermal_gap 0.5)
			(thermal_bridge_width 0.5)
			(island_removal_mode 0)
		)
		(polygon
			(pts
				(arc
					(start 133.731 -43.942)
					(mid 133.695079 -43.956879)
					(end 133.6802 -43.9928)
				)
				(arc
					(start 133.6802 -44.8056)
					(mid 133.695079 -44.841521)
					(end 133.731 -44.8564)
				)
				(arc
					(start 133.9342 -44.8564)
					(mid 133.970121 -44.841521)
					(end 133.985 -44.8056)
				)
				(arc
					(start 133.985 -43.9928)
					(mid 133.970121 -43.956879)
					(end 133.9342 -43.942)
				)
			)
		)
	)
	(zone
		(layers "In5.Cu" "In6.Cu")
		(hatch none 0.5)
		(connect_pads
			(clearance 0)
		)
		(min_thickness 0.25)
		(keepout
			(tracks not_allowed)
			(vias allowed)
			(pads allowed)
			(copperpour not_allowed)
			(footprints allowed)
		)
		(placement
			(enabled no)
			(sheetname "")
		)
		(fill yes
			(thermal_gap 0.5)
			(thermal_bridge_width 0.5)
			(island_removal_mode 0)
		)
		(polygon
			(pts
				(arc
					(start 105.6894 -43.7642)
					(mid 105.653479 -43.779079)
					(end 105.6386 -43.815)
				)
				(arc
					(start 105.6386 -44.6278)
					(mid 105.653479 -44.663721)
					(end 105.6894 -44.6786)
				)
				(arc
					(start 105.8926 -44.6786)
					(mid 105.928521 -44.663721)
					(end 105.9434 -44.6278)
				)
				(arc
					(start 105.9434 -43.815)
					(mid 105.928521 -43.779079)
					(end 105.8926 -43.7642)
				)
			)
		)
	)
	(zone
		(layers "In5.Cu" "In6.Cu")
		(hatch none 0.5)
		(connect_pads
			(clearance 0)
		)
		(min_thickness 0.25)
		(keepout
			(tracks not_allowed)
			(vias allowed)
			(pads allowed)
			(copperpour not_allowed)
			(footprints allowed)
		)
		(placement
			(enabled no)
			(sheetname "")
		)
		(fill yes
			(thermal_gap 0.5)
			(thermal_bridge_width 0.5)
			(island_removal_mode 0)
		)
		(polygon
			(pts
				(arc
					(start 106.2482 -43.7642)
					(mid 106.212279 -43.779079)
					(end 106.1974 -43.815)
				)
				(arc
					(start 106.1974 -44.6278)
					(mid 106.212279 -44.663721)
					(end 106.2482 -44.6786)
				)
				(arc
					(start 106.4514 -44.6786)
					(mid 106.487321 -44.663721)
					(end 106.5022 -44.6278)
				)
				(arc
					(start 106.5022 -43.815)
					(mid 106.487321 -43.779079)
					(end 106.4514 -43.7642)
				)
			)
		)
	)
	(zone
		(layers "In5.Cu" "In6.Cu")
		(hatch none 0.5)
		(connect_pads
			(clearance 0)
		)
		(min_thickness 0.25)
		(keepout
			(tracks not_allowed)
			(vias allowed)
			(pads allowed)
			(copperpour not_allowed)
			(footprints allowed)
		)
		(placement
			(enabled no)
			(sheetname "")
		)
		(fill yes
			(thermal_gap 0.5)
			(thermal_bridge_width 0.5)
			(island_removal_mode 0)
		)
		(polygon
			(pts
				(arc
					(start 135.7884 -77.343)
					(mid 135.752479 -77.357879)
					(end 135.7376 -77.3938)
				)
				(arc
					(start 135.7376 -77.597)
					(mid 135.752479 -77.632921)
					(end 135.7884 -77.6478)
				)
				(arc
					(start 136.6012 -77.6478)
					(mid 136.637121 -77.632921)
					(end 136.652 -77.597)
				)
				(arc
					(start 136.652 -77.3938)
					(mid 136.637121 -77.357879)
					(end 136.6012 -77.343)
				)
			)
		)
	)
	(zone
		(layers "In5.Cu" "In6.Cu")
		(hatch none 0.5)
		(connect_pads
			(clearance 0)
		)
		(min_thickness 0.25)
		(keepout
			(tracks not_allowed)
			(vias allowed)
			(pads allowed)
			(copperpour not_allowed)
			(footprints allowed)
		)
		(placement
			(enabled no)
			(sheetname "")
		)
		(fill yes
			(thermal_gap 0.5)
			(thermal_bridge_width 0.5)
			(island_removal_mode 0)
		)
		(polygon
			(pts
				(arc
					(start 125.476 -39.0144)
					(mid 125.440079 -39.029279)
					(end 125.4252 -39.0652)
				)
				(arc
					(start 125.4252 -39.878)
					(mid 125.440079 -39.913921)
					(end 125.476 -39.9288)
				)
				(arc
					(start 125.6792 -39.9288)
					(mid 125.715121 -39.913921)
					(end 125.73 -39.878)
				)
				(arc
					(start 125.73 -39.0652)
					(mid 125.715121 -39.029279)
					(end 125.6792 -39.0144)
				)
			)
		)
	)
	(zone
		(layers "In5.Cu" "In6.Cu")
		(hatch none 0.5)
		(connect_pads
			(clearance 0)
		)
		(min_thickness 0.25)
		(keepout
			(tracks not_allowed)
			(vias allowed)
			(pads allowed)
			(copperpour not_allowed)
			(footprints allowed)
		)
		(placement
			(enabled no)
			(sheetname "")
		)
		(fill yes
			(thermal_gap 0.5)
			(thermal_bridge_width 0.5)
			(island_removal_mode 0)
		)
		(polygon
			(pts
				(arc
					(start 101.1174 -43.7642)
					(mid 101.081479 -43.779079)
					(end 101.0666 -43.815)
				)
				(arc
					(start 101.0666 -44.6278)
					(mid 101.081479 -44.663721)
					(end 101.1174 -44.6786)
				)
				(arc
					(start 101.3206 -44.6786)
					(mid 101.356521 -44.663721)
					(end 101.3714 -44.6278)
				)
				(arc
					(start 101.3714 -43.815)
					(mid 101.356521 -43.779079)
					(end 101.3206 -43.7642)
				)
			)
		)
	)
	(zone
		(layers "In5.Cu" "In6.Cu")
		(hatch none 0.5)
		(connect_pads
			(clearance 0)
		)
		(min_thickness 0.25)
		(keepout
			(tracks not_allowed)
			(vias allowed)
			(pads allowed)
			(copperpour not_allowed)
			(footprints allowed)
		)
		(placement
			(enabled no)
			(sheetname "")
		)
		(fill yes
			(thermal_gap 0.5)
			(thermal_bridge_width 0.5)
			(island_removal_mode 0)
		)
		(polygon
			(pts
				(arc
					(start 116.9162 -43.7642)
					(mid 116.880279 -43.779079)
					(end 116.8654 -43.815)
				)
				(arc
					(start 116.8654 -44.6278)
					(mid 116.880279 -44.663721)
					(end 116.9162 -44.6786)
				)
				(arc
					(start 117.1194 -44.6786)
					(mid 117.155321 -44.663721)
					(end 117.1702 -44.6278)
				)
				(arc
					(start 117.1702 -43.815)
					(mid 117.155321 -43.779079)
					(end 117.1194 -43.7642)
				)
			)
		)
	)
	(zone
		(layers "In5.Cu" "In6.Cu")
		(hatch none 0.5)
		(connect_pads
			(clearance 0)
		)
		(min_thickness 0.25)
		(keepout
			(tracks not_allowed)
			(vias allowed)
			(pads allowed)
			(copperpour not_allowed)
			(footprints allowed)
		)
		(placement
			(enabled no)
			(sheetname "")
		)
		(fill yes
			(thermal_gap 0.5)
			(thermal_bridge_width 0.5)
			(island_removal_mode 0)
		)
		(polygon
			(pts
				(arc
					(start 137.0076 -74.4474)
					(mid 136.971679 -74.462279)
					(end 136.9568 -74.4982)
				)
				(arc
					(start 136.9568 -74.7014)
					(mid 136.971679 -74.737321)
					(end 137.0076 -74.7522)
				)
				(arc
					(start 137.8204 -74.7522)
					(mid 137.856321 -74.737321)
					(end 137.8712 -74.7014)
				)
				(arc
					(start 137.8712 -74.4982)
					(mid 137.856321 -74.462279)
					(end 137.8204 -74.4474)
				)
			)
		)
	)
	(zone
		(layers "In5.Cu" "In6.Cu")
		(hatch none 0.5)
		(connect_pads
			(clearance 0)
		)
		(min_thickness 0.25)
		(keepout
			(tracks not_allowed)
			(vias allowed)
			(pads allowed)
			(copperpour not_allowed)
			(footprints allowed)
		)
		(placement
			(enabled no)
			(sheetname "")
		)
		(fill yes
			(thermal_gap 0.5)
			(thermal_bridge_width 0.5)
			(island_removal_mode 0)
		)
		(polygon
			(pts
				(arc
					(start 96.090994 -54.404768)
					(mid 96.055073 -54.419647)
					(end 96.040194 -54.455568)
				)
				(arc
					(start 96.040194 -54.658768)
					(mid 96.055073 -54.694689)
					(end 96.090994 -54.709568)
				)
				(arc
					(start 96.903794 -54.709568)
					(mid 96.939715 -54.694689)
					(end 96.954594 -54.658768)
				)
				(arc
					(start 96.954594 -54.455568)
					(mid 96.939715 -54.419647)
					(end 96.903794 -54.404768)
				)
			)
		)
	)
	(zone
		(layers "In5.Cu" "In6.Cu")
		(hatch none 0.5)
		(connect_pads
			(clearance 0)
		)
		(min_thickness 0.25)
		(keepout
			(tracks not_allowed)
			(vias allowed)
			(pads allowed)
			(copperpour not_allowed)
			(footprints allowed)
		)
		(placement
			(enabled no)
			(sheetname "")
		)
		(fill yes
			(thermal_gap 0.5)
			(thermal_bridge_width 0.5)
			(island_removal_mode 0)
		)
		(polygon
			(pts
				(arc
					(start 126.7714 -39.0144)
					(mid 126.735479 -39.029279)
					(end 126.7206 -39.0652)
				)
				(arc
					(start 126.7206 -39.878)
					(mid 126.735479 -39.913921)
					(end 126.7714 -39.9288)
				)
				(arc
					(start 126.9746 -39.9288)
					(mid 127.010521 -39.913921)
					(end 127.0254 -39.878)
				)
				(arc
					(start 127.0254 -39.0652)
					(mid 127.010521 -39.029279)
					(end 126.9746 -39.0144)
				)
			)
		)
	)
	(zone
		(layers "In5.Cu" "In6.Cu")
		(hatch none 0.5)
		(connect_pads
			(clearance 0)
		)
		(min_thickness 0.25)
		(keepout
			(tracks not_allowed)
			(vias allowed)
			(pads allowed)
			(copperpour not_allowed)
			(footprints allowed)
		)
		(placement
			(enabled no)
			(sheetname "")
		)
		(fill yes
			(thermal_gap 0.5)
			(thermal_bridge_width 0.5)
			(island_removal_mode 0)
		)
		(polygon
			(pts
				(arc
					(start 112.3442 -43.7642)
					(mid 112.308279 -43.779079)
					(end 112.2934 -43.815)
				)
				(arc
					(start 112.2934 -44.6278)
					(mid 112.308279 -44.663721)
					(end 112.3442 -44.6786)
				)
				(arc
					(start 112.5474 -44.6786)
					(mid 112.583321 -44.663721)
					(end 112.5982 -44.6278)
				)
				(arc
					(start 112.5982 -43.815)
					(mid 112.583321 -43.779079)
					(end 112.5474 -43.7642)
				)
			)
		)
	)
	(zone
		(layers "In5.Cu" "In6.Cu")
		(hatch none 0.5)
		(connect_pads
			(clearance 0)
		)
		(min_thickness 0.25)
		(keepout
			(tracks not_allowed)
			(vias allowed)
			(pads allowed)
			(copperpour not_allowed)
			(footprints allowed)
		)
		(placement
			(enabled no)
			(sheetname "")
		)
		(fill yes
			(thermal_gap 0.5)
			(thermal_bridge_width 0.5)
			(island_removal_mode 0)
		)
		(polygon
			(pts
				(arc
					(start 101.6762 -43.7642)
					(mid 101.640279 -43.779079)
					(end 101.6254 -43.815)
				)
				(arc
					(start 101.6254 -44.6278)
					(mid 101.640279 -44.663721)
					(end 101.6762 -44.6786)
				)
				(arc
					(start 101.8794 -44.6786)
					(mid 101.915321 -44.663721)
					(end 101.9302 -44.6278)
				)
				(arc
					(start 101.9302 -43.815)
					(mid 101.915321 -43.779079)
					(end 101.8794 -43.7642)
				)
			)
		)
	)
	(zone
		(layers "In5.Cu" "In6.Cu")
		(hatch none 0.5)
		(connect_pads
			(clearance 0)
		)
		(min_thickness 0.25)
		(keepout
			(tracks not_allowed)
			(vias allowed)
			(pads allowed)
			(copperpour not_allowed)
			(footprints allowed)
		)
		(placement
			(enabled no)
			(sheetname "")
		)
		(fill yes
			(thermal_gap 0.5)
			(thermal_bridge_width 0.5)
			(island_removal_mode 0)
		)
		(polygon
			(pts
				(arc
					(start 168.88079 -20.549616)
					(mid 168.844869 -20.564495)
					(end 168.82999 -20.600416)
				)
				(arc
					(start 168.82999 -21.413216)
					(mid 168.844869 -21.449137)
					(end 168.88079 -21.464016)
				)
				(arc
					(start 169.08399 -21.464016)
					(mid 169.119911 -21.449137)
					(end 169.13479 -21.413216)
				)
				(arc
					(start 169.13479 -20.600416)
					(mid 169.119911 -20.564495)
					(end 169.08399 -20.549616)
				)
			)
		)
	)
	(zone
		(layers "In5.Cu" "In6.Cu")
		(hatch none 0.5)
		(connect_pads
			(clearance 0)
		)
		(min_thickness 0.25)
		(keepout
			(tracks not_allowed)
			(vias allowed)
			(pads allowed)
			(copperpour not_allowed)
			(footprints allowed)
		)
		(placement
			(enabled no)
			(sheetname "")
		)
		(fill yes
			(thermal_gap 0.5)
			(thermal_bridge_width 0.5)
			(island_removal_mode 0)
		)
		(polygon
			(pts
				(arc
					(start 133.1722 -43.942)
					(mid 133.136279 -43.956879)
					(end 133.1214 -43.9928)
				)
				(arc
					(start 133.1214 -44.8056)
					(mid 133.136279 -44.841521)
					(end 133.1722 -44.8564)
				)
				(arc
					(start 133.3754 -44.8564)
					(mid 133.411321 -44.841521)
					(end 133.4262 -44.8056)
				)
				(arc
					(start 133.4262 -43.9928)
					(mid 133.411321 -43.956879)
					(end 133.3754 -43.942)
				)
			)
		)
	)
	(zone
		(layers "In5.Cu" "In6.Cu")
		(hatch none 0.5)
		(connect_pads
			(clearance 0)
		)
		(min_thickness 0.25)
		(keepout
			(tracks not_allowed)
			(vias allowed)
			(pads allowed)
			(copperpour not_allowed)
			(footprints allowed)
		)
		(placement
			(enabled no)
			(sheetname "")
		)
		(fill yes
			(thermal_gap 0.5)
			(thermal_bridge_width 0.5)
			(island_removal_mode 0)
		)
		(polygon
			(pts
				(arc
					(start 99.5934 -43.7642)
					(mid 99.557479 -43.779079)
					(end 99.5426 -43.815)
				)
				(arc
					(start 99.5426 -44.6278)
					(mid 99.557479 -44.663721)
					(end 99.5934 -44.6786)
				)
				(arc
					(start 99.7966 -44.6786)
					(mid 99.832521 -44.663721)
					(end 99.8474 -44.6278)
				)
				(arc
					(start 99.8474 -43.815)
					(mid 99.832521 -43.779079)
					(end 99.7966 -43.7642)
				)
			)
		)
	)
	(zone
		(layers "In5.Cu" "In6.Cu")
		(hatch none 0.5)
		(connect_pads
			(clearance 0)
		)
		(min_thickness 0.25)
		(keepout
			(tracks not_allowed)
			(vias allowed)
			(pads allowed)
			(copperpour not_allowed)
			(footprints allowed)
		)
		(placement
			(enabled no)
			(sheetname "")
		)
		(fill yes
			(thermal_gap 0.5)
			(thermal_bridge_width 0.5)
			(island_removal_mode 0)
		)
		(polygon
			(pts
				(arc
					(start 108.7374 -43.7642)
					(mid 108.701479 -43.779079)
					(end 108.6866 -43.815)
				)
				(arc
					(start 108.6866 -44.6278)
					(mid 108.701479 -44.663721)
					(end 108.7374 -44.6786)
				)
				(arc
					(start 108.9406 -44.6786)
					(mid 108.976521 -44.663721)
					(end 108.9914 -44.6278)
				)
				(arc
					(start 108.9914 -43.815)
					(mid 108.976521 -43.779079)
					(end 108.9406 -43.7642)
				)
			)
		)
	)
	(zone
		(layers "In5.Cu" "In6.Cu")
		(hatch none 0.5)
		(connect_pads
			(clearance 0)
		)
		(min_thickness 0.25)
		(keepout
			(tracks not_allowed)
			(vias allowed)
			(pads allowed)
			(copperpour not_allowed)
			(footprints allowed)
		)
		(placement
			(enabled no)
			(sheetname "")
		)
		(fill yes
			(thermal_gap 0.5)
			(thermal_bridge_width 0.5)
			(island_removal_mode 0)
		)
		(polygon
			(pts
				(arc
					(start 98.6282 -43.7642)
					(mid 98.592279 -43.779079)
					(end 98.5774 -43.815)
				)
				(arc
					(start 98.5774 -44.6278)
					(mid 98.592279 -44.663721)
					(end 98.6282 -44.6786)
				)
				(arc
					(start 98.8314 -44.6786)
					(mid 98.867321 -44.663721)
					(end 98.8822 -44.6278)
				)
				(arc
					(start 98.8822 -43.815)
					(mid 98.867321 -43.779079)
					(end 98.8314 -43.7642)
				)
			)
		)
	)
	(zone
		(layers "In5.Cu" "In6.Cu")
		(hatch none 0.5)
		(connect_pads
			(clearance 0)
		)
		(min_thickness 0.25)
		(keepout
			(tracks not_allowed)
			(vias allowed)
			(pads allowed)
			(copperpour not_allowed)
			(footprints allowed)
		)
		(placement
			(enabled no)
			(sheetname "")
		)
		(fill yes
			(thermal_gap 0.5)
			(thermal_bridge_width 0.5)
			(island_removal_mode 0)
		)
		(polygon
			(pts
				(arc
					(start 170.821604 -20.42922)
					(mid 170.785683 -20.444099)
					(end 170.770804 -20.48002)
				)
				(arc
					(start 170.770804 -21.29282)
					(mid 170.785683 -21.328741)
					(end 170.821604 -21.34362)
				)
				(arc
					(start 171.024804 -21.34362)
					(mid 171.060725 -21.328741)
					(end 171.075604 -21.29282)
				)
				(arc
					(start 171.075604 -20.48002)
					(mid 171.060725 -20.444099)
					(end 171.024804 -20.42922)
				)
			)
		)
	)
	(zone
		(layers "In5.Cu" "In6.Cu")
		(hatch none 0.5)
		(connect_pads
			(clearance 0)
		)
		(min_thickness 0.25)
		(keepout
			(tracks not_allowed)
			(vias allowed)
			(pads allowed)
			(copperpour not_allowed)
			(footprints allowed)
		)
		(placement
			(enabled no)
			(sheetname "")
		)
		(fill yes
			(thermal_gap 0.5)
			(thermal_bridge_width 0.5)
			(island_removal_mode 0)
		)
		(polygon
			(pts
				(arc
					(start 135.7884 -77.9018)
					(mid 135.752479 -77.916679)
					(end 135.7376 -77.9526)
				)
				(arc
					(start 135.7376 -78.1558)
					(mid 135.752479 -78.191721)
					(end 135.7884 -78.2066)
				)
				(arc
					(start 136.6012 -78.2066)
					(mid 136.637121 -78.191721)
					(end 136.652 -78.1558)
				)
				(arc
					(start 136.652 -77.9526)
					(mid 136.637121 -77.916679)
					(end 136.6012 -77.9018)
				)
			)
		)
	)
	(zone
		(layers "In5.Cu" "In6.Cu")
		(hatch none 0.5)
		(connect_pads
			(clearance 0)
		)
		(min_thickness 0.25)
		(keepout
			(tracks not_allowed)
			(vias allowed)
			(pads allowed)
			(copperpour not_allowed)
			(footprints allowed)
		)
		(placement
			(enabled no)
			(sheetname "")
		)
		(fill yes
			(thermal_gap 0.5)
			(thermal_bridge_width 0.5)
			(island_removal_mode 0)
		)
		(polygon
			(pts
				(arc
					(start 118.4402 -43.7642)
					(mid 118.404279 -43.779079)
					(end 118.3894 -43.815)
				)
				(arc
					(start 118.3894 -44.6278)
					(mid 118.404279 -44.663721)
					(end 118.4402 -44.6786)
				)
				(arc
					(start 118.6434 -44.6786)
					(mid 118.679321 -44.663721)
					(end 118.6942 -44.6278)
				)
				(arc
					(start 118.6942 -43.815)
					(mid 118.679321 -43.779079)
					(end 118.6434 -43.7642)
				)
			)
		)
	)
	(zone
		(layers "In5.Cu" "In6.Cu")
		(hatch none 0.5)
		(connect_pads
			(clearance 0)
		)
		(min_thickness 0.25)
		(keepout
			(tracks not_allowed)
			(vias allowed)
			(pads allowed)
			(copperpour not_allowed)
			(footprints allowed)
		)
		(placement
			(enabled no)
			(sheetname "")
		)
		(fill yes
			(thermal_gap 0.5)
			(thermal_bridge_width 0.5)
			(island_removal_mode 0)
		)
		(polygon
			(pts
				(arc
					(start 116.3574 -43.7642)
					(mid 116.321479 -43.779079)
					(end 116.3066 -43.815)
				)
				(arc
					(start 116.3066 -44.6278)
					(mid 116.321479 -44.663721)
					(end 116.3574 -44.6786)
				)
				(arc
					(start 116.5606 -44.6786)
					(mid 116.596521 -44.663721)
					(end 116.6114 -44.6278)
				)
				(arc
					(start 116.6114 -43.815)
					(mid 116.596521 -43.779079)
					(end 116.5606 -43.7642)
				)
			)
		)
	)
	(zone
		(layers "In5.Cu" "In6.Cu")
		(hatch none 0.5)
		(connect_pads
			(clearance 0)
		)
		(min_thickness 0.25)
		(keepout
			(tracks not_allowed)
			(vias allowed)
			(pads allowed)
			(copperpour not_allowed)
			(footprints allowed)
		)
		(placement
			(enabled no)
			(sheetname "")
		)
		(fill yes
			(thermal_gap 0.5)
			(thermal_bridge_width 0.5)
			(island_removal_mode 0)
		)
		(polygon
			(pts
				(arc
					(start 165.457378 -20.125944)
					(mid 165.421457 -20.140823)
					(end 165.406578 -20.176744)
				)
				(arc
					(start 165.406578 -20.989544)
					(mid 165.421457 -21.025465)
					(end 165.457378 -21.040344)
				)
				(arc
					(start 165.660578 -21.040344)
					(mid 165.696499 -21.025465)
					(end 165.711378 -20.989544)
				)
				(arc
					(start 165.711378 -20.176744)
					(mid 165.696499 -20.140823)
					(end 165.660578 -20.125944)
				)
			)
		)
	)
	(zone
		(layers "In5.Cu" "In6.Cu")
		(hatch none 0.5)
		(connect_pads
			(clearance 0)
		)
		(min_thickness 0.25)
		(keepout
			(tracks not_allowed)
			(vias allowed)
			(pads allowed)
			(copperpour not_allowed)
			(footprints allowed)
		)
		(placement
			(enabled no)
			(sheetname "")
		)
		(fill yes
			(thermal_gap 0.5)
			(thermal_bridge_width 0.5)
			(island_removal_mode 0)
		)
		(polygon
			(pts
				(arc
					(start 123.698 -39.0144)
					(mid 123.662079 -39.029279)
					(end 123.6472 -39.0652)
				)
				(arc
					(start 123.6472 -39.878)
					(mid 123.662079 -39.913921)
					(end 123.698 -39.9288)
				)
				(arc
					(start 123.9012 -39.9288)
					(mid 123.937121 -39.913921)
					(end 123.952 -39.878)
				)
				(arc
					(start 123.952 -39.0652)
					(mid 123.937121 -39.029279)
					(end 123.9012 -39.0144)
				)
			)
		)
	)
	(zone
		(layers "In5.Cu" "In6.Cu")
		(hatch none 0.5)
		(connect_pads
			(clearance 0)
		)
		(min_thickness 0.25)
		(keepout
			(tracks not_allowed)
			(vias allowed)
			(pads allowed)
			(copperpour not_allowed)
			(footprints allowed)
		)
		(placement
			(enabled no)
			(sheetname "")
		)
		(fill yes
			(thermal_gap 0.5)
			(thermal_bridge_width 0.5)
			(island_removal_mode 0)
		)
		(polygon
			(pts
				(arc
					(start 113.3094 -43.7642)
					(mid 113.273479 -43.779079)
					(end 113.2586 -43.815)
				)
				(arc
					(start 113.2586 -44.6278)
					(mid 113.273479 -44.663721)
					(end 113.3094 -44.6786)
				)
				(arc
					(start 113.5126 -44.6786)
					(mid 113.548521 -44.663721)
					(end 113.5634 -44.6278)
				)
				(arc
					(start 113.5634 -43.815)
					(mid 113.548521 -43.779079)
					(end 113.5126 -43.7642)
				)
			)
		)
	)
	(zone
		(layers "In5.Cu" "In6.Cu")
		(hatch none 0.5)
		(connect_pads
			(clearance 0)
		)
		(min_thickness 0.25)
		(keepout
			(tracks not_allowed)
			(vias allowed)
			(pads allowed)
			(copperpour not_allowed)
			(footprints allowed)
		)
		(placement
			(enabled no)
			(sheetname "")
		)
		(fill yes
			(thermal_gap 0.5)
			(thermal_bridge_width 0.5)
			(island_removal_mode 0)
		)
		(polygon
			(pts
				(arc
					(start 135.763 -75.9968)
					(mid 135.727079 -76.011679)
					(end 135.7122 -76.0476)
				)
				(arc
					(start 135.7122 -76.2508)
					(mid 135.727079 -76.286721)
					(end 135.763 -76.3016)
				)
				(arc
					(start 136.5758 -76.3016)
					(mid 136.611721 -76.286721)
					(end 136.6266 -76.2508)
				)
				(arc
					(start 136.6266 -76.0476)
					(mid 136.611721 -76.011679)
					(end 136.5758 -75.9968)
				)
			)
		)
	)
	(zone
		(layers "In5.Cu" "In6.Cu")
		(hatch none 0.5)
		(connect_pads
			(clearance 0)
		)
		(min_thickness 0.25)
		(keepout
			(tracks not_allowed)
			(vias allowed)
			(pads allowed)
			(copperpour not_allowed)
			(footprints allowed)
		)
		(placement
			(enabled no)
			(sheetname "")
		)
		(fill yes
			(thermal_gap 0.5)
			(thermal_bridge_width 0.5)
			(island_removal_mode 0)
		)
		(polygon
			(pts
				(arc
					(start 128.1176 -40.4114)
					(mid 128.081679 -40.426279)
					(end 128.0668 -40.4622)
				)
				(arc
					(start 128.0668 -41.275)
					(mid 128.081679 -41.310921)
					(end 128.1176 -41.3258)
				)
				(arc
					(start 128.3208 -41.3258)
					(mid 128.356721 -41.310921)
					(end 128.3716 -41.275)
				)
				(arc
					(start 128.3716 -40.4622)
					(mid 128.356721 -40.426279)
					(end 128.3208 -40.4114)
				)
			)
		)
	)
	(zone
		(layers "In5.Cu" "In6.Cu")
		(hatch none 0.5)
		(connect_pads
			(clearance 0)
		)
		(min_thickness 0.25)
		(keepout
			(tracks not_allowed)
			(vias allowed)
			(pads allowed)
			(copperpour not_allowed)
			(footprints allowed)
		)
		(placement
			(enabled no)
			(sheetname "")
		)
		(fill yes
			(thermal_gap 0.5)
			(thermal_bridge_width 0.5)
			(island_removal_mode 0)
		)
		(polygon
			(pts
				(arc
					(start 135.56488 -60.847478)
					(mid 135.528959 -60.862357)
					(end 135.51408 -60.898278)
				)
				(arc
					(start 135.51408 -61.711078)
					(mid 135.528959 -61.746999)
					(end 135.56488 -61.761878)
				)
				(arc
					(start 135.76808 -61.761878)
					(mid 135.804001 -61.746999)
					(end 135.81888 -61.711078)
				)
				(arc
					(start 135.81888 -60.898278)
					(mid 135.804001 -60.862357)
					(end 135.76808 -60.847478)
				)
			)
		)
	)
	(zone
		(layers "In5.Cu" "In6.Cu")
		(hatch none 0.5)
		(connect_pads
			(clearance 0)
		)
		(min_thickness 0.25)
		(keepout
			(tracks not_allowed)
			(vias allowed)
			(pads allowed)
			(copperpour not_allowed)
			(footprints allowed)
		)
		(placement
			(enabled no)
			(sheetname "")
		)
		(fill yes
			(thermal_gap 0.5)
			(thermal_bridge_width 0.5)
			(island_removal_mode 0)
		)
		(polygon
			(pts
				(arc
					(start 104.7242 -43.7642)
					(mid 104.688279 -43.779079)
					(end 104.6734 -43.815)
				)
				(arc
					(start 104.6734 -44.6278)
					(mid 104.688279 -44.663721)
					(end 104.7242 -44.6786)
				)
				(arc
					(start 104.9274 -44.6786)
					(mid 104.963321 -44.663721)
					(end 104.9782 -44.6278)
				)
				(arc
					(start 104.9782 -43.815)
					(mid 104.963321 -43.779079)
					(end 104.9274 -43.7642)
				)
			)
		)
	)
	(zone
		(layers "In5.Cu" "In6.Cu")
		(hatch none 0.5)
		(connect_pads
			(clearance 0)
		)
		(min_thickness 0.25)
		(keepout
			(tracks not_allowed)
			(vias allowed)
			(pads allowed)
			(copperpour not_allowed)
			(footprints allowed)
		)
		(placement
			(enabled no)
			(sheetname "")
		)
		(fill yes
			(thermal_gap 0.5)
			(thermal_bridge_width 0.5)
			(island_removal_mode 0)
		)
		(polygon
			(pts
				(arc
					(start 96.5454 -43.7642)
					(mid 96.509479 -43.779079)
					(end 96.4946 -43.815)
				)
				(arc
					(start 96.4946 -44.6278)
					(mid 96.509479 -44.663721)
					(end 96.5454 -44.6786)
				)
				(arc
					(start 96.7486 -44.6786)
					(mid 96.784521 -44.663721)
					(end 96.7994 -44.6278)
				)
				(arc
					(start 96.7994 -43.815)
					(mid 96.784521 -43.779079)
					(end 96.7486 -43.7642)
				)
			)
		)
	)
	(zone
		(layers "In5.Cu" "In6.Cu")
		(hatch none 0.5)
		(connect_pads
			(clearance 0)
		)
		(min_thickness 0.25)
		(keepout
			(tracks not_allowed)
			(vias allowed)
			(pads allowed)
			(copperpour not_allowed)
			(footprints allowed)
		)
		(placement
			(enabled no)
			(sheetname "")
		)
		(fill yes
			(thermal_gap 0.5)
			(thermal_bridge_width 0.5)
			(island_removal_mode 0)
		)
		(polygon
			(pts
				(arc
					(start 113.8682 -43.7642)
					(mid 113.832279 -43.779079)
					(end 113.8174 -43.815)
				)
				(arc
					(start 113.8174 -44.6278)
					(mid 113.832279 -44.663721)
					(end 113.8682 -44.6786)
				)
				(arc
					(start 114.0714 -44.6786)
					(mid 114.107321 -44.663721)
					(end 114.1222 -44.6278)
				)
				(arc
					(start 114.1222 -43.815)
					(mid 114.107321 -43.779079)
					(end 114.0714 -43.7642)
				)
			)
		)
	)
	(zone
		(layers "In5.Cu" "In6.Cu")
		(hatch none 0.5)
		(connect_pads
			(clearance 0)
		)
		(min_thickness 0.25)
		(keepout
			(tracks not_allowed)
			(vias allowed)
			(pads allowed)
			(copperpour not_allowed)
			(footprints allowed)
		)
		(placement
			(enabled no)
			(sheetname "")
		)
		(fill yes
			(thermal_gap 0.5)
			(thermal_bridge_width 0.5)
			(island_removal_mode 0)
		)
		(polygon
			(pts
				(arc
					(start 109.2962 -43.7642)
					(mid 109.260279 -43.779079)
					(end 109.2454 -43.815)
				)
				(arc
					(start 109.2454 -44.6278)
					(mid 109.260279 -44.663721)
					(end 109.2962 -44.6786)
				)
				(arc
					(start 109.4994 -44.6786)
					(mid 109.535321 -44.663721)
					(end 109.5502 -44.6278)
				)
				(arc
					(start 109.5502 -43.815)
					(mid 109.535321 -43.779079)
					(end 109.4994 -43.7642)
				)
			)
		)
	)
	(zone
		(layers "In5.Cu" "In6.Cu")
		(hatch none 0.5)
		(connect_pads
			(clearance 0)
		)
		(min_thickness 0.25)
		(keepout
			(tracks not_allowed)
			(vias allowed)
			(pads allowed)
			(copperpour not_allowed)
			(footprints allowed)
		)
		(placement
			(enabled no)
			(sheetname "")
		)
		(fill yes
			(thermal_gap 0.5)
			(thermal_bridge_width 0.5)
			(island_removal_mode 0)
		)
		(polygon
			(pts
				(arc
					(start 107.2134 -43.7642)
					(mid 107.177479 -43.779079)
					(end 107.1626 -43.815)
				)
				(arc
					(start 107.1626 -44.6278)
					(mid 107.177479 -44.663721)
					(end 107.2134 -44.6786)
				)
				(arc
					(start 107.4166 -44.6786)
					(mid 107.452521 -44.663721)
					(end 107.4674 -44.6278)
				)
				(arc
					(start 107.4674 -43.815)
					(mid 107.452521 -43.779079)
					(end 107.4166 -43.7642)
				)
			)
		)
	)
	(zone
		(layers "In5.Cu" "In6.Cu")
		(hatch none 0.5)
		(connect_pads
			(clearance 0)
		)
		(min_thickness 0.25)
		(keepout
			(tracks not_allowed)
			(vias allowed)
			(pads allowed)
			(copperpour not_allowed)
			(footprints allowed)
		)
		(placement
			(enabled no)
			(sheetname "")
		)
		(fill yes
			(thermal_gap 0.5)
			(thermal_bridge_width 0.5)
			(island_removal_mode 0)
		)
		(polygon
			(pts
				(arc
					(start 137.0584 -69.7484)
					(mid 137.022479 -69.763279)
					(end 137.0076 -69.7992)
				)
				(arc
					(start 137.0076 -70.0024)
					(mid 137.022479 -70.038321)
					(end 137.0584 -70.0532)
				)
				(arc
					(start 137.8712 -70.0532)
					(mid 137.907121 -70.038321)
					(end 137.922 -70.0024)
				)
				(arc
					(start 137.922 -69.7992)
					(mid 137.907121 -69.763279)
					(end 137.8712 -69.7484)
				)
			)
		)
	)
	(zone
		(layers "In5.Cu" "In6.Cu")
		(hatch none 0.5)
		(connect_pads
			(clearance 0)
		)
		(min_thickness 0.25)
		(keepout
			(tracks not_allowed)
			(vias allowed)
			(pads allowed)
			(copperpour not_allowed)
			(footprints allowed)
		)
		(placement
			(enabled no)
			(sheetname "")
		)
		(fill yes
			(thermal_gap 0.5)
			(thermal_bridge_width 0.5)
			(island_removal_mode 0)
		)
		(polygon
			(pts
				(arc
					(start 96.090994 -53.007768)
					(mid 96.055073 -53.022647)
					(end 96.040194 -53.058568)
				)
				(arc
					(start 96.040194 -53.261768)
					(mid 96.055073 -53.297689)
					(end 96.090994 -53.312568)
				)
				(arc
					(start 96.903794 -53.312568)
					(mid 96.939715 -53.297689)
					(end 96.954594 -53.261768)
				)
				(arc
					(start 96.954594 -53.058568)
					(mid 96.939715 -53.022647)
					(end 96.903794 -53.007768)
				)
			)
		)
	)
	(zone
		(layers "In5.Cu" "In6.Cu")
		(hatch none 0.5)
		(connect_pads
			(clearance 0)
		)
		(min_thickness 0.25)
		(keepout
			(tracks not_allowed)
			(vias allowed)
			(pads allowed)
			(copperpour not_allowed)
			(footprints allowed)
		)
		(placement
			(enabled no)
			(sheetname "")
		)
		(fill yes
			(thermal_gap 0.5)
			(thermal_bridge_width 0.5)
			(island_removal_mode 0)
		)
		(polygon
			(pts
				(arc
					(start 137.0584 -72.2884)
					(mid 137.022479 -72.303279)
					(end 137.0076 -72.3392)
				)
				(arc
					(start 137.0076 -72.5424)
					(mid 137.022479 -72.578321)
					(end 137.0584 -72.5932)
				)
				(arc
					(start 137.8712 -72.5932)
					(mid 137.907121 -72.578321)
					(end 137.922 -72.5424)
				)
				(arc
					(start 137.922 -72.3392)
					(mid 137.907121 -72.303279)
					(end 137.8712 -72.2884)
				)
			)
		)
	)
	(zone
		(layers "In5.Cu" "In6.Cu")
		(hatch none 0.5)
		(connect_pads
			(clearance 0)
		)
		(min_thickness 0.25)
		(keepout
			(tracks not_allowed)
			(vias allowed)
			(pads allowed)
			(copperpour not_allowed)
			(footprints allowed)
		)
		(placement
			(enabled no)
			(sheetname "")
		)
		(fill yes
			(thermal_gap 0.5)
			(thermal_bridge_width 0.5)
			(island_removal_mode 0)
		)
		(polygon
			(pts
				(arc
					(start 175.509428 -20.497546)
					(mid 175.473507 -20.512425)
					(end 175.458628 -20.548346)
				)
				(arc
					(start 175.458628 -21.361146)
					(mid 175.473507 -21.397067)
					(end 175.509428 -21.411946)
				)
				(arc
					(start 175.712628 -21.411946)
					(mid 175.748549 -21.397067)
					(end 175.763428 -21.361146)
				)
				(arc
					(start 175.763428 -20.548346)
					(mid 175.748549 -20.512425)
					(end 175.712628 -20.497546)
				)
			)
		)
	)
	(zone
		(layers "In5.Cu" "In6.Cu")
		(hatch none 0.5)
		(connect_pads
			(clearance 0)
		)
		(min_thickness 0.25)
		(keepout
			(tracks not_allowed)
			(vias allowed)
			(pads allowed)
			(copperpour not_allowed)
			(footprints allowed)
		)
		(placement
			(enabled no)
			(sheetname "")
		)
		(fill yes
			(thermal_gap 0.5)
			(thermal_bridge_width 0.5)
			(island_removal_mode 0)
		)
		(polygon
			(pts
				(arc
					(start 104.1654 -43.7642)
					(mid 104.129479 -43.779079)
					(end 104.1146 -43.815)
				)
				(arc
					(start 104.1146 -44.6278)
					(mid 104.129479 -44.663721)
					(end 104.1654 -44.6786)
				)
				(arc
					(start 104.3686 -44.6786)
					(mid 104.404521 -44.663721)
					(end 104.4194 -44.6278)
				)
				(arc
					(start 104.4194 -43.815)
					(mid 104.404521 -43.779079)
					(end 104.3686 -43.7642)
				)
			)
		)
	)
	(zone
		(layers "In5.Cu" "In6.Cu")
		(hatch none 0.5)
		(connect_pads
			(clearance 0)
		)
		(min_thickness 0.25)
		(keepout
			(tracks not_allowed)
			(vias allowed)
			(pads allowed)
			(copperpour not_allowed)
			(footprints allowed)
		)
		(placement
			(enabled no)
			(sheetname "")
		)
		(fill yes
			(thermal_gap 0.5)
			(thermal_bridge_width 0.5)
			(island_removal_mode 0)
		)
		(polygon
			(pts
				(arc
					(start 96.090994 -52.194968)
					(mid 96.055073 -52.209847)
					(end 96.040194 -52.245768)
				)
				(arc
					(start 96.040194 -52.448968)
					(mid 96.055073 -52.484889)
					(end 96.090994 -52.499768)
				)
				(arc
					(start 96.903794 -52.499768)
					(mid 96.939715 -52.484889)
					(end 96.954594 -52.448968)
				)
				(arc
					(start 96.954594 -52.245768)
					(mid 96.939715 -52.209847)
					(end 96.903794 -52.194968)
				)
			)
		)
	)
	(zone
		(layers "In5.Cu" "In6.Cu")
		(hatch none 0.5)
		(connect_pads
			(clearance 0)
		)
		(min_thickness 0.25)
		(keepout
			(tracks not_allowed)
			(vias allowed)
			(pads allowed)
			(copperpour not_allowed)
			(footprints allowed)
		)
		(placement
			(enabled no)
			(sheetname "")
		)
		(fill yes
			(thermal_gap 0.5)
			(thermal_bridge_width 0.5)
			(island_removal_mode 0)
		)
		(polygon
			(pts
				(arc
					(start 114.8334 -43.7642)
					(mid 114.797479 -43.779079)
					(end 114.7826 -43.815)
				)
				(arc
					(start 114.7826 -44.6278)
					(mid 114.797479 -44.663721)
					(end 114.8334 -44.6786)
				)
				(arc
					(start 115.0366 -44.6786)
					(mid 115.072521 -44.663721)
					(end 115.0874 -44.6278)
				)
				(arc
					(start 115.0874 -43.815)
					(mid 115.072521 -43.779079)
					(end 115.0366 -43.7642)
				)
			)
		)
	)
	(zone
		(layers "In5.Cu" "In6.Cu")
		(hatch none 0.5)
		(connect_pads
			(clearance 0)
		)
		(min_thickness 0.25)
		(keepout
			(tracks not_allowed)
			(vias allowed)
			(pads allowed)
			(copperpour not_allowed)
			(footprints allowed)
		)
		(placement
			(enabled no)
			(sheetname "")
		)
		(fill yes
			(thermal_gap 0.5)
			(thermal_bridge_width 0.5)
			(island_removal_mode 0)
		)
		(polygon
			(pts
				(arc
					(start 137.0584 -67.6402)
					(mid 137.022479 -67.655079)
					(end 137.0076 -67.691)
				)
				(arc
					(start 137.0076 -67.8942)
					(mid 137.022479 -67.930121)
					(end 137.0584 -67.945)
				)
				(arc
					(start 137.8712 -67.945)
					(mid 137.907121 -67.930121)
					(end 137.922 -67.8942)
				)
				(arc
					(start 137.922 -67.691)
					(mid 137.907121 -67.655079)
					(end 137.8712 -67.6402)
				)
			)
		)
	)
	(zone
		(layers "In5.Cu" "In6.Cu")
		(hatch none 0.5)
		(connect_pads
			(clearance 0)
		)
		(min_thickness 0.25)
		(keepout
			(tracks not_allowed)
			(vias allowed)
			(pads allowed)
			(copperpour not_allowed)
			(footprints allowed)
		)
		(placement
			(enabled no)
			(sheetname "")
		)
		(fill yes
			(thermal_gap 0.5)
			(thermal_bridge_width 0.5)
			(island_removal_mode 0)
		)
		(polygon
			(pts
				(arc
					(start 137.0076 -73.8886)
					(mid 136.971679 -73.903479)
					(end 136.9568 -73.9394)
				)
				(arc
					(start 136.9568 -74.1426)
					(mid 136.971679 -74.178521)
					(end 137.0076 -74.1934)
				)
				(arc
					(start 137.8204 -74.1934)
					(mid 137.856321 -74.178521)
					(end 137.8712 -74.1426)
				)
				(arc
					(start 137.8712 -73.9394)
					(mid 137.856321 -73.903479)
					(end 137.8204 -73.8886)
				)
			)
		)
	)
	(zone
		(layers "In5.Cu" "In6.Cu")
		(hatch none 0.5)
		(connect_pads
			(clearance 0)
		)
		(min_thickness 0.25)
		(keepout
			(tracks not_allowed)
			(vias allowed)
			(pads allowed)
			(copperpour not_allowed)
			(footprints allowed)
		)
		(placement
			(enabled no)
			(sheetname "")
		)
		(fill yes
			(thermal_gap 0.5)
			(thermal_bridge_width 0.5)
			(island_removal_mode 0)
		)
		(polygon
			(pts
				(arc
					(start 134.086854 -64.355218)
					(mid 134.050933 -64.370097)
					(end 134.036054 -64.406018)
				)
				(arc
					(start 134.036054 -64.609218)
					(mid 134.050933 -64.645139)
					(end 134.086854 -64.660018)
				)
				(arc
					(start 134.899654 -64.660018)
					(mid 134.935575 -64.645139)
					(end 134.950454 -64.609218)
				)
				(arc
					(start 134.950454 -64.406018)
					(mid 134.935575 -64.370097)
					(end 134.899654 -64.355218)
				)
			)
		)
	)
	(zone
		(layers "In5.Cu" "In6.Cu")
		(hatch none 0.5)
		(connect_pads
			(clearance 0)
		)
		(min_thickness 0.25)
		(keepout
			(tracks not_allowed)
			(vias allowed)
			(pads allowed)
			(copperpour not_allowed)
			(footprints allowed)
		)
		(placement
			(enabled no)
			(sheetname "")
		)
		(fill yes
			(thermal_gap 0.5)
			(thermal_bridge_width 0.5)
			(island_removal_mode 0)
		)
		(polygon
			(pts
				(arc
					(start 137.0584 -68.199)
					(mid 137.022479 -68.213879)
					(end 137.0076 -68.2498)
				)
				(arc
					(start 137.0076 -68.453)
					(mid 137.022479 -68.488921)
					(end 137.0584 -68.5038)
				)
				(arc
					(start 137.8712 -68.5038)
					(mid 137.907121 -68.488921)
					(end 137.922 -68.453)
				)
				(arc
					(start 137.922 -68.2498)
					(mid 137.907121 -68.213879)
					(end 137.8712 -68.199)
				)
			)
		)
	)
	(zone
		(layers "In5.Cu" "In6.Cu")
		(hatch none 0.5)
		(connect_pads
			(clearance 0)
		)
		(min_thickness 0.25)
		(keepout
			(tracks not_allowed)
			(vias allowed)
			(pads allowed)
			(copperpour not_allowed)
			(footprints allowed)
		)
		(placement
			(enabled no)
			(sheetname "")
		)
		(fill yes
			(thermal_gap 0.5)
			(thermal_bridge_width 0.5)
			(island_removal_mode 0)
		)
		(polygon
			(pts
				(arc
					(start 97.1042 -43.7642)
					(mid 97.068279 -43.779079)
					(end 97.0534 -43.815)
				)
				(arc
					(start 97.0534 -44.6278)
					(mid 97.068279 -44.663721)
					(end 97.1042 -44.6786)
				)
				(arc
					(start 97.3074 -44.6786)
					(mid 97.343321 -44.663721)
					(end 97.3582 -44.6278)
				)
				(arc
					(start 97.3582 -43.815)
					(mid 97.343321 -43.779079)
					(end 97.3074 -43.7642)
				)
			)
		)
	)
	(zone
		(layers "In5.Cu" "In6.Cu")
		(hatch none 0.5)
		(connect_pads
			(clearance 0)
		)
		(min_thickness 0.25)
		(keepout
			(tracks not_allowed)
			(vias allowed)
			(pads allowed)
			(copperpour not_allowed)
			(footprints allowed)
		)
		(placement
			(enabled no)
			(sheetname "")
		)
		(fill yes
			(thermal_gap 0.5)
			(thermal_bridge_width 0.5)
			(island_removal_mode 0)
		)
		(polygon
			(pts
				(arc
					(start 107.7722 -43.7642)
					(mid 107.736279 -43.779079)
					(end 107.7214 -43.815)
				)
				(arc
					(start 107.7214 -44.6278)
					(mid 107.736279 -44.663721)
					(end 107.7722 -44.6786)
				)
				(arc
					(start 107.9754 -44.6786)
					(mid 108.011321 -44.663721)
					(end 108.0262 -44.6278)
				)
				(arc
					(start 108.0262 -43.815)
					(mid 108.011321 -43.779079)
					(end 107.9754 -43.7642)
				)
			)
		)
	)
	(zone
		(layers "In5.Cu" "In6.Cu")
		(hatch none 0.5)
		(connect_pads
			(clearance 0)
		)
		(min_thickness 0.25)
		(keepout
			(tracks not_allowed)
			(vias allowed)
			(pads allowed)
			(copperpour not_allowed)
			(footprints allowed)
		)
		(placement
			(enabled no)
			(sheetname "")
		)
		(fill yes
			(thermal_gap 0.5)
			(thermal_bridge_width 0.5)
			(island_removal_mode 0)
		)
		(polygon
			(pts
				(arc
					(start 137.0584 -69.1896)
					(mid 137.022479 -69.204479)
					(end 137.0076 -69.2404)
				)
				(arc
					(start 137.0076 -69.4436)
					(mid 137.022479 -69.479521)
					(end 137.0584 -69.4944)
				)
				(arc
					(start 137.8712 -69.4944)
					(mid 137.907121 -69.479521)
					(end 137.922 -69.4436)
				)
				(arc
					(start 137.922 -69.2404)
					(mid 137.907121 -69.204479)
					(end 137.8712 -69.1896)
				)
			)
		)
	)
	(zone
		(layers "In5.Cu" "In6.Cu")
		(hatch none 0.5)
		(connect_pads
			(clearance 0)
		)
		(min_thickness 0.25)
		(keepout
			(tracks not_allowed)
			(vias allowed)
			(pads allowed)
			(copperpour not_allowed)
			(footprints allowed)
		)
		(placement
			(enabled no)
			(sheetname "")
		)
		(fill yes
			(thermal_gap 0.5)
			(thermal_bridge_width 0.5)
			(island_removal_mode 0)
		)
		(polygon
			(pts
				(arc
					(start 96.090994 -54.988968)
					(mid 96.055073 -55.003847)
					(end 96.040194 -55.039768)
				)
				(arc
					(start 96.040194 -55.242968)
					(mid 96.055073 -55.278889)
					(end 96.090994 -55.293768)
				)
				(arc
					(start 96.903794 -55.293768)
					(mid 96.939715 -55.278889)
					(end 96.954594 -55.242968)
				)
				(arc
					(start 96.954594 -55.039768)
					(mid 96.939715 -55.003847)
					(end 96.903794 -54.988968)
				)
			)
		)
	)
	(zone
		(layers "In5.Cu" "In6.Cu")
		(hatch none 0.5)
		(connect_pads
			(clearance 0)
		)
		(min_thickness 0.25)
		(keepout
			(tracks not_allowed)
			(vias allowed)
			(pads allowed)
			(copperpour not_allowed)
			(footprints allowed)
		)
		(placement
			(enabled no)
			(sheetname "")
		)
		(fill yes
			(thermal_gap 0.5)
			(thermal_bridge_width 0.5)
			(island_removal_mode 0)
		)
		(polygon
			(pts
				(arc
					(start 124.8918 -39.0144)
					(mid 124.855879 -39.029279)
					(end 124.841 -39.0652)
				)
				(arc
					(start 124.841 -39.878)
					(mid 124.855879 -39.913921)
					(end 124.8918 -39.9288)
				)
				(arc
					(start 125.095 -39.9288)
					(mid 125.130921 -39.913921)
					(end 125.1458 -39.878)
				)
				(arc
					(start 125.1458 -39.0652)
					(mid 125.130921 -39.029279)
					(end 125.095 -39.0144)
				)
			)
		)
	)
	(zone
		(layers "In5.Cu" "In6.Cu")
		(hatch none 0.5)
		(connect_pads
			(clearance 0)
		)
		(min_thickness 0.25)
		(keepout
			(tracks not_allowed)
			(vias allowed)
			(pads allowed)
			(copperpour not_allowed)
			(footprints allowed)
		)
		(placement
			(enabled no)
			(sheetname "")
		)
		(fill yes
			(thermal_gap 0.5)
			(thermal_bridge_width 0.5)
			(island_removal_mode 0)
		)
		(polygon
			(pts
				(arc
					(start 137.0584 -71.2978)
					(mid 137.022479 -71.312679)
					(end 137.0076 -71.3486)
				)
				(arc
					(start 137.0076 -71.5518)
					(mid 137.022479 -71.587721)
					(end 137.0584 -71.6026)
				)
				(arc
					(start 137.8712 -71.6026)
					(mid 137.907121 -71.587721)
					(end 137.922 -71.5518)
				)
				(arc
					(start 137.922 -71.3486)
					(mid 137.907121 -71.312679)
					(end 137.8712 -71.2978)
				)
			)
		)
	)
	(zone
		(layers "In5.Cu" "In6.Cu")
		(hatch none 0.5)
		(connect_pads
			(clearance 0)
		)
		(min_thickness 0.25)
		(keepout
			(tracks not_allowed)
			(vias allowed)
			(pads allowed)
			(copperpour not_allowed)
			(footprints allowed)
		)
		(placement
			(enabled no)
			(sheetname "")
		)
		(fill yes
			(thermal_gap 0.5)
			(thermal_bridge_width 0.5)
			(island_removal_mode 0)
		)
		(polygon
			(pts
				(arc
					(start 178.877214 -20.478242)
					(mid 178.862335 -20.442321)
					(end 178.826414 -20.427442)
				)
				(arc
					(start 178.013614 -20.427442)
					(mid 177.977693 -20.442321)
					(end 177.962814 -20.478242)
				)
				(arc
					(start 177.962814 -20.681442)
					(mid 177.977693 -20.717363)
					(end 178.013614 -20.732242)
				)
				(arc
					(start 178.826414 -20.732242)
					(mid 178.862335 -20.717363)
					(end 178.877214 -20.681442)
				)
			)
		)
	)
	(zone
		(layers "In5.Cu" "In6.Cu")
		(hatch none 0.5)
		(connect_pads
			(clearance 0)
		)
		(min_thickness 0.25)
		(keepout
			(tracks not_allowed)
			(vias allowed)
			(pads allowed)
			(copperpour not_allowed)
			(footprints allowed)
		)
		(placement
			(enabled no)
			(sheetname "")
		)
		(fill yes
			(thermal_gap 0.5)
			(thermal_bridge_width 0.5)
			(island_removal_mode 0)
		)
		(polygon
			(pts
				(arc
					(start 130.72237 -43.922188)
					(mid 130.686449 -43.937067)
					(end 130.67157 -43.972988)
				)
				(arc
					(start 130.67157 -44.785788)
					(mid 130.686449 -44.821709)
					(end 130.72237 -44.836588)
				)
				(arc
					(start 130.92557 -44.836588)
					(mid 130.961491 -44.821709)
					(end 130.97637 -44.785788)
				)
				(arc
					(start 130.97637 -43.972988)
					(mid 130.961491 -43.937067)
					(end 130.92557 -43.922188)
				)
			)
		)
	)
	(zone
		(layers "In5.Cu" "In6.Cu")
		(hatch none 0.5)
		(connect_pads
			(clearance 0)
		)
		(min_thickness 0.25)
		(keepout
			(tracks not_allowed)
			(vias allowed)
			(pads allowed)
			(copperpour not_allowed)
			(footprints allowed)
		)
		(placement
			(enabled no)
			(sheetname "")
		)
		(fill yes
			(thermal_gap 0.5)
			(thermal_bridge_width 0.5)
			(island_removal_mode 0)
		)
		(polygon
			(pts
				(arc
					(start 96.090994 -50.213768)
					(mid 96.055073 -50.228647)
					(end 96.040194 -50.264568)
				)
				(arc
					(start 96.040194 -50.467768)
					(mid 96.055073 -50.503689)
					(end 96.090994 -50.518568)
				)
				(arc
					(start 96.903794 -50.518568)
					(mid 96.939715 -50.503689)
					(end 96.954594 -50.467768)
				)
				(arc
					(start 96.954594 -50.264568)
					(mid 96.939715 -50.228647)
					(end 96.903794 -50.213768)
				)
			)
		)
	)
	(zone
		(layers "In5.Cu" "In6.Cu")
		(hatch none 0.5)
		(connect_pads
			(clearance 0)
		)
		(min_thickness 0.25)
		(keepout
			(tracks not_allowed)
			(vias allowed)
			(pads allowed)
			(copperpour not_allowed)
			(footprints allowed)
		)
		(placement
			(enabled no)
			(sheetname "")
		)
		(fill yes
			(thermal_gap 0.5)
			(thermal_bridge_width 0.5)
			(island_removal_mode 0)
		)
		(polygon
			(pts
				(arc
					(start 137.0584 -70.739)
					(mid 137.022479 -70.753879)
					(end 137.0076 -70.7898)
				)
				(arc
					(start 137.0076 -70.993)
					(mid 137.022479 -71.028921)
					(end 137.0584 -71.0438)
				)
				(arc
					(start 137.8712 -71.0438)
					(mid 137.907121 -71.028921)
					(end 137.922 -70.993)
				)
				(arc
					(start 137.922 -70.7898)
					(mid 137.907121 -70.753879)
					(end 137.8712 -70.739)
				)
			)
		)
	)
	(zone
		(layers "In5.Cu" "In6.Cu")
		(hatch none 0.5)
		(connect_pads
			(clearance 0)
		)
		(min_thickness 0.25)
		(keepout
			(tracks not_allowed)
			(vias allowed)
			(pads allowed)
			(copperpour not_allowed)
			(footprints allowed)
		)
		(placement
			(enabled no)
			(sheetname "")
		)
		(fill yes
			(thermal_gap 0.5)
			(thermal_bridge_width 0.5)
			(island_removal_mode 0)
		)
		(polygon
			(pts
				(arc
					(start 96.090994 -50.797968)
					(mid 96.055073 -50.812847)
					(end 96.040194 -50.848768)
				)
				(arc
					(start 96.040194 -51.051968)
					(mid 96.055073 -51.087889)
					(end 96.090994 -51.102768)
				)
				(arc
					(start 96.903794 -51.102768)
					(mid 96.939715 -51.087889)
					(end 96.954594 -51.051968)
				)
				(arc
					(start 96.954594 -50.848768)
					(mid 96.939715 -50.812847)
					(end 96.903794 -50.797968)
				)
			)
		)
	)
	(zone
		(layers "In5.Cu" "In6.Cu")
		(hatch none 0.5)
		(connect_pads
			(clearance 0)
		)
		(min_thickness 0.25)
		(keepout
			(tracks not_allowed)
			(vias allowed)
			(pads allowed)
			(copperpour not_allowed)
			(footprints allowed)
		)
		(placement
			(enabled no)
			(sheetname "")
		)
		(fill yes
			(thermal_gap 0.5)
			(thermal_bridge_width 0.5)
			(island_removal_mode 0)
		)
		(polygon
			(pts
				(arc
					(start 134.745222 -55.922418)
					(mid 134.709301 -55.937297)
					(end 134.694422 -55.973218)
				)
				(arc
					(start 134.694422 -56.786018)
					(mid 134.709301 -56.821939)
					(end 134.745222 -56.836818)
				)
				(arc
					(start 134.948422 -56.836818)
					(mid 134.984343 -56.821939)
					(end 134.999222 -56.786018)
				)
				(arc
					(start 134.999222 -55.973218)
					(mid 134.984343 -55.937297)
					(end 134.948422 -55.922418)
				)
			)
		)
	)
	(zone
		(layers "In5.Cu" "In6.Cu")
		(hatch none 0.5)
		(connect_pads
			(clearance 0)
		)
		(min_thickness 0.25)
		(keepout
			(tracks not_allowed)
			(vias allowed)
			(pads allowed)
			(copperpour not_allowed)
			(footprints allowed)
		)
		(placement
			(enabled no)
			(sheetname "")
		)
		(fill yes
			(thermal_gap 0.5)
			(thermal_bridge_width 0.5)
			(island_removal_mode 0)
		)
		(polygon
			(pts
				(arc
					(start 96.090994 -51.610768)
					(mid 96.055073 -51.625647)
					(end 96.040194 -51.661568)
				)
				(arc
					(start 96.040194 -51.864768)
					(mid 96.055073 -51.900689)
					(end 96.090994 -51.915568)
				)
				(arc
					(start 96.903794 -51.915568)
					(mid 96.939715 -51.900689)
					(end 96.954594 -51.864768)
				)
				(arc
					(start 96.954594 -51.661568)
					(mid 96.939715 -51.625647)
					(end 96.903794 -51.610768)
				)
			)
		)
	)
	(zone
		(layers "In5.Cu" "In6.Cu")
		(hatch none 0.5)
		(connect_pads
			(clearance 0)
		)
		(min_thickness 0.25)
		(keepout
			(tracks not_allowed)
			(vias allowed)
			(pads allowed)
			(copperpour not_allowed)
			(footprints allowed)
		)
		(placement
			(enabled no)
			(sheetname "")
		)
		(fill yes
			(thermal_gap 0.5)
			(thermal_bridge_width 0.5)
			(island_removal_mode 0)
		)
		(polygon
			(pts
				(arc
					(start 137.0584 -72.8472)
					(mid 137.022479 -72.862079)
					(end 137.0076 -72.898)
				)
				(arc
					(start 137.0076 -73.1012)
					(mid 137.022479 -73.137121)
					(end 137.0584 -73.152)
				)
				(arc
					(start 137.8712 -73.152)
					(mid 137.907121 -73.137121)
					(end 137.922 -73.1012)
				)
				(arc
					(start 137.922 -72.898)
					(mid 137.907121 -72.862079)
					(end 137.8712 -72.8472)
				)
			)
		)
	)
	(zone
		(layers "In5.Cu" "In6.Cu")
		(hatch none 0.5)
		(connect_pads
			(clearance 0)
		)
		(min_thickness 0.25)
		(keepout
			(tracks not_allowed)
			(vias allowed)
			(pads allowed)
			(copperpour not_allowed)
			(footprints allowed)
		)
		(placement
			(enabled no)
			(sheetname "")
		)
		(fill yes
			(thermal_gap 0.5)
			(thermal_bridge_width 0.5)
			(island_removal_mode 0)
		)
		(polygon
			(pts
				(arc
					(start 117.8814 -43.7642)
					(mid 117.845479 -43.779079)
					(end 117.8306 -43.815)
				)
				(arc
					(start 117.8306 -44.6278)
					(mid 117.845479 -44.663721)
					(end 117.8814 -44.6786)
				)
				(arc
					(start 118.0846 -44.6786)
					(mid 118.120521 -44.663721)
					(end 118.1354 -44.6278)
				)
				(arc
					(start 118.1354 -43.815)
					(mid 118.120521 -43.779079)
					(end 118.0846 -43.7642)
				)
			)
		)
	)
	(zone
		(layers "In5.Cu" "In6.Cu")
		(hatch none 0.5)
		(connect_pads
			(clearance 0)
		)
		(min_thickness 0.25)
		(keepout
			(tracks not_allowed)
			(vias allowed)
			(pads allowed)
			(copperpour not_allowed)
			(footprints allowed)
		)
		(placement
			(enabled no)
			(sheetname "")
		)
		(fill yes
			(thermal_gap 0.5)
			(thermal_bridge_width 0.5)
			(island_removal_mode 0)
		)
		(polygon
			(pts
				(arc
					(start 119.9642 -43.7642)
					(mid 119.928279 -43.779079)
					(end 119.9134 -43.815)
				)
				(arc
					(start 119.9134 -44.6278)
					(mid 119.928279 -44.663721)
					(end 119.9642 -44.6786)
				)
				(arc
					(start 120.1674 -44.6786)
					(mid 120.203321 -44.663721)
					(end 120.2182 -44.6278)
				)
				(arc
					(start 120.2182 -43.815)
					(mid 120.203321 -43.779079)
					(end 120.1674 -43.7642)
				)
			)
		)
	)
	(zone
		(layers "In5.Cu" "In6.Cu")
		(hatch none 0.5)
		(connect_pads
			(clearance 0)
		)
		(min_thickness 0.25)
		(keepout
			(tracks not_allowed)
			(vias allowed)
			(pads allowed)
			(copperpour not_allowed)
			(footprints allowed)
		)
		(placement
			(enabled no)
			(sheetname "")
		)
		(fill yes
			(thermal_gap 0.5)
			(thermal_bridge_width 0.5)
			(island_removal_mode 0)
		)
		(polygon
			(pts
				(arc
					(start 137.0584 -66.1162)
					(mid 137.022479 -66.131079)
					(end 137.0076 -66.167)
				)
				(arc
					(start 137.0076 -66.3702)
					(mid 137.022479 -66.406121)
					(end 137.0584 -66.421)
				)
				(arc
					(start 137.8712 -66.421)
					(mid 137.907121 -66.406121)
					(end 137.922 -66.3702)
				)
				(arc
					(start 137.922 -66.167)
					(mid 137.907121 -66.131079)
					(end 137.8712 -66.1162)
				)
			)
		)
	)
	(zone
		(layers "In5.Cu" "In6.Cu")
		(hatch none 0.5)
		(connect_pads
			(clearance 0)
		)
		(min_thickness 0.25)
		(keepout
			(tracks not_allowed)
			(vias allowed)
			(pads allowed)
			(copperpour not_allowed)
			(footprints allowed)
		)
		(placement
			(enabled no)
			(sheetname "")
		)
		(fill yes
			(thermal_gap 0.5)
			(thermal_bridge_width 0.5)
			(island_removal_mode 0)
		)
		(polygon
			(pts
				(arc
					(start 167.17772 -20.115784)
					(mid 167.141799 -20.130663)
					(end 167.12692 -20.166584)
				)
				(arc
					(start 167.12692 -20.979384)
					(mid 167.141799 -21.015305)
					(end 167.17772 -21.030184)
				)
				(arc
					(start 167.38092 -21.030184)
					(mid 167.416841 -21.015305)
					(end 167.43172 -20.979384)
				)
				(arc
					(start 167.43172 -20.166584)
					(mid 167.416841 -20.130663)
					(end 167.38092 -20.115784)
				)
			)
		)
	)
	(zone
		(layers "In5.Cu" "In6.Cu")
		(hatch none 0.5)
		(connect_pads
			(clearance 0)
		)
		(min_thickness 0.25)
		(keepout
			(tracks not_allowed)
			(vias allowed)
			(pads allowed)
			(copperpour not_allowed)
			(footprints allowed)
		)
		(placement
			(enabled no)
			(sheetname "")
		)
		(fill yes
			(thermal_gap 0.5)
			(thermal_bridge_width 0.5)
			(island_removal_mode 0)
		)
		(polygon
			(pts
				(arc
					(start 135.8138 -78.8924)
					(mid 135.777879 -78.907279)
					(end 135.763 -78.9432)
				)
				(arc
					(start 135.763 -79.1464)
					(mid 135.777879 -79.182321)
					(end 135.8138 -79.1972)
				)
				(arc
					(start 136.6266 -79.1972)
					(mid 136.662521 -79.182321)
					(end 136.6774 -79.1464)
				)
				(arc
					(start 136.6774 -78.9432)
					(mid 136.662521 -78.907279)
					(end 136.6266 -78.8924)
				)
			)
		)
	)
	(zone
		(layers "In5.Cu" "In6.Cu")
		(hatch none 0.5)
		(connect_pads
			(clearance 0)
		)
		(min_thickness 0.25)
		(keepout
			(tracks not_allowed)
			(vias allowed)
			(pads allowed)
			(copperpour not_allowed)
			(footprints allowed)
		)
		(placement
			(enabled no)
			(sheetname "")
		)
		(fill yes
			(thermal_gap 0.5)
			(thermal_bridge_width 0.5)
			(island_removal_mode 0)
		)
		(polygon
			(pts
				(arc
					(start 171.431204 -20.42922)
					(mid 171.395283 -20.444099)
					(end 171.380404 -20.48002)
				)
				(arc
					(start 171.380404 -21.29282)
					(mid 171.395283 -21.328741)
					(end 171.431204 -21.34362)
				)
				(arc
					(start 171.634404 -21.34362)
					(mid 171.670325 -21.328741)
					(end 171.685204 -21.29282)
				)
				(arc
					(start 171.685204 -20.48002)
					(mid 171.670325 -20.444099)
					(end 171.634404 -20.42922)
				)
			)
		)
	)
	(zone
		(layers "In5.Cu" "In6.Cu")
		(hatch none 0.5)
		(connect_pads
			(clearance 0)
		)
		(min_thickness 0.25)
		(keepout
			(tracks not_allowed)
			(vias allowed)
			(pads allowed)
			(copperpour not_allowed)
			(footprints allowed)
		)
		(placement
			(enabled no)
			(sheetname "")
		)
		(fill yes
			(thermal_gap 0.5)
			(thermal_bridge_width 0.5)
			(island_removal_mode 0)
		)
		(polygon
			(pts
				(arc
					(start 135.00608 -60.847478)
					(mid 134.970159 -60.862357)
					(end 134.95528 -60.898278)
				)
				(arc
					(start 134.95528 -61.711078)
					(mid 134.970159 -61.746999)
					(end 135.00608 -61.761878)
				)
				(arc
					(start 135.20928 -61.761878)
					(mid 135.245201 -61.746999)
					(end 135.26008 -61.711078)
				)
				(arc
					(start 135.26008 -60.898278)
					(mid 135.245201 -60.862357)
					(end 135.20928 -60.847478)
				)
			)
		)
	)
	(zone
		(layers "In5.Cu" "In6.Cu")
		(hatch none 0.5)
		(connect_pads
			(clearance 0)
		)
		(min_thickness 0.25)
		(keepout
			(tracks not_allowed)
			(vias allowed)
			(pads allowed)
			(copperpour not_allowed)
			(footprints allowed)
		)
		(placement
			(enabled no)
			(sheetname "")
		)
		(fill yes
			(thermal_gap 0.5)
			(thermal_bridge_width 0.5)
			(island_removal_mode 0)
		)
		(polygon
			(pts
				(arc
					(start 131.28117 -43.922188)
					(mid 131.245249 -43.937067)
					(end 131.23037 -43.972988)
				)
				(arc
					(start 131.23037 -44.785788)
					(mid 131.245249 -44.821709)
					(end 131.28117 -44.836588)
				)
				(arc
					(start 131.48437 -44.836588)
					(mid 131.520291 -44.821709)
					(end 131.53517 -44.785788)
				)
				(arc
					(start 131.53517 -43.972988)
					(mid 131.520291 -43.937067)
					(end 131.48437 -43.922188)
				)
			)
		)
	)
	(zone
		(layers "In5.Cu" "In6.Cu")
		(hatch none 0.5)
		(connect_pads
			(clearance 0)
		)
		(min_thickness 0.25)
		(keepout
			(tracks not_allowed)
			(vias allowed)
			(pads allowed)
			(copperpour not_allowed)
			(footprints allowed)
		)
		(placement
			(enabled no)
			(sheetname "")
		)
		(fill yes
			(thermal_gap 0.5)
			(thermal_bridge_width 0.5)
			(island_removal_mode 0)
		)
		(polygon
			(pts
				(arc
					(start 178.877976 -21.04898)
					(mid 178.863097 -21.013059)
					(end 178.827176 -20.99818)
				)
				(arc
					(start 178.014376 -20.99818)
					(mid 177.978455 -21.013059)
					(end 177.963576 -21.04898)
				)
				(arc
					(start 177.963576 -21.25218)
					(mid 177.978455 -21.288101)
					(end 178.014376 -21.30298)
				)
				(arc
					(start 178.827176 -21.30298)
					(mid 178.863097 -21.288101)
					(end 178.877976 -21.25218)
				)
			)
		)
	)
	(zone
		(layers "In5.Cu" "In6.Cu")
		(hatch none 0.5)
		(connect_pads
			(clearance 0)
		)
		(min_thickness 0.25)
		(keepout
			(tracks not_allowed)
			(vias allowed)
			(pads allowed)
			(copperpour not_allowed)
			(footprints allowed)
		)
		(placement
			(enabled no)
			(sheetname "")
		)
		(fill yes
			(thermal_gap 0.5)
			(thermal_bridge_width 0.5)
			(island_removal_mode 0)
		)
		(polygon
			(pts
				(arc
					(start 121.92 -39.0144)
					(mid 121.884079 -39.029279)
					(end 121.8692 -39.0652)
				)
				(arc
					(start 121.8692 -39.878)
					(mid 121.884079 -39.913921)
					(end 121.92 -39.9288)
				)
				(arc
					(start 122.1232 -39.9288)
					(mid 122.159121 -39.913921)
					(end 122.174 -39.878)
				)
				(arc
					(start 122.174 -39.0652)
					(mid 122.159121 -39.029279)
					(end 122.1232 -39.0144)
				)
			)
		)
	)
	(zone
		(layers "In5.Cu" "In6.Cu")
		(hatch none 0.5)
		(connect_pads
			(clearance 0)
		)
		(min_thickness 0.25)
		(keepout
			(tracks not_allowed)
			(vias allowed)
			(pads allowed)
			(copperpour not_allowed)
			(footprints allowed)
		)
		(placement
			(enabled no)
			(sheetname "")
		)
		(fill yes
			(thermal_gap 0.5)
			(thermal_bridge_width 0.5)
			(island_removal_mode 0)
		)
		(polygon
			(pts
				(arc
					(start 110.2614 -43.7642)
					(mid 110.225479 -43.779079)
					(end 110.2106 -43.815)
				)
				(arc
					(start 110.2106 -44.6278)
					(mid 110.225479 -44.663721)
					(end 110.2614 -44.6786)
				)
				(arc
					(start 110.4646 -44.6786)
					(mid 110.500521 -44.663721)
					(end 110.5154 -44.6278)
				)
				(arc
					(start 110.5154 -43.815)
					(mid 110.500521 -43.779079)
					(end 110.4646 -43.7642)
				)
			)
		)
	)
	(zone
		(layers "In5.Cu" "In6.Cu")
		(hatch none 0.5)
		(connect_pads
			(clearance 0)
		)
		(min_thickness 0.25)
		(keepout
			(tracks not_allowed)
			(vias allowed)
			(pads allowed)
			(copperpour not_allowed)
			(footprints allowed)
		)
		(placement
			(enabled no)
			(sheetname "")
		)
		(fill yes
			(thermal_gap 0.5)
			(thermal_bridge_width 0.5)
			(island_removal_mode 0)
		)
		(polygon
			(pts
				(arc
					(start 164.822378 -20.125944)
					(mid 164.786457 -20.140823)
					(end 164.771578 -20.176744)
				)
				(arc
					(start 164.771578 -20.989544)
					(mid 164.786457 -21.025465)
					(end 164.822378 -21.040344)
				)
				(arc
					(start 165.025578 -21.040344)
					(mid 165.061499 -21.025465)
					(end 165.076378 -20.989544)
				)
				(arc
					(start 165.076378 -20.176744)
					(mid 165.061499 -20.140823)
					(end 165.025578 -20.125944)
				)
			)
		)
	)
	(zone
		(layers "In5.Cu" "In6.Cu")
		(hatch none 0.5)
		(connect_pads
			(clearance 0)
		)
		(min_thickness 0.25)
		(keepout
			(tracks not_allowed)
			(vias allowed)
			(pads allowed)
			(copperpour not_allowed)
			(footprints allowed)
		)
		(placement
			(enabled no)
			(sheetname "")
		)
		(fill yes
			(thermal_gap 0.5)
			(thermal_bridge_width 0.5)
			(island_removal_mode 0)
		)
		(polygon
			(pts
				(arc
					(start 123.1138 -39.0144)
					(mid 123.077879 -39.029279)
					(end 123.063 -39.0652)
				)
				(arc
					(start 123.063 -39.878)
					(mid 123.077879 -39.913921)
					(end 123.1138 -39.9288)
				)
				(arc
					(start 123.317 -39.9288)
					(mid 123.352921 -39.913921)
					(end 123.3678 -39.878)
				)
				(arc
					(start 123.3678 -39.0652)
					(mid 123.352921 -39.029279)
					(end 123.317 -39.0144)
				)
			)
		)
	)
	(zone
		(layers "In5.Cu" "In6.Cu")
		(hatch none 0.5)
		(connect_pads
			(clearance 0)
		)
		(min_thickness 0.25)
		(keepout
			(tracks not_allowed)
			(vias allowed)
			(pads allowed)
			(copperpour not_allowed)
			(footprints allowed)
		)
		(placement
			(enabled no)
			(sheetname "")
		)
		(fill yes
			(thermal_gap 0.5)
			(thermal_bridge_width 0.5)
			(island_removal_mode 0)
		)
		(polygon
			(pts
				(arc
					(start 96.090994 -53.591968)
					(mid 96.055073 -53.606847)
					(end 96.040194 -53.642768)
				)
				(arc
					(start 96.040194 -53.845968)
					(mid 96.055073 -53.881889)
					(end 96.090994 -53.896768)
				)
				(arc
					(start 96.903794 -53.896768)
					(mid 96.939715 -53.881889)
					(end 96.954594 -53.845968)
				)
				(arc
					(start 96.954594 -53.642768)
					(mid 96.939715 -53.606847)
					(end 96.903794 -53.591968)
				)
			)
		)
	)
	(zone
		(layers "In5.Cu" "In6.Cu")
		(hatch none 0.5)
		(connect_pads
			(clearance 0)
		)
		(min_thickness 0.25)
		(keepout
			(tracks not_allowed)
			(vias allowed)
			(pads allowed)
			(copperpour not_allowed)
			(footprints allowed)
		)
		(placement
			(enabled no)
			(sheetname "")
		)
		(fill yes
			(thermal_gap 0.5)
			(thermal_bridge_width 0.5)
			(island_removal_mode 0)
		)
		(polygon
			(pts
				(arc
					(start 172.944282 -20.428966)
					(mid 172.908361 -20.443845)
					(end 172.893482 -20.479766)
				)
				(arc
					(start 172.893482 -21.292566)
					(mid 172.908361 -21.328487)
					(end 172.944282 -21.343366)
				)
				(arc
					(start 173.147482 -21.343366)
					(mid 173.183403 -21.328487)
					(end 173.198282 -21.292566)
				)
				(arc
					(start 173.198282 -20.479766)
					(mid 173.183403 -20.443845)
					(end 173.147482 -20.428966)
				)
			)
		)
	)
	(zone
		(layers "In5.Cu" "In6.Cu")
		(hatch none 0.5)
		(connect_pads
			(clearance 0)
		)
		(min_thickness 0.25)
		(keepout
			(tracks not_allowed)
			(vias allowed)
			(pads allowed)
			(copperpour not_allowed)
			(footprints allowed)
		)
		(placement
			(enabled no)
			(sheetname "")
		)
		(fill yes
			(thermal_gap 0.5)
			(thermal_bridge_width 0.5)
			(island_removal_mode 0)
		)
		(polygon
			(pts
				(arc
					(start 110.8202 -43.7642)
					(mid 110.784279 -43.779079)
					(end 110.7694 -43.815)
				)
				(arc
					(start 110.7694 -44.6278)
					(mid 110.784279 -44.663721)
					(end 110.8202 -44.6786)
				)
				(arc
					(start 111.0234 -44.6786)
					(mid 111.059321 -44.663721)
					(end 111.0742 -44.6278)
				)
				(arc
					(start 111.0742 -43.815)
					(mid 111.059321 -43.779079)
					(end 111.0234 -43.7642)
				)
			)
		)
	)
	(zone
		(layers "In5.Cu" "In6.Cu")
		(hatch none 0.5)
		(connect_pads
			(clearance 0)
		)
		(min_thickness 0.25)
		(keepout
			(tracks not_allowed)
			(vias allowed)
			(pads allowed)
			(copperpour not_allowed)
			(footprints allowed)
		)
		(placement
			(enabled no)
			(sheetname "")
		)
		(fill yes
			(thermal_gap 0.5)
			(thermal_bridge_width 0.5)
			(island_removal_mode 0)
		)
		(polygon
			(pts
				(arc
					(start 137.0584 -66.675)
					(mid 137.022479 -66.689879)
					(end 137.0076 -66.7258)
				)
				(arc
					(start 137.0076 -66.929)
					(mid 137.022479 -66.964921)
					(end 137.0584 -66.9798)
				)
				(arc
					(start 137.8712 -66.9798)
					(mid 137.907121 -66.964921)
					(end 137.922 -66.929)
				)
				(arc
					(start 137.922 -66.7258)
					(mid 137.907121 -66.689879)
					(end 137.8712 -66.675)
				)
			)
		)
	)
	(zone
		(layers "In5.Cu" "In6.Cu")
		(hatch none 0.5)
		(connect_pads
			(clearance 0)
		)
		(min_thickness 0.25)
		(keepout
			(tracks not_allowed)
			(vias allowed)
			(pads allowed)
			(copperpour not_allowed)
			(footprints allowed)
		)
		(placement
			(enabled no)
			(sheetname "")
		)
		(fill yes
			(thermal_gap 0.5)
			(thermal_bridge_width 0.5)
			(island_removal_mode 0)
		)
		(polygon
			(pts
				(arc
					(start 173.523402 -20.42922)
					(mid 173.487481 -20.444099)
					(end 173.472602 -20.48002)
				)
				(arc
					(start 173.472602 -21.29282)
					(mid 173.487481 -21.328741)
					(end 173.523402 -21.34362)
				)
				(arc
					(start 173.726602 -21.34362)
					(mid 173.762523 -21.328741)
					(end 173.777402 -21.29282)
				)
				(arc
					(start 173.777402 -20.48002)
					(mid 173.762523 -20.444099)
					(end 173.726602 -20.42922)
				)
			)
		)
	)
	(zone
		(layers "In5.Cu" "In6.Cu")
		(hatch none 0.5)
		(connect_pads
			(clearance 0)
		)
		(min_thickness 0.25)
		(keepout
			(tracks not_allowed)
			(vias allowed)
			(pads allowed)
			(copperpour not_allowed)
			(footprints allowed)
		)
		(placement
			(enabled no)
			(sheetname "")
		)
		(fill yes
			(thermal_gap 0.5)
			(thermal_bridge_width 0.5)
			(island_removal_mode 0)
		)
		(polygon
			(pts
				(arc
					(start 166.54272 -20.115784)
					(mid 166.506799 -20.130663)
					(end 166.49192 -20.166584)
				)
				(arc
					(start 166.49192 -20.979384)
					(mid 166.506799 -21.015305)
					(end 166.54272 -21.030184)
				)
				(arc
					(start 166.74592 -21.030184)
					(mid 166.781841 -21.015305)
					(end 166.79672 -20.979384)
				)
				(arc
					(start 166.79672 -20.166584)
					(mid 166.781841 -20.130663)
					(end 166.74592 -20.115784)
				)
			)
		)
	)
	(zone
		(layers "In5.Cu" "In6.Cu")
		(hatch none 0.5)
		(connect_pads
			(clearance 0)
		)
		(min_thickness 0.25)
		(keepout
			(tracks not_allowed)
			(vias allowed)
			(pads allowed)
			(copperpour not_allowed)
			(footprints allowed)
		)
		(placement
			(enabled no)
			(sheetname "")
		)
		(fill yes
			(thermal_gap 0.5)
			(thermal_bridge_width 0.5)
			(island_removal_mode 0)
		)
		(polygon
			(pts
				(arc
					(start 135.8138 -79.4512)
					(mid 135.777879 -79.466079)
					(end 135.763 -79.502)
				)
				(arc
					(start 135.763 -79.7052)
					(mid 135.777879 -79.741121)
					(end 135.8138 -79.756)
				)
				(arc
					(start 136.6266 -79.756)
					(mid 136.662521 -79.741121)
					(end 136.6774 -79.7052)
				)
				(arc
					(start 136.6774 -79.502)
					(mid 136.662521 -79.466079)
					(end 136.6266 -79.4512)
				)
			)
		)
	)
	(zone
		(layers "In5.Cu" "In6.Cu")
		(hatch none 0.5)
		(connect_pads
			(clearance 0)
		)
		(min_thickness 0.25)
		(keepout
			(tracks not_allowed)
			(vias allowed)
			(pads allowed)
			(copperpour not_allowed)
			(footprints allowed)
		)
		(placement
			(enabled no)
			(sheetname "")
		)
		(fill yes
			(thermal_gap 0.5)
			(thermal_bridge_width 0.5)
			(island_removal_mode 0)
		)
		(polygon
			(pts
				(arc
					(start 121.3358 -39.0144)
					(mid 121.299879 -39.029279)
					(end 121.285 -39.0652)
				)
				(arc
					(start 121.285 -39.878)
					(mid 121.299879 -39.913921)
					(end 121.3358 -39.9288)
				)
				(arc
					(start 121.539 -39.9288)
					(mid 121.574921 -39.913921)
					(end 121.5898 -39.878)
				)
				(arc
					(start 121.5898 -39.0652)
					(mid 121.574921 -39.029279)
					(end 121.539 -39.0144)
				)
			)
		)
	)
	(zone
		(layers "In5.Cu" "In6.Cu")
		(hatch none 0.5)
		(connect_pads
			(clearance 0)
		)
		(min_thickness 0.25)
		(keepout
			(tracks not_allowed)
			(vias allowed)
			(pads allowed)
			(copperpour not_allowed)
			(footprints allowed)
		)
		(placement
			(enabled no)
			(sheetname "")
		)
		(fill yes
			(thermal_gap 0.5)
			(thermal_bridge_width 0.5)
			(island_removal_mode 0)
		)
		(polygon
			(pts
				(arc
					(start 174.942246 -20.497292)
					(mid 174.906325 -20.512171)
					(end 174.891446 -20.548092)
				)
				(arc
					(start 174.891446 -21.360892)
					(mid 174.906325 -21.396813)
					(end 174.942246 -21.411692)
				)
				(arc
					(start 175.145446 -21.411692)
					(mid 175.181367 -21.396813)
					(end 175.196246 -21.360892)
				)
				(arc
					(start 175.196246 -20.548092)
					(mid 175.181367 -20.512171)
					(end 175.145446 -20.497292)
				)
			)
		)
	)
	(zone
		(layers "In5.Cu" "In6.Cu")
		(hatch none 0.5)
		(connect_pads
			(clearance 0)
		)
		(min_thickness 0.25)
		(keepout
			(tracks not_allowed)
			(vias allowed)
			(pads allowed)
			(copperpour not_allowed)
			(footprints allowed)
		)
		(placement
			(enabled no)
			(sheetname "")
		)
		(fill yes
			(thermal_gap 0.5)
			(thermal_bridge_width 0.5)
			(island_removal_mode 0)
		)
		(polygon
			(pts
				(arc
					(start 119.4054 -43.7642)
					(mid 119.369479 -43.779079)
					(end 119.3546 -43.815)
				)
				(arc
					(start 119.3546 -44.6278)
					(mid 119.369479 -44.663721)
					(end 119.4054 -44.6786)
				)
				(arc
					(start 119.6086 -44.6786)
					(mid 119.644521 -44.663721)
					(end 119.6594 -44.6278)
				)
				(arc
					(start 119.6594 -43.815)
					(mid 119.644521 -43.779079)
					(end 119.6086 -43.7642)
				)
			)
		)
	)
	(zone
		(layers "In5.Cu" "In6.Cu")
		(hatch none 0.5)
		(connect_pads
			(clearance 0)
		)
		(min_thickness 0.25)
		(keepout
			(tracks not_allowed)
			(vias allowed)
			(pads allowed)
			(copperpour not_allowed)
			(footprints allowed)
		)
		(placement
			(enabled no)
			(sheetname "")
		)
		(fill yes
			(thermal_gap 0.5)
			(thermal_bridge_width 0.5)
			(island_removal_mode 0)
		)
		(polygon
			(pts
				(arc
					(start 115.3922 -43.7642)
					(mid 115.356279 -43.779079)
					(end 115.3414 -43.815)
				)
				(arc
					(start 115.3414 -44.6278)
					(mid 115.356279 -44.663721)
					(end 115.3922 -44.6786)
				)
				(arc
					(start 115.5954 -44.6786)
					(mid 115.631321 -44.663721)
					(end 115.6462 -44.6278)
				)
				(arc
					(start 115.6462 -43.815)
					(mid 115.631321 -43.779079)
					(end 115.5954 -43.7642)
				)
			)
		)
	)
	(zone
		(layers "In5.Cu" "In6.Cu")
		(hatch none 0.5)
		(connect_pads
			(clearance 0)
		)
		(min_thickness 0.25)
		(keepout
			(tracks not_allowed)
			(vias allowed)
			(pads allowed)
			(copperpour not_allowed)
			(footprints allowed)
		)
		(placement
			(enabled no)
			(sheetname "")
		)
		(fill yes
			(thermal_gap 0.5)
			(thermal_bridge_width 0.5)
			(island_removal_mode 0)
		)
		(polygon
			(pts
				(arc
					(start 103.2002 -43.7642)
					(mid 103.164279 -43.779079)
					(end 103.1494 -43.815)
				)
				(arc
					(start 103.1494 -44.6278)
					(mid 103.164279 -44.663721)
					(end 103.2002 -44.6786)
				)
				(arc
					(start 103.4034 -44.6786)
					(mid 103.439321 -44.663721)
					(end 103.4542 -44.6278)
				)
				(arc
					(start 103.4542 -43.815)
					(mid 103.439321 -43.779079)
					(end 103.4034 -43.7642)
				)
			)
		)
	)
	(zone
		(layers "In5.Cu" "In6.Cu")
		(hatch none 0.5)
		(connect_pads
			(clearance 0)
		)
		(min_thickness 0.25)
		(keepout
			(tracks not_allowed)
			(vias allowed)
			(pads allowed)
			(copperpour not_allowed)
			(footprints allowed)
		)
		(placement
			(enabled no)
			(sheetname "")
		)
		(fill yes
			(thermal_gap 0.5)
			(thermal_bridge_width 0.5)
			(island_removal_mode 0)
		)
		(polygon
			(pts
				(arc
					(start 100.1522 -43.7642)
					(mid 100.116279 -43.779079)
					(end 100.1014 -43.815)
				)
				(arc
					(start 100.1014 -44.6278)
					(mid 100.116279 -44.663721)
					(end 100.1522 -44.6786)
				)
				(arc
					(start 100.3554 -44.6786)
					(mid 100.391321 -44.663721)
					(end 100.4062 -44.6278)
				)
				(arc
					(start 100.4062 -43.815)
					(mid 100.391321 -43.779079)
					(end 100.3554 -43.7642)
				)
			)
		)
	)
	(zone
		(layers "In5.Cu" "In6.Cu")
		(hatch none 0.5)
		(connect_pads
			(clearance 0)
		)
		(min_thickness 0.25)
		(keepout
			(tracks not_allowed)
			(vias allowed)
			(pads allowed)
			(copperpour not_allowed)
			(footprints allowed)
		)
		(placement
			(enabled no)
			(sheetname "")
		)
		(fill yes
			(thermal_gap 0.5)
			(thermal_bridge_width 0.5)
			(island_removal_mode 0)
		)
		(polygon
			(pts
				(arc
					(start 181.72684 -21.17344)
					(mid 181.711961 -21.137519)
					(end 181.67604 -21.12264)
				)
				(arc
					(start 180.86324 -21.12264)
					(mid 180.827319 -21.137519)
					(end 180.81244 -21.17344)
				)
				(arc
					(start 180.81244 -21.37664)
					(mid 180.827319 -21.412561)
					(end 180.86324 -21.42744)
				)
				(arc
					(start 181.67604 -21.42744)
					(mid 181.711961 -21.412561)
					(end 181.72684 -21.37664)
				)
			)
		)
	)
	(zone
		(layers "In5.Cu" "In6.Cu")
		(hatch none 0.5)
		(connect_pads
			(clearance 0)
		)
		(min_thickness 0.25)
		(keepout
			(tracks not_allowed)
			(vias allowed)
			(pads allowed)
			(copperpour not_allowed)
			(footprints allowed)
		)
		(placement
			(enabled no)
			(sheetname "")
		)
		(fill yes
			(thermal_gap 0.5)
			(thermal_bridge_width 0.5)
			(island_removal_mode 0)
		)
		(polygon
			(pts
				(arc
					(start 111.7854 -43.7642)
					(mid 111.749479 -43.779079)
					(end 111.7346 -43.815)
				)
				(arc
					(start 111.7346 -44.6278)
					(mid 111.749479 -44.663721)
					(end 111.7854 -44.6786)
				)
				(arc
					(start 111.9886 -44.6786)
					(mid 112.024521 -44.663721)
					(end 112.0394 -44.6278)
				)
				(arc
					(start 112.0394 -43.815)
					(mid 112.024521 -43.779079)
					(end 111.9886 -43.7642)
				)
			)
		)
	)
	(zone
		(net "GND")
		(layer "In6.Cu")
		(hatch none 0.5)
		(connect_pads
			(clearance 0.5)
		)
		(min_thickness 0.25)
		(fill yes
			(thermal_gap 0.5)
			(thermal_bridge_width 0.5)
			(island_removal_mode 0)
		)
		(polygon
			(pts
				(arc
					(start 1.999996 -0.763016)
					(mid 1.125319 -1.125319)
					(end 0.763016 -1.999996)
				)
				(arc
					(start 0.763016 -142.999968)
					(mid 1.125319 -143.874645)
					(end 1.999996 -144.236948)
				)
				(arc
					(start 83.002882 -144.236948)
					(mid 83.877395 -143.874555)
					(end 84.239608 -142.999968)
				)
				(arc
					(start 84.239608 -132.262626)
					(mid 85.617496 -128.523498)
					(end 89.092024 -126.572264)
				)
				(xy 97.43948 -125.236986) (xy 112.560354 -125.236986)
				(arc
					(start 120.91289 -126.573026)
					(mid 124.387646 -128.524285)
					(end 125.76556 -132.263642)
				)
				(arc
					(start 125.76556 -142.999968)
					(mid 126.127863 -143.874645)
					(end 127.00254 -144.236948)
				)
				(arc
					(start 208.000092 -144.236948)
					(mid 208.874769 -143.874645)
					(end 209.237072 -142.999968)
				)
				(arc
					(start 209.237072 -1.999996)
					(mid 208.874769 -1.125319)
					(end 208.000092 -0.763016)
				)
			)
		)
		(polygon
			(pts
				(arc
					(start 106.233722 -115.10899)
					(mid 106.009186 -114.366294)
					(end 105.26649 -114.59083)
				)
				(arc
					(start 104.516428 -115.990624)
					(mid 104.740809 -116.733627)
					(end 105.48366 -116.509038)
				)
			)
		)
		(polygon
			(pts
				(arc
					(start 103.983536 -115.10899)
					(mid 103.759 -114.366294)
					(end 103.016304 -114.59083)
				)
				(xy 102.266496 -115.990624)
				(arc
					(start 102.266496 -115.990878)
					(mid 102.491032 -116.733574)
					(end 103.233728 -116.509038)
				)
			)
		)
		(polygon
			(pts
				(arc
					(start 106.233722 -111.30915)
					(mid 106.009186 -110.566454)
					(end 105.26649 -110.79099)
				)
				(arc
					(start 104.516428 -112.190784)
					(mid 104.740809 -112.933787)
					(end 105.48366 -112.709198)
				)
			)
		)
		(polygon
			(pts
				(arc
					(start 103.983536 -111.30915)
					(mid 103.759 -110.566454)
					(end 103.016304 -110.79099)
				)
				(xy 102.266496 -112.190784)
				(arc
					(start 102.266496 -112.191038)
					(mid 102.491032 -112.933734)
					(end 103.233728 -112.709198)
				)
			)
		)
		(polygon
			(pts
				(arc
					(start 106.188256 -107.484672)
					(mid 105.984802 -106.811826)
					(end 105.311956 -107.01528)
				)
				(xy 105.311194 -107.014772) (xy 104.561386 -108.41482) (xy 104.561386 -108.415074)
				(arc
					(start 104.561894 -108.415328)
					(mid 104.765348 -109.088174)
					(end 105.438194 -108.88472)
				)
				(xy 105.438956 -108.885228) (xy 106.189018 -107.48518)
			)
		)
		(polygon
			(pts
				(arc
					(start 103.93807 -107.484672)
					(mid 103.734616 -106.811826)
					(end 103.06177 -107.01528)
				)
				(xy 103.061008 -107.015026) (xy 102.311454 -108.41482) (xy 102.311454 -108.415074)
				(arc
					(start 102.311962 -108.415328)
					(mid 102.515416 -109.088174)
					(end 103.188262 -108.88472)
				)
				(xy 103.189024 -108.884974) (xy 103.938832 -107.484926)
			)
		)
		(polygon
			(pts
				(arc
					(start 106.188256 -103.684832)
					(mid 105.984802 -103.011986)
					(end 105.311956 -103.21544)
				)
				(xy 105.311194 -103.214932) (xy 104.561386 -104.614472) (xy 104.561386 -104.61498)
				(arc
					(start 104.561894 -104.615234)
					(mid 104.765348 -105.28808)
					(end 105.438194 -105.084626)
				)
				(xy 105.438956 -105.085134) (xy 106.189018 -103.68534)
			)
		)
		(polygon
			(pts
				(arc
					(start 103.93807 -103.684832)
					(mid 103.734616 -103.011986)
					(end 103.06177 -103.21544)
				)
				(xy 103.061008 -103.215186) (xy 102.311454 -104.614726) (xy 102.311454 -104.61498)
				(arc
					(start 102.311962 -104.615234)
					(mid 102.515416 -105.28808)
					(end 103.188262 -105.084626)
				)
				(xy 103.189024 -105.08488) (xy 103.938832 -103.685086)
			)
		)
		(polygon
			(pts
				(xy 139.986258 -81.924906) (xy 138.843512 -81.924906) (xy 138.843258 -81.92516)
				(arc
					(start 138.843258 -81.925668)
					(mid 138.46048 -82.308446)
					(end 138.843258 -82.691224)
				)
				(xy 138.843258 -82.691986) (xy 139.986258 -82.691986)
				(arc
					(start 139.986258 -82.691224)
					(mid 140.369036 -82.308446)
					(end 139.986258 -81.925668)
				)
			)
		)
		(polygon
			(pts
				(xy 139.643612 -79.813912) (xy 138.500866 -79.813912) (xy 138.500612 -79.814166)
				(arc
					(start 138.500612 -79.814674)
					(mid 138.117834 -80.197452)
					(end 138.500612 -80.58023)
				)
				(xy 138.500612 -80.580992) (xy 139.643612 -80.580992)
				(arc
					(start 139.643612 -80.58023)
					(mid 140.02639 -80.197452)
					(end 139.643612 -79.814674)
				)
			)
		)
		(polygon
			(pts
				(xy 139.629134 -78.044294) (xy 138.486134 -78.044294)
				(arc
					(start 138.486134 -78.045056)
					(mid 138.103356 -78.427834)
					(end 138.486134 -78.810612)
				)
				(xy 138.486134 -78.811374) (xy 139.62888 -78.811374) (xy 139.629134 -78.81112)
				(arc
					(start 139.629134 -78.810612)
					(mid 140.011912 -78.427834)
					(end 139.629134 -78.045056)
				)
			)
		)
		(polygon
			(pts
				(arc
					(start 127 -77.35824)
					(mid 127.35814 -77.0001)
					(end 127 -76.64196)
				)
				(arc
					(start 125.999748 -76.64196)
					(mid 125.641862 -77.000227)
					(end 126.000002 -77.35824)
				)
			)
		)
		(polygon
			(pts
				(xy 139.622022 -76.14158) (xy 138.479276 -76.14158) (xy 138.479022 -76.141834)
				(arc
					(start 138.479022 -76.142342)
					(mid 138.096244 -76.52512)
					(end 138.479022 -76.907898)
				)
				(xy 138.479022 -76.90866) (xy 139.622022 -76.90866)
				(arc
					(start 139.622022 -76.907898)
					(mid 140.0048 -76.52512)
					(end 139.622022 -76.142342)
				)
			)
		)
		(polygon
			(pts
				(arc
					(start 127 -76.358242)
					(mid 127.35814 -76.000102)
					(end 127 -75.641962)
				)
				(arc
					(start 125.999748 -75.641962)
					(mid 125.641862 -76.000229)
					(end 126.000002 -76.358242)
				)
			)
		)
		(polygon
			(pts
				(arc
					(start 136.6266 -75.4888)
					(mid 136.611721 -75.452879)
					(end 136.5758 -75.438)
				)
				(arc
					(start 135.763 -75.438)
					(mid 135.727079 -75.452879)
					(end 135.7122 -75.4888)
				)
				(arc
					(start 135.7122 -75.692)
					(mid 135.727079 -75.727921)
					(end 135.763 -75.7428)
				)
				(arc
					(start 136.5758 -75.7428)
					(mid 136.611721 -75.727921)
					(end 136.6266 -75.692)
				)
			)
		)
		(polygon
			(pts
				(arc
					(start 127 -75.358244)
					(mid 127.35814 -75.000104)
					(end 127 -74.641964)
				)
				(arc
					(start 125.999748 -74.641964)
					(mid 125.641862 -75.000231)
					(end 126.000002 -75.358244)
				)
			)
		)
		(polygon
			(pts
				(arc
					(start 137.8712 -74.4982)
					(mid 137.856321 -74.462279)
					(end 137.8204 -74.4474)
				)
				(arc
					(start 137.0076 -74.4474)
					(mid 136.971679 -74.462279)
					(end 136.9568 -74.4982)
				)
				(arc
					(start 136.9568 -74.7014)
					(mid 136.971679 -74.737321)
					(end 137.0076 -74.7522)
				)
				(arc
					(start 137.8204 -74.7522)
					(mid 137.856321 -74.737321)
					(end 137.8712 -74.7014)
				)
			)
		)
		(polygon
			(pts
				(arc
					(start 137.8712 -73.9394)
					(mid 137.856321 -73.903479)
					(end 137.8204 -73.8886)
				)
				(arc
					(start 137.0076 -73.8886)
					(mid 136.971679 -73.903479)
					(end 136.9568 -73.9394)
				)
				(arc
					(start 136.9568 -74.1426)
					(mid 136.971679 -74.178521)
					(end 137.0076 -74.1934)
				)
				(arc
					(start 137.8204 -74.1934)
					(mid 137.856321 -74.178521)
					(end 137.8712 -74.1426)
				)
			)
		)
		(polygon
			(pts
				(arc
					(start 127 -74.358246)
					(mid 127.35814 -74.000106)
					(end 127 -73.641966)
				)
				(arc
					(start 125.999748 -73.641966)
					(mid 125.641862 -74.000233)
					(end 126.000002 -74.358246)
				)
			)
		)
		(polygon
			(pts
				(arc
					(start 137.922 -72.898)
					(mid 137.907121 -72.862079)
					(end 137.8712 -72.8472)
				)
				(arc
					(start 137.0584 -72.8472)
					(mid 137.022479 -72.862079)
					(end 137.0076 -72.898)
				)
				(arc
					(start 137.0076 -73.1012)
					(mid 137.022479 -73.137121)
					(end 137.0584 -73.152)
				)
				(arc
					(start 137.8712 -73.152)
					(mid 137.907121 -73.137121)
					(end 137.922 -73.1012)
				)
			)
		)
		(polygon
			(pts
				(arc
					(start 130.999992 -73.358248)
					(mid 131.358132 -73.000108)
					(end 130.999992 -72.641968)
				)
				(arc
					(start 129.99974 -72.641968)
					(mid 129.641854 -73.000235)
					(end 129.999994 -73.358248)
				)
			)
		)
		(polygon
			(pts
				(arc
					(start 127 -73.358248)
					(mid 127.35814 -73.000108)
					(end 127 -72.641968)
				)
				(arc
					(start 125.999748 -72.641968)
					(mid 125.641862 -73.000235)
					(end 126.000002 -73.358248)
				)
			)
		)
		(polygon
			(pts
				(arc
					(start 137.922 -72.3392)
					(mid 137.907121 -72.303279)
					(end 137.8712 -72.2884)
				)
				(arc
					(start 137.0584 -72.2884)
					(mid 137.022479 -72.303279)
					(end 137.0076 -72.3392)
				)
				(arc
					(start 137.0076 -72.5424)
					(mid 137.022479 -72.578321)
					(end 137.0584 -72.5932)
				)
				(arc
					(start 137.8712 -72.5932)
					(mid 137.907121 -72.578321)
					(end 137.922 -72.5424)
				)
			)
		)
		(polygon
			(pts
				(arc
					(start 129.999994 -72.35825)
					(mid 130.358134 -72.00011)
					(end 129.999994 -71.64197)
				)
				(arc
					(start 128.999742 -71.64197)
					(mid 128.641856 -72.000237)
					(end 128.999996 -72.35825)
				)
			)
		)
		(polygon
			(pts
				(arc
					(start 127 -72.35825)
					(mid 127.35814 -72.00011)
					(end 127 -71.64197)
				)
				(arc
					(start 125.999748 -71.64197)
					(mid 125.641862 -72.000237)
					(end 126.000002 -72.35825)
				)
			)
		)
		(polygon
			(pts
				(arc
					(start 137.922 -71.3486)
					(mid 137.907121 -71.312679)
					(end 137.8712 -71.2978)
				)
				(arc
					(start 137.0584 -71.2978)
					(mid 137.022479 -71.312679)
					(end 137.0076 -71.3486)
				)
				(arc
					(start 137.0076 -71.5518)
					(mid 137.022479 -71.587721)
					(end 137.0584 -71.6026)
				)
				(arc
					(start 137.8712 -71.6026)
					(mid 137.907121 -71.587721)
					(end 137.922 -71.5518)
				)
			)
		)
		(polygon
			(pts
				(arc
					(start 137.922 -70.7898)
					(mid 137.907121 -70.753879)
					(end 137.8712 -70.739)
				)
				(arc
					(start 137.0584 -70.739)
					(mid 137.022479 -70.753879)
					(end 137.0076 -70.7898)
				)
				(arc
					(start 137.0076 -70.993)
					(mid 137.022479 -71.028921)
					(end 137.0584 -71.0438)
				)
				(arc
					(start 137.8712 -71.0438)
					(mid 137.907121 -71.028921)
					(end 137.922 -70.993)
				)
			)
		)
		(polygon
			(pts
				(arc
					(start 130.999992 -71.358252)
					(mid 131.358132 -71.000112)
					(end 130.999992 -70.641972)
				)
				(arc
					(start 129.99974 -70.641972)
					(mid 129.641854 -71.000239)
					(end 129.999994 -71.358252)
				)
			)
		)
		(polygon
			(pts
				(arc
					(start 127 -71.358252)
					(mid 127.35814 -71.000112)
					(end 127 -70.641972)
				)
				(arc
					(start 125.999748 -70.641972)
					(mid 125.641862 -71.000239)
					(end 126.000002 -71.358252)
				)
			)
		)
		(polygon
			(pts
				(arc
					(start 137.922 -69.7992)
					(mid 137.907121 -69.763279)
					(end 137.8712 -69.7484)
				)
				(arc
					(start 137.0584 -69.7484)
					(mid 137.022479 -69.763279)
					(end 137.0076 -69.7992)
				)
				(arc
					(start 137.0076 -70.0024)
					(mid 137.022479 -70.038321)
					(end 137.0584 -70.0532)
				)
				(arc
					(start 137.8712 -70.0532)
					(mid 137.907121 -70.038321)
					(end 137.922 -70.0024)
				)
			)
		)
		(polygon
			(pts
				(arc
					(start 129.999994 -70.358254)
					(mid 130.358134 -70.000114)
					(end 129.999994 -69.641974)
				)
				(arc
					(start 128.999742 -69.641974)
					(mid 128.641856 -70.000241)
					(end 128.999996 -70.358254)
				)
			)
		)
		(polygon
			(pts
				(arc
					(start 127 -70.358254)
					(mid 127.35814 -70.000114)
					(end 127 -69.641974)
				)
				(arc
					(start 125.999748 -69.641974)
					(mid 125.641862 -70.000241)
					(end 126.000002 -70.358254)
				)
			)
		)
		(polygon
			(pts
				(arc
					(start 137.922 -69.2404)
					(mid 137.907121 -69.204479)
					(end 137.8712 -69.1896)
				)
				(arc
					(start 137.0584 -69.1896)
					(mid 137.022479 -69.204479)
					(end 137.0076 -69.2404)
				)
				(arc
					(start 137.0076 -69.4436)
					(mid 137.022479 -69.479521)
					(end 137.0584 -69.4944)
				)
				(arc
					(start 137.8712 -69.4944)
					(mid 137.907121 -69.479521)
					(end 137.922 -69.4436)
				)
			)
		)
		(polygon
			(pts
				(arc
					(start 130.999992 -69.358256)
					(mid 131.358132 -69.000116)
					(end 130.999992 -68.641976)
				)
				(arc
					(start 129.99974 -68.641976)
					(mid 129.641854 -69.000243)
					(end 129.999994 -69.358256)
				)
			)
		)
		(polygon
			(pts
				(arc
					(start 127 -69.358256)
					(mid 127.35814 -69.000116)
					(end 127 -68.641976)
				)
				(arc
					(start 125.999748 -68.641976)
					(mid 125.641862 -69.000243)
					(end 126.000002 -69.358256)
				)
			)
		)
		(polygon
			(pts
				(arc
					(start 137.922 -68.2498)
					(mid 137.907121 -68.213879)
					(end 137.8712 -68.199)
				)
				(arc
					(start 137.0584 -68.199)
					(mid 137.022479 -68.213879)
					(end 137.0076 -68.2498)
				)
				(arc
					(start 137.0076 -68.453)
					(mid 137.022479 -68.488921)
					(end 137.0584 -68.5038)
				)
				(arc
					(start 137.8712 -68.5038)
					(mid 137.907121 -68.488921)
					(end 137.922 -68.453)
				)
			)
		)
		(polygon
			(pts
				(arc
					(start 129.999994 -68.358258)
					(mid 130.358134 -68.000118)
					(end 129.999994 -67.641978)
				)
				(arc
					(start 128.999742 -67.641978)
					(mid 128.641856 -68.000245)
					(end 128.999996 -68.358258)
				)
			)
		)
		(polygon
			(pts
				(arc
					(start 127 -68.358258)
					(mid 127.35814 -68.000118)
					(end 127 -67.641978)
				)
				(arc
					(start 125.999748 -67.641978)
					(mid 125.641862 -68.000245)
					(end 126.000002 -68.358258)
				)
			)
		)
		(polygon
			(pts
				(arc
					(start 137.922 -67.691)
					(mid 137.907121 -67.655079)
					(end 137.8712 -67.6402)
				)
				(arc
					(start 137.0584 -67.6402)
					(mid 137.022479 -67.655079)
					(end 137.0076 -67.691)
				)
				(arc
					(start 137.0076 -67.8942)
					(mid 137.022479 -67.930121)
					(end 137.0584 -67.945)
				)
				(arc
					(start 137.8712 -67.945)
					(mid 137.907121 -67.930121)
					(end 137.922 -67.8942)
				)
			)
		)
		(polygon
			(pts
				(arc
					(start 137.922 -66.7258)
					(mid 137.907121 -66.689879)
					(end 137.8712 -66.675)
				)
				(arc
					(start 137.0584 -66.675)
					(mid 137.022479 -66.689879)
					(end 137.0076 -66.7258)
				)
				(arc
					(start 137.0076 -66.929)
					(mid 137.022479 -66.964921)
					(end 137.0584 -66.9798)
				)
				(arc
					(start 137.8712 -66.9798)
					(mid 137.907121 -66.964921)
					(end 137.922 -66.929)
				)
			)
		)
		(polygon
			(pts
				(arc
					(start 137.922 -66.167)
					(mid 137.907121 -66.131079)
					(end 137.8712 -66.1162)
				)
				(arc
					(start 137.0584 -66.1162)
					(mid 137.022479 -66.131079)
					(end 137.0076 -66.167)
				)
				(arc
					(start 137.0076 -66.3702)
					(mid 137.022479 -66.406121)
					(end 137.0584 -66.421)
				)
				(arc
					(start 137.8712 -66.421)
					(mid 137.907121 -66.406121)
					(end 137.922 -66.3702)
				)
			)
		)
		(polygon
			(pts
				(arc
					(start 130.999992 -66.358262)
					(mid 131.358132 -66.000122)
					(end 130.999992 -65.641982)
				)
				(arc
					(start 129.99974 -65.641982)
					(mid 129.641854 -66.000249)
					(end 129.999994 -66.358262)
				)
			)
		)
		(polygon
			(pts
				(arc
					(start 127 -66.358262)
					(mid 127.35814 -66.000122)
					(end 127 -65.641982)
				)
				(arc
					(start 125.999748 -65.641982)
					(mid 125.641862 -66.000249)
					(end 126.000002 -66.358262)
				)
			)
		)
		(polygon
			(pts
				(arc
					(start 134.950454 -64.964818)
					(mid 134.935575 -64.928897)
					(end 134.899654 -64.914018)
				)
				(arc
					(start 134.086854 -64.914018)
					(mid 134.050933 -64.928897)
					(end 134.036054 -64.964818)
				)
				(arc
					(start 134.036054 -65.168018)
					(mid 134.050933 -65.203939)
					(end 134.086854 -65.218818)
				)
				(arc
					(start 134.899654 -65.218818)
					(mid 134.935575 -65.203939)
					(end 134.950454 -65.168018)
				)
			)
		)
		(polygon
			(pts
				(arc
					(start 129.999994 -65.358264)
					(mid 130.358134 -65.000124)
					(end 129.999994 -64.641984)
				)
				(arc
					(start 128.999742 -64.641984)
					(mid 128.641856 -65.000251)
					(end 128.999996 -65.358264)
				)
			)
		)
		(polygon
			(pts
				(arc
					(start 127 -65.358264)
					(mid 127.35814 -65.000124)
					(end 127 -64.641984)
				)
				(arc
					(start 125.999748 -64.641984)
					(mid 125.641862 -65.000251)
					(end 126.000002 -65.358264)
				)
			)
		)
		(polygon
			(pts
				(arc
					(start 139.882372 -65.426844)
					(mid 140.336778 -64.972057)
					(end 139.882118 -64.517524)
				)
				(arc
					(start 138.739118 -64.517524)
					(mid 138.284458 -64.972184)
					(end 138.739118 -65.426844)
				)
			)
		)
		(polygon
			(pts
				(arc
					(start 134.950454 -64.406018)
					(mid 134.935575 -64.370097)
					(end 134.899654 -64.355218)
				)
				(arc
					(start 134.086854 -64.355218)
					(mid 134.050933 -64.370097)
					(end 134.036054 -64.406018)
				)
				(arc
					(start 134.036054 -64.609218)
					(mid 134.050933 -64.645139)
					(end 134.086854 -64.660018)
				)
				(arc
					(start 134.899654 -64.660018)
					(mid 134.935575 -64.645139)
					(end 134.950454 -64.609218)
				)
			)
		)
		(polygon
			(pts
				(arc
					(start 130.999992 -64.358266)
					(mid 131.358132 -64.000126)
					(end 130.999992 -63.641986)
				)
				(arc
					(start 129.99974 -63.641986)
					(mid 129.641854 -64.000253)
					(end 129.999994 -64.358266)
				)
			)
		)
		(polygon
			(pts
				(arc
					(start 127 -64.358266)
					(mid 127.35814 -64.000126)
					(end 127 -63.641986)
				)
				(arc
					(start 125.999748 -63.641986)
					(mid 125.641862 -64.000253)
					(end 126.000002 -64.358266)
				)
			)
		)
		(polygon
			(pts
				(arc
					(start 129.999994 -63.358268)
					(mid 130.358134 -63.000128)
					(end 129.999994 -62.641988)
				)
				(arc
					(start 128.999742 -62.641988)
					(mid 128.641856 -63.000255)
					(end 128.999996 -63.358268)
				)
			)
		)
		(polygon
			(pts
				(arc
					(start 127 -63.358268)
					(mid 127.35814 -63.000128)
					(end 127 -62.641988)
				)
				(arc
					(start 125.999748 -62.641988)
					(mid 125.641862 -63.000255)
					(end 126.000002 -63.358268)
				)
			)
		)
		(polygon
			(pts
				(arc
					(start 139.947904 -63.499746)
					(mid 140.40231 -63.044959)
					(end 139.94765 -62.590426)
				)
				(arc
					(start 138.80465 -62.590426)
					(mid 138.34999 -63.045086)
					(end 138.80465 -63.499746)
				)
			)
		)
		(polygon
			(pts
				(arc
					(start 130.999992 -62.35827)
					(mid 131.358132 -62.00013)
					(end 130.999992 -61.64199)
				)
				(arc
					(start 129.99974 -61.64199)
					(mid 129.641854 -62.000257)
					(end 129.999994 -62.35827)
				)
			)
		)
		(polygon
			(pts
				(arc
					(start 127 -62.35827)
					(mid 127.35814 -62.00013)
					(end 127 -61.64199)
				)
				(arc
					(start 125.999748 -61.64199)
					(mid 125.641862 -62.000257)
					(end 126.000002 -62.35827)
				)
			)
		)
		(polygon
			(pts
				(arc
					(start 140.173964 -61.576712)
					(mid 140.62837 -61.121925)
					(end 140.17371 -60.667392)
				)
				(arc
					(start 139.03071 -60.667392)
					(mid 138.57605 -61.122052)
					(end 139.03071 -61.576712)
				)
			)
		)
		(polygon
			(pts
				(arc
					(start 129.999994 -61.358272)
					(mid 130.358134 -61.000132)
					(end 129.999994 -60.641992)
				)
				(arc
					(start 128.999742 -60.641992)
					(mid 128.641856 -61.000259)
					(end 128.999996 -61.358272)
				)
			)
		)
		(polygon
			(pts
				(arc
					(start 127 -61.358272)
					(mid 127.35814 -61.000132)
					(end 127 -60.641992)
				)
				(arc
					(start 125.999748 -60.641992)
					(mid 125.641862 -61.000259)
					(end 126.000002 -61.358272)
				)
			)
		)
		(polygon
			(pts
				(arc
					(start 127 -60.358274)
					(mid 127.35814 -60.000134)
					(end 127 -59.641994)
				)
				(arc
					(start 125.999748 -59.641994)
					(mid 125.641862 -60.000261)
					(end 126.000002 -60.358274)
				)
			)
		)
		(polygon
			(pts
				(arc
					(start 127 -59.358276)
					(mid 127.35814 -59.000136)
					(end 127 -58.641996)
				)
				(arc
					(start 125.999748 -58.641996)
					(mid 125.641862 -59.000263)
					(end 126.000002 -59.358276)
				)
			)
		)
		(polygon
			(pts
				(arc
					(start 140.589254 -59.35726)
					(mid 141.04366 -58.902473)
					(end 140.589 -58.44794)
				)
				(arc
					(start 139.446 -58.44794)
					(mid 138.99134 -58.9026)
					(end 139.446 -59.35726)
				)
			)
		)
		(polygon
			(pts
				(arc
					(start 127 -58.358278)
					(mid 127.35814 -58.000138)
					(end 127 -57.641998)
				)
				(arc
					(start 125.999748 -57.641998)
					(mid 125.641862 -58.000265)
					(end 126.000002 -58.358278)
				)
			)
		)
		(polygon
			(pts
				(arc
					(start 127 -57.35828)
					(mid 127.35814 -57.00014)
					(end 127 -56.642)
				)
				(arc
					(start 125.999748 -56.642)
					(mid 125.641862 -57.000267)
					(end 126.000002 -57.35828)
				)
			)
		)
		(polygon
			(pts
				(arc
					(start 135.558022 -55.973218)
					(mid 135.543143 -55.937297)
					(end 135.507222 -55.922418)
				)
				(arc
					(start 135.304022 -55.922418)
					(mid 135.268101 -55.937297)
					(end 135.253222 -55.973218)
				)
				(arc
					(start 135.253222 -56.786018)
					(mid 135.268101 -56.821939)
					(end 135.304022 -56.836818)
				)
				(arc
					(start 135.507222 -56.836818)
					(mid 135.543143 -56.821939)
					(end 135.558022 -56.786018)
				)
			)
		)
		(polygon
			(pts
				(arc
					(start 134.999222 -55.973218)
					(mid 134.984343 -55.937297)
					(end 134.948422 -55.922418)
				)
				(arc
					(start 134.745222 -55.922418)
					(mid 134.709301 -55.937297)
					(end 134.694422 -55.973218)
				)
				(arc
					(start 134.694422 -56.786018)
					(mid 134.709301 -56.821939)
					(end 134.745222 -56.836818)
				)
				(arc
					(start 134.948422 -56.836818)
					(mid 134.984343 -56.821939)
					(end 134.999222 -56.786018)
				)
			)
		)
		(polygon
			(pts
				(arc
					(start 127 -56.358282)
					(mid 127.35814 -56.000142)
					(end 127 -55.642002)
				)
				(arc
					(start 125.999748 -55.642002)
					(mid 125.641862 -56.000269)
					(end 126.000002 -56.358282)
				)
			)
		)
		(polygon
			(pts
				(arc
					(start 96.954594 -55.039768)
					(mid 96.939715 -55.003847)
					(end 96.903794 -54.988968)
				)
				(arc
					(start 96.090994 -54.988968)
					(mid 96.055073 -55.003847)
					(end 96.040194 -55.039768)
				)
				(arc
					(start 96.040194 -55.242968)
					(mid 96.055073 -55.278889)
					(end 96.090994 -55.293768)
				)
				(arc
					(start 96.903794 -55.293768)
					(mid 96.939715 -55.278889)
					(end 96.954594 -55.242968)
				)
			)
		)
		(polygon
			(pts
				(arc
					(start 127 -55.358284)
					(mid 127.35814 -55.000144)
					(end 127 -54.642004)
				)
				(arc
					(start 125.999748 -54.642004)
					(mid 125.641862 -55.000271)
					(end 126.000002 -55.358284)
				)
			)
		)
		(polygon
			(pts
				(arc
					(start 124.358146 -55.000144)
					(mid 124.000006 -54.642004)
					(end 123.641866 -55.000144)
				)
				(arc
					(start 123.641866 -56.000396)
					(mid 124.000133 -56.358282)
					(end 124.358146 -56.000142)
				)
			)
		)
		(polygon
			(pts
				(arc
					(start 123.358148 -55.000144)
					(mid 123.000008 -54.642004)
					(end 122.641868 -55.000144)
				)
				(arc
					(start 122.641868 -56.000396)
					(mid 123.000135 -56.358282)
					(end 123.358148 -56.000142)
				)
			)
		)
		(polygon
			(pts
				(arc
					(start 122.35815 -55.000144)
					(mid 122.00001 -54.642004)
					(end 121.64187 -55.000144)
				)
				(arc
					(start 121.64187 -56.000396)
					(mid 122.000137 -56.358282)
					(end 122.35815 -56.000142)
				)
			)
		)
		(polygon
			(pts
				(arc
					(start 121.358152 -55.000144)
					(mid 121.000012 -54.642004)
					(end 120.641872 -55.000144)
				)
				(arc
					(start 120.641872 -56.000396)
					(mid 121.000139 -56.358282)
					(end 121.358152 -56.000142)
				)
			)
		)
		(polygon
			(pts
				(arc
					(start 120.358154 -55.000144)
					(mid 120.000014 -54.642004)
					(end 119.641874 -55.000144)
				)
				(arc
					(start 119.641874 -56.000396)
					(mid 120.000141 -56.358282)
					(end 120.358154 -56.000142)
				)
			)
		)
		(polygon
			(pts
				(arc
					(start 119.358156 -55.000144)
					(mid 119.000016 -54.642004)
					(end 118.641876 -55.000144)
				)
				(arc
					(start 118.641876 -56.000396)
					(mid 119.000143 -56.358282)
					(end 119.358156 -56.000142)
				)
			)
		)
		(polygon
			(pts
				(arc
					(start 118.358158 -55.000144)
					(mid 118.000018 -54.642004)
					(end 117.641878 -55.000144)
				)
				(arc
					(start 117.641878 -56.000396)
					(mid 118.000145 -56.358282)
					(end 118.358158 -56.000142)
				)
			)
		)
		(polygon
			(pts
				(arc
					(start 117.35816 -55.000144)
					(mid 117.00002 -54.642004)
					(end 116.64188 -55.000144)
				)
				(arc
					(start 116.64188 -56.000396)
					(mid 117.000147 -56.358282)
					(end 117.35816 -56.000142)
				)
			)
		)
		(polygon
			(pts
				(arc
					(start 116.358162 -55.000144)
					(mid 116.000022 -54.642004)
					(end 115.641882 -55.000144)
				)
				(arc
					(start 115.641882 -56.000396)
					(mid 116.000149 -56.358282)
					(end 116.358162 -56.000142)
				)
			)
		)
		(polygon
			(pts
				(arc
					(start 114.358166 -55.000144)
					(mid 114.000026 -54.642004)
					(end 113.641886 -55.000144)
				)
				(arc
					(start 113.641886 -56.000396)
					(mid 114.000153 -56.358282)
					(end 114.358166 -56.000142)
				)
			)
		)
		(polygon
			(pts
				(arc
					(start 113.358168 -55.000144)
					(mid 113.000028 -54.642004)
					(end 112.641888 -55.000144)
				)
				(arc
					(start 112.641888 -56.000396)
					(mid 113.000155 -56.358282)
					(end 113.358168 -56.000142)
				)
			)
		)
		(polygon
			(pts
				(arc
					(start 112.35817 -55.000144)
					(mid 112.00003 -54.642004)
					(end 111.64189 -55.000144)
				)
				(arc
					(start 111.64189 -56.000396)
					(mid 112.000157 -56.358282)
					(end 112.35817 -56.000142)
				)
			)
		)
		(polygon
			(pts
				(arc
					(start 111.358172 -55.000144)
					(mid 111.000032 -54.642004)
					(end 110.641892 -55.000144)
				)
				(arc
					(start 110.641892 -56.000396)
					(mid 111.000159 -56.358282)
					(end 111.358172 -56.000142)
				)
			)
		)
		(polygon
			(pts
				(arc
					(start 110.358174 -55.000144)
					(mid 110.000034 -54.642004)
					(end 109.641894 -55.000144)
				)
				(arc
					(start 109.641894 -56.000396)
					(mid 110.000161 -56.358282)
					(end 110.358174 -56.000142)
				)
			)
		)
		(polygon
			(pts
				(arc
					(start 109.358176 -55.000144)
					(mid 109.000036 -54.642004)
					(end 108.641896 -55.000144)
				)
				(arc
					(start 108.641896 -56.000396)
					(mid 109.000163 -56.358282)
					(end 109.358176 -56.000142)
				)
			)
		)
		(polygon
			(pts
				(arc
					(start 108.358178 -55.000144)
					(mid 108.000038 -54.642004)
					(end 107.641898 -55.000144)
				)
				(arc
					(start 107.641898 -56.000396)
					(mid 108.000165 -56.358282)
					(end 108.358178 -56.000142)
				)
			)
		)
		(polygon
			(pts
				(arc
					(start 107.35818 -55.000144)
					(mid 107.00004 -54.642004)
					(end 106.6419 -55.000144)
				)
				(arc
					(start 106.6419 -56.000396)
					(mid 107.000167 -56.358282)
					(end 107.35818 -56.000142)
				)
			)
		)
		(polygon
			(pts
				(arc
					(start 106.358182 -55.000144)
					(mid 106.000042 -54.642004)
					(end 105.641902 -55.000144)
				)
				(arc
					(start 105.641902 -56.000396)
					(mid 106.000169 -56.358282)
					(end 106.358182 -56.000142)
				)
			)
		)
		(polygon
			(pts
				(arc
					(start 105.358184 -55.000144)
					(mid 105.000044 -54.642004)
					(end 104.641904 -55.000144)
				)
				(arc
					(start 104.641904 -56.000396)
					(mid 105.000171 -56.358282)
					(end 105.358184 -56.000142)
				)
			)
		)
		(polygon
			(pts
				(arc
					(start 104.358186 -55.000144)
					(mid 104.000046 -54.642004)
					(end 103.641906 -55.000144)
				)
				(arc
					(start 103.641906 -56.000396)
					(mid 104.000173 -56.358282)
					(end 104.358186 -56.000142)
				)
			)
		)
		(polygon
			(pts
				(arc
					(start 103.358188 -55.000144)
					(mid 103.000048 -54.642004)
					(end 102.641908 -55.000144)
				)
				(arc
					(start 102.641908 -56.000396)
					(mid 103.000175 -56.358282)
					(end 103.358188 -56.000142)
				)
			)
		)
		(polygon
			(pts
				(arc
					(start 102.35819 -55.000144)
					(mid 102.00005 -54.642004)
					(end 101.64191 -55.000144)
				)
				(arc
					(start 101.64191 -56.000396)
					(mid 102.000177 -56.358282)
					(end 102.35819 -56.000142)
				)
			)
		)
		(polygon
			(pts
				(arc
					(start 101.358192 -55.000144)
					(mid 101.000052 -54.642004)
					(end 100.641912 -55.000144)
				)
				(arc
					(start 100.641912 -56.000396)
					(mid 101.000179 -56.358282)
					(end 101.358192 -56.000142)
				)
			)
		)
		(polygon
			(pts
				(arc
					(start 96.954594 -54.455568)
					(mid 96.939715 -54.419647)
					(end 96.903794 -54.404768)
				)
				(arc
					(start 96.090994 -54.404768)
					(mid 96.055073 -54.419647)
					(end 96.040194 -54.455568)
				)
				(arc
					(start 96.040194 -54.658768)
					(mid 96.055073 -54.694689)
					(end 96.090994 -54.709568)
				)
				(arc
					(start 96.903794 -54.709568)
					(mid 96.939715 -54.694689)
					(end 96.954594 -54.658768)
				)
			)
		)
		(polygon
			(pts
				(arc
					(start 150.087584 -54.478174)
					(mid 149.735286 -53.935884)
					(end 149.192996 -54.288182)
				)
				(arc
					(start 148.957792 -55.395876)
					(mid 149.302356 -55.947245)
					(end 149.84984 -55.596282)
				)
			)
		)
		(polygon
			(pts
				(arc
					(start 127 -54.358286)
					(mid 127.35814 -54.000146)
					(end 127 -53.642006)
				)
				(arc
					(start 125.999748 -53.642006)
					(mid 125.641862 -54.000273)
					(end 126.000002 -54.358286)
				)
			)
		)
		(polygon
			(pts
				(arc
					(start 99.358196 -54.000146)
					(mid 99.000056 -53.642006)
					(end 98.641916 -54.000146)
				)
				(arc
					(start 98.641916 -55.000398)
					(mid 99.000183 -55.358284)
					(end 99.358196 -55.000144)
				)
			)
		)
		(polygon
			(pts
				(arc
					(start 96.954594 -53.642768)
					(mid 96.939715 -53.606847)
					(end 96.903794 -53.591968)
				)
				(arc
					(start 96.090994 -53.591968)
					(mid 96.055073 -53.606847)
					(end 96.040194 -53.642768)
				)
				(arc
					(start 96.040194 -53.845968)
					(mid 96.055073 -53.881889)
					(end 96.090994 -53.896768)
				)
				(arc
					(start 96.903794 -53.896768)
					(mid 96.939715 -53.881889)
					(end 96.954594 -53.845968)
				)
			)
		)
		(polygon
			(pts
				(arc
					(start 96.954594 -53.058568)
					(mid 96.939715 -53.022647)
					(end 96.903794 -53.007768)
				)
				(arc
					(start 96.090994 -53.007768)
					(mid 96.055073 -53.022647)
					(end 96.040194 -53.058568)
				)
				(arc
					(start 96.040194 -53.261768)
					(mid 96.055073 -53.297689)
					(end 96.090994 -53.312568)
				)
				(arc
					(start 96.903794 -53.312568)
					(mid 96.939715 -53.297689)
					(end 96.954594 -53.261768)
				)
			)
		)
		(polygon
			(pts
				(arc
					(start 127.999998 -53.358288)
					(mid 128.358138 -53.000148)
					(end 127.999998 -52.642008)
				)
				(arc
					(start 126.999746 -52.642008)
					(mid 126.64186 -53.000275)
					(end 127 -53.358288)
				)
			)
		)
		(polygon
			(pts
				(arc
					(start 96.954594 -52.245768)
					(mid 96.939715 -52.209847)
					(end 96.903794 -52.194968)
				)
				(arc
					(start 96.090994 -52.194968)
					(mid 96.055073 -52.209847)
					(end 96.040194 -52.245768)
				)
				(arc
					(start 96.040194 -52.448968)
					(mid 96.055073 -52.484889)
					(end 96.090994 -52.499768)
				)
				(arc
					(start 96.903794 -52.499768)
					(mid 96.939715 -52.484889)
					(end 96.954594 -52.448968)
				)
			)
		)
		(polygon
			(pts
				(arc
					(start 124.358146 -52.00015)
					(mid 124.000006 -51.64201)
					(end 123.641866 -52.00015)
				)
				(arc
					(start 123.641866 -53.000402)
					(mid 124.000133 -53.358288)
					(end 124.358146 -53.000148)
				)
			)
		)
		(polygon
			(pts
				(arc
					(start 122.35815 -52.00015)
					(mid 122.00001 -51.64201)
					(end 121.64187 -52.00015)
				)
				(arc
					(start 121.64187 -53.000402)
					(mid 122.000137 -53.358288)
					(end 122.35815 -53.000148)
				)
			)
		)
		(polygon
			(pts
				(arc
					(start 120.358154 -52.00015)
					(mid 120.000014 -51.64201)
					(end 119.641874 -52.00015)
				)
				(arc
					(start 119.641874 -53.000402)
					(mid 120.000141 -53.358288)
					(end 120.358154 -53.000148)
				)
			)
		)
		(polygon
			(pts
				(arc
					(start 118.358158 -52.00015)
					(mid 118.000018 -51.64201)
					(end 117.641878 -52.00015)
				)
				(arc
					(start 117.641878 -53.000402)
					(mid 118.000145 -53.358288)
					(end 118.358158 -53.000148)
				)
			)
		)
		(polygon
			(pts
				(arc
					(start 116.358162 -52.00015)
					(mid 116.000022 -51.64201)
					(end 115.641882 -52.00015)
				)
				(arc
					(start 115.641882 -53.000402)
					(mid 116.000149 -53.358288)
					(end 116.358162 -53.000148)
				)
			)
		)
		(polygon
			(pts
				(arc
					(start 113.358168 -52.00015)
					(mid 113.000028 -51.64201)
					(end 112.641888 -52.00015)
				)
				(arc
					(start 112.641888 -53.000402)
					(mid 113.000155 -53.358288)
					(end 113.358168 -53.000148)
				)
			)
		)
		(polygon
			(pts
				(arc
					(start 111.358172 -52.00015)
					(mid 111.000032 -51.64201)
					(end 110.641892 -52.00015)
				)
				(arc
					(start 110.641892 -53.000402)
					(mid 111.000159 -53.358288)
					(end 111.358172 -53.000148)
				)
			)
		)
		(polygon
			(pts
				(arc
					(start 109.358176 -52.00015)
					(mid 109.000036 -51.64201)
					(end 108.641896 -52.00015)
				)
				(arc
					(start 108.641896 -53.000402)
					(mid 109.000163 -53.358288)
					(end 109.358176 -53.000148)
				)
			)
		)
		(polygon
			(pts
				(arc
					(start 107.35818 -52.00015)
					(mid 107.00004 -51.64201)
					(end 106.6419 -52.00015)
				)
				(arc
					(start 106.6419 -53.000402)
					(mid 107.000167 -53.358288)
					(end 107.35818 -53.000148)
				)
			)
		)
		(polygon
			(pts
				(arc
					(start 105.358184 -52.00015)
					(mid 105.000044 -51.64201)
					(end 104.641904 -52.00015)
				)
				(arc
					(start 104.641904 -53.000402)
					(mid 105.000171 -53.358288)
					(end 105.358184 -53.000148)
				)
			)
		)
		(polygon
			(pts
				(arc
					(start 103.358188 -52.00015)
					(mid 103.000048 -51.64201)
					(end 102.641908 -52.00015)
				)
				(arc
					(start 102.641908 -53.000402)
					(mid 103.000175 -53.358288)
					(end 103.358188 -53.000148)
				)
			)
		)
		(polygon
			(pts
				(arc
					(start 101.358192 -52.00015)
					(mid 101.000052 -51.64201)
					(end 100.641912 -52.00015)
				)
				(arc
					(start 100.641912 -53.000402)
					(mid 101.000179 -53.358288)
					(end 101.358192 -53.000148)
				)
			)
		)
		(polygon
			(pts
				(arc
					(start 96.954594 -51.661568)
					(mid 96.939715 -51.625647)
					(end 96.903794 -51.610768)
				)
				(arc
					(start 96.090994 -51.610768)
					(mid 96.055073 -51.625647)
					(end 96.040194 -51.661568)
				)
				(arc
					(start 96.040194 -51.864768)
					(mid 96.055073 -51.900689)
					(end 96.090994 -51.915568)
				)
				(arc
					(start 96.903794 -51.915568)
					(mid 96.939715 -51.900689)
					(end 96.954594 -51.864768)
				)
			)
		)
		(polygon
			(pts
				(arc
					(start 96.954594 -50.848768)
					(mid 96.939715 -50.812847)
					(end 96.903794 -50.797968)
				)
				(arc
					(start 96.090994 -50.797968)
					(mid 96.055073 -50.812847)
					(end 96.040194 -50.848768)
				)
				(arc
					(start 96.040194 -51.051968)
					(mid 96.055073 -51.087889)
					(end 96.090994 -51.102768)
				)
				(arc
					(start 96.903794 -51.102768)
					(mid 96.939715 -51.087889)
					(end 96.954594 -51.051968)
				)
			)
		)
		(polygon
			(pts
				(arc
					(start 123.358148 -51.000152)
					(mid 123.000008 -50.642012)
					(end 122.641868 -51.000152)
				)
				(arc
					(start 122.641868 -52.000404)
					(mid 123.000135 -52.35829)
					(end 123.358148 -52.00015)
				)
			)
		)
		(polygon
			(pts
				(arc
					(start 121.358152 -51.000152)
					(mid 121.000012 -50.642012)
					(end 120.641872 -51.000152)
				)
				(arc
					(start 120.641872 -52.000404)
					(mid 121.000139 -52.35829)
					(end 121.358152 -52.00015)
				)
			)
		)
		(polygon
			(pts
				(arc
					(start 119.358156 -51.000152)
					(mid 119.000016 -50.642012)
					(end 118.641876 -51.000152)
				)
				(arc
					(start 118.641876 -52.000404)
					(mid 119.000143 -52.35829)
					(end 119.358156 -52.00015)
				)
			)
		)
		(polygon
			(pts
				(arc
					(start 117.35816 -51.000152)
					(mid 117.00002 -50.642012)
					(end 116.64188 -51.000152)
				)
				(arc
					(start 116.64188 -52.000404)
					(mid 117.000147 -52.35829)
					(end 117.35816 -52.00015)
				)
			)
		)
		(polygon
			(pts
				(arc
					(start 114.358166 -51.000152)
					(mid 114.000026 -50.642012)
					(end 113.641886 -51.000152)
				)
				(arc
					(start 113.641886 -52.000404)
					(mid 114.000153 -52.35829)
					(end 114.358166 -52.00015)
				)
			)
		)
		(polygon
			(pts
				(arc
					(start 112.35817 -51.000152)
					(mid 112.00003 -50.642012)
					(end 111.64189 -51.000152)
				)
				(arc
					(start 111.64189 -52.000404)
					(mid 112.000157 -52.35829)
					(end 112.35817 -52.00015)
				)
			)
		)
		(polygon
			(pts
				(arc
					(start 110.358174 -51.000152)
					(mid 110.000034 -50.642012)
					(end 109.641894 -51.000152)
				)
				(arc
					(start 109.641894 -52.000404)
					(mid 110.000161 -52.35829)
					(end 110.358174 -52.00015)
				)
			)
		)
		(polygon
			(pts
				(arc
					(start 108.358178 -51.000152)
					(mid 108.000038 -50.642012)
					(end 107.641898 -51.000152)
				)
				(arc
					(start 107.641898 -52.000404)
					(mid 108.000165 -52.35829)
					(end 108.358178 -52.00015)
				)
			)
		)
		(polygon
			(pts
				(arc
					(start 106.358182 -51.000152)
					(mid 106.000042 -50.642012)
					(end 105.641902 -51.000152)
				)
				(arc
					(start 105.641902 -52.000404)
					(mid 106.000169 -52.35829)
					(end 106.358182 -52.00015)
				)
			)
		)
		(polygon
			(pts
				(arc
					(start 104.358186 -51.000152)
					(mid 104.000046 -50.642012)
					(end 103.641906 -51.000152)
				)
				(arc
					(start 103.641906 -52.000404)
					(mid 104.000173 -52.35829)
					(end 104.358186 -52.00015)
				)
			)
		)
		(polygon
			(pts
				(arc
					(start 102.35819 -51.000152)
					(mid 102.00005 -50.642012)
					(end 101.64191 -51.000152)
				)
				(arc
					(start 101.64191 -52.000404)
					(mid 102.000177 -52.35829)
					(end 102.35819 -52.00015)
				)
			)
		)
		(polygon
			(pts
				(arc
					(start 100.358194 -51.000152)
					(mid 100.000054 -50.642012)
					(end 99.641914 -51.000152)
				)
				(arc
					(start 99.641914 -52.000404)
					(mid 100.000181 -52.35829)
					(end 100.358194 -52.00015)
				)
			)
		)
		(polygon
			(pts
				(arc
					(start 96.954594 -50.264568)
					(mid 96.939715 -50.228647)
					(end 96.903794 -50.213768)
				)
				(arc
					(start 96.090994 -50.213768)
					(mid 96.055073 -50.228647)
					(end 96.040194 -50.264568)
				)
				(arc
					(start 96.040194 -50.467768)
					(mid 96.055073 -50.503689)
					(end 96.090994 -50.518568)
				)
				(arc
					(start 96.903794 -50.518568)
					(mid 96.939715 -50.503689)
					(end 96.954594 -50.467768)
				)
			)
		)
		(polygon
			(pts
				(arc
					(start 149.037294 -50.520092)
					(mid 148.69273 -49.968723)
					(end 148.145246 -50.319686)
				)
				(arc
					(start 147.907502 -51.437794)
					(mid 148.2598 -51.980084)
					(end 148.80209 -51.627786)
				)
			)
		)
		(polygon
			(pts
				(arc
					(start 147.989544 -46.551596)
					(mid 147.64498 -46.000227)
					(end 147.097496 -46.35119)
				)
				(arc
					(start 146.859752 -47.469298)
					(mid 147.21205 -48.011588)
					(end 147.75434 -47.65929)
				)
			)
		)
		(polygon
			(pts
				(arc
					(start 125.139958 -45.858938)
					(mid 124.682758 -45.401738)
					(end 124.225558 -45.858938)
				)
				(arc
					(start 124.225558 -47.002192)
					(mid 124.682885 -47.459138)
					(end 125.139958 -47.001938)
				)
			)
		)
		(polygon
			(pts
				(arc
					(start 127.533908 -45.844206)
					(mid 127.076708 -45.387006)
					(end 126.619508 -45.844206)
				)
				(arc
					(start 126.619508 -46.98746)
					(mid 127.076835 -47.444406)
					(end 127.533908 -46.987206)
				)
			)
		)
		(polygon
			(pts
				(arc
					(start 130.105658 -45.829474)
					(mid 129.648458 -45.372274)
					(end 129.191258 -45.829474)
				)
				(arc
					(start 129.191258 -46.972728)
					(mid 129.648585 -47.429674)
					(end 130.105658 -46.972474)
				)
			)
		)
		(polygon
			(pts
				(arc
					(start 132.677408 -45.814742)
					(mid 132.220208 -45.357542)
					(end 131.763008 -45.814742)
				)
				(arc
					(start 131.763008 -46.957996)
					(mid 132.220335 -47.414942)
					(end 132.677408 -46.957742)
				)
			)
		)
		(polygon
			(pts
				(arc
					(start 133.985 -43.9928)
					(mid 133.970121 -43.956879)
					(end 133.9342 -43.942)
				)
				(arc
					(start 133.731 -43.942)
					(mid 133.695079 -43.956879)
					(end 133.6802 -43.9928)
				)
				(arc
					(start 133.6802 -44.8056)
					(mid 133.695079 -44.841521)
					(end 133.731 -44.8564)
				)
				(arc
					(start 133.9342 -44.8564)
					(mid 133.970121 -44.841521)
					(end 133.985 -44.8056)
				)
			)
		)
		(polygon
			(pts
				(arc
					(start 133.4262 -43.9928)
					(mid 133.411321 -43.956879)
					(end 133.3754 -43.942)
				)
				(arc
					(start 133.1722 -43.942)
					(mid 133.136279 -43.956879)
					(end 133.1214 -43.9928)
				)
				(arc
					(start 133.1214 -44.8056)
					(mid 133.136279 -44.841521)
					(end 133.1722 -44.8564)
				)
				(arc
					(start 133.3754 -44.8564)
					(mid 133.411321 -44.841521)
					(end 133.4262 -44.8056)
				)
			)
		)
		(polygon
			(pts
				(arc
					(start 131.53517 -43.972988)
					(mid 131.520291 -43.937067)
					(end 131.48437 -43.922188)
				)
				(arc
					(start 131.28117 -43.922188)
					(mid 131.245249 -43.937067)
					(end 131.23037 -43.972988)
				)
				(arc
					(start 131.23037 -44.785788)
					(mid 131.245249 -44.821709)
					(end 131.28117 -44.836588)
				)
				(arc
					(start 131.48437 -44.836588)
					(mid 131.520291 -44.821709)
					(end 131.53517 -44.785788)
				)
			)
		)
		(polygon
			(pts
				(arc
					(start 130.97637 -43.972988)
					(mid 130.961491 -43.937067)
					(end 130.92557 -43.922188)
				)
				(arc
					(start 130.72237 -43.922188)
					(mid 130.686449 -43.937067)
					(end 130.67157 -43.972988)
				)
				(arc
					(start 130.67157 -44.785788)
					(mid 130.686449 -44.821709)
					(end 130.72237 -44.836588)
				)
				(arc
					(start 130.92557 -44.836588)
					(mid 130.961491 -44.821709)
					(end 130.97637 -44.785788)
				)
			)
		)
		(polygon
			(pts
				(arc
					(start 120.2182 -43.815)
					(mid 120.203321 -43.779079)
					(end 120.1674 -43.7642)
				)
				(arc
					(start 119.9642 -43.7642)
					(mid 119.928279 -43.779079)
					(end 119.9134 -43.815)
				)
				(arc
					(start 119.9134 -44.6278)
					(mid 119.928279 -44.663721)
					(end 119.9642 -44.6786)
				)
				(arc
					(start 120.1674 -44.6786)
					(mid 120.203321 -44.663721)
					(end 120.2182 -44.6278)
				)
			)
		)
		(polygon
			(pts
				(arc
					(start 119.6594 -43.815)
					(mid 119.644521 -43.779079)
					(end 119.6086 -43.7642)
				)
				(arc
					(start 119.4054 -43.7642)
					(mid 119.369479 -43.779079)
					(end 119.3546 -43.815)
				)
				(arc
					(start 119.3546 -44.6278)
					(mid 119.369479 -44.663721)
					(end 119.4054 -44.6786)
				)
				(arc
					(start 119.6086 -44.6786)
					(mid 119.644521 -44.663721)
					(end 119.6594 -44.6278)
				)
			)
		)
		(polygon
			(pts
				(arc
					(start 118.6942 -43.815)
					(mid 118.679321 -43.779079)
					(end 118.6434 -43.7642)
				)
				(arc
					(start 118.4402 -43.7642)
					(mid 118.404279 -43.779079)
					(end 118.3894 -43.815)
				)
				(arc
					(start 118.3894 -44.6278)
					(mid 118.404279 -44.663721)
					(end 118.4402 -44.6786)
				)
				(arc
					(start 118.6434 -44.6786)
					(mid 118.679321 -44.663721)
					(end 118.6942 -44.6278)
				)
			)
		)
		(polygon
			(pts
				(arc
					(start 118.1354 -43.815)
					(mid 118.120521 -43.779079)
					(end 118.0846 -43.7642)
				)
				(arc
					(start 117.8814 -43.7642)
					(mid 117.845479 -43.779079)
					(end 117.8306 -43.815)
				)
				(arc
					(start 117.8306 -44.6278)
					(mid 117.845479 -44.663721)
					(end 117.8814 -44.6786)
				)
				(arc
					(start 118.0846 -44.6786)
					(mid 118.120521 -44.663721)
					(end 118.1354 -44.6278)
				)
			)
		)
		(polygon
			(pts
				(arc
					(start 117.1702 -43.815)
					(mid 117.155321 -43.779079)
					(end 117.1194 -43.7642)
				)
				(arc
					(start 116.9162 -43.7642)
					(mid 116.880279 -43.779079)
					(end 116.8654 -43.815)
				)
				(arc
					(start 116.8654 -44.6278)
					(mid 116.880279 -44.663721)
					(end 116.9162 -44.6786)
				)
				(arc
					(start 117.1194 -44.6786)
					(mid 117.155321 -44.663721)
					(end 117.1702 -44.6278)
				)
			)
		)
		(polygon
			(pts
				(arc
					(start 116.6114 -43.815)
					(mid 116.596521 -43.779079)
					(end 116.5606 -43.7642)
				)
				(arc
					(start 116.3574 -43.7642)
					(mid 116.321479 -43.779079)
					(end 116.3066 -43.815)
				)
				(arc
					(start 116.3066 -44.6278)
					(mid 116.321479 -44.663721)
					(end 116.3574 -44.6786)
				)
				(arc
					(start 116.5606 -44.6786)
					(mid 116.596521 -44.663721)
					(end 116.6114 -44.6278)
				)
			)
		)
		(polygon
			(pts
				(arc
					(start 115.6462 -43.815)
					(mid 115.631321 -43.779079)
					(end 115.5954 -43.7642)
				)
				(arc
					(start 115.3922 -43.7642)
					(mid 115.356279 -43.779079)
					(end 115.3414 -43.815)
				)
				(arc
					(start 115.3414 -44.6278)
					(mid 115.356279 -44.663721)
					(end 115.3922 -44.6786)
				)
				(arc
					(start 115.5954 -44.6786)
					(mid 115.631321 -44.663721)
					(end 115.6462 -44.6278)
				)
			)
		)
		(polygon
			(pts
				(arc
					(start 115.0874 -43.815)
					(mid 115.072521 -43.779079)
					(end 115.0366 -43.7642)
				)
				(arc
					(start 114.8334 -43.7642)
					(mid 114.797479 -43.779079)
					(end 114.7826 -43.815)
				)
				(arc
					(start 114.7826 -44.6278)
					(mid 114.797479 -44.663721)
					(end 114.8334 -44.6786)
				)
				(arc
					(start 115.0366 -44.6786)
					(mid 115.072521 -44.663721)
					(end 115.0874 -44.6278)
				)
			)
		)
		(polygon
			(pts
				(arc
					(start 114.1222 -43.815)
					(mid 114.107321 -43.779079)
					(end 114.0714 -43.7642)
				)
				(arc
					(start 113.8682 -43.7642)
					(mid 113.832279 -43.779079)
					(end 113.8174 -43.815)
				)
				(arc
					(start 113.8174 -44.6278)
					(mid 113.832279 -44.663721)
					(end 113.8682 -44.6786)
				)
				(arc
					(start 114.0714 -44.6786)
					(mid 114.107321 -44.663721)
					(end 114.1222 -44.6278)
				)
			)
		)
		(polygon
			(pts
				(arc
					(start 113.5634 -43.815)
					(mid 113.548521 -43.779079)
					(end 113.5126 -43.7642)
				)
				(arc
					(start 113.3094 -43.7642)
					(mid 113.273479 -43.779079)
					(end 113.2586 -43.815)
				)
				(arc
					(start 113.2586 -44.6278)
					(mid 113.273479 -44.663721)
					(end 113.3094 -44.6786)
				)
				(arc
					(start 113.5126 -44.6786)
					(mid 113.548521 -44.663721)
					(end 113.5634 -44.6278)
				)
			)
		)
		(polygon
			(pts
				(arc
					(start 112.5982 -43.815)
					(mid 112.583321 -43.779079)
					(end 112.5474 -43.7642)
				)
				(arc
					(start 112.3442 -43.7642)
					(mid 112.308279 -43.779079)
					(end 112.2934 -43.815)
				)
				(arc
					(start 112.2934 -44.6278)
					(mid 112.308279 -44.663721)
					(end 112.3442 -44.6786)
				)
				(arc
					(start 112.5474 -44.6786)
					(mid 112.583321 -44.663721)
					(end 112.5982 -44.6278)
				)
			)
		)
		(polygon
			(pts
				(arc
					(start 112.0394 -43.815)
					(mid 112.024521 -43.779079)
					(end 111.9886 -43.7642)
				)
				(arc
					(start 111.7854 -43.7642)
					(mid 111.749479 -43.779079)
					(end 111.7346 -43.815)
				)
				(arc
					(start 111.7346 -44.6278)
					(mid 111.749479 -44.663721)
					(end 111.7854 -44.6786)
				)
				(arc
					(start 111.9886 -44.6786)
					(mid 112.024521 -44.663721)
					(end 112.0394 -44.6278)
				)
			)
		)
		(polygon
			(pts
				(arc
					(start 111.0742 -43.815)
					(mid 111.059321 -43.779079)
					(end 111.0234 -43.7642)
				)
				(arc
					(start 110.8202 -43.7642)
					(mid 110.784279 -43.779079)
					(end 110.7694 -43.815)
				)
				(arc
					(start 110.7694 -44.6278)
					(mid 110.784279 -44.663721)
					(end 110.8202 -44.6786)
				)
				(arc
					(start 111.0234 -44.6786)
					(mid 111.059321 -44.663721)
					(end 111.0742 -44.6278)
				)
			)
		)
		(polygon
			(pts
				(arc
					(start 110.5154 -43.815)
					(mid 110.500521 -43.779079)
					(end 110.4646 -43.7642)
				)
				(arc
					(start 110.2614 -43.7642)
					(mid 110.225479 -43.779079)
					(end 110.2106 -43.815)
				)
				(arc
					(start 110.2106 -44.6278)
					(mid 110.225479 -44.663721)
					(end 110.2614 -44.6786)
				)
				(arc
					(start 110.4646 -44.6786)
					(mid 110.500521 -44.663721)
					(end 110.5154 -44.6278)
				)
			)
		)
		(polygon
			(pts
				(arc
					(start 109.5502 -43.815)
					(mid 109.535321 -43.779079)
					(end 109.4994 -43.7642)
				)
				(arc
					(start 109.2962 -43.7642)
					(mid 109.260279 -43.779079)
					(end 109.2454 -43.815)
				)
				(arc
					(start 109.2454 -44.6278)
					(mid 109.260279 -44.663721)
					(end 109.2962 -44.6786)
				)
				(arc
					(start 109.4994 -44.6786)
					(mid 109.535321 -44.663721)
					(end 109.5502 -44.6278)
				)
			)
		)
		(polygon
			(pts
				(arc
					(start 108.9914 -43.815)
					(mid 108.976521 -43.779079)
					(end 108.9406 -43.7642)
				)
				(arc
					(start 108.7374 -43.7642)
					(mid 108.701479 -43.779079)
					(end 108.6866 -43.815)
				)
				(arc
					(start 108.6866 -44.6278)
					(mid 108.701479 -44.663721)
					(end 108.7374 -44.6786)
				)
				(arc
					(start 108.9406 -44.6786)
					(mid 108.976521 -44.663721)
					(end 108.9914 -44.6278)
				)
			)
		)
		(polygon
			(pts
				(arc
					(start 108.0262 -43.815)
					(mid 108.011321 -43.779079)
					(end 107.9754 -43.7642)
				)
				(arc
					(start 107.7722 -43.7642)
					(mid 107.736279 -43.779079)
					(end 107.7214 -43.815)
				)
				(arc
					(start 107.7214 -44.6278)
					(mid 107.736279 -44.663721)
					(end 107.7722 -44.6786)
				)
				(arc
					(start 107.9754 -44.6786)
					(mid 108.011321 -44.663721)
					(end 108.0262 -44.6278)
				)
			)
		)
		(polygon
			(pts
				(arc
					(start 107.4674 -43.815)
					(mid 107.452521 -43.779079)
					(end 107.4166 -43.7642)
				)
				(arc
					(start 107.2134 -43.7642)
					(mid 107.177479 -43.779079)
					(end 107.1626 -43.815)
				)
				(arc
					(start 107.1626 -44.6278)
					(mid 107.177479 -44.663721)
					(end 107.2134 -44.6786)
				)
				(arc
					(start 107.4166 -44.6786)
					(mid 107.452521 -44.663721)
					(end 107.4674 -44.6278)
				)
			)
		)
		(polygon
			(pts
				(arc
					(start 106.5022 -43.815)
					(mid 106.487321 -43.779079)
					(end 106.4514 -43.7642)
				)
				(arc
					(start 106.2482 -43.7642)
					(mid 106.212279 -43.779079)
					(end 106.1974 -43.815)
				)
				(arc
					(start 106.1974 -44.6278)
					(mid 106.212279 -44.663721)
					(end 106.2482 -44.6786)
				)
				(arc
					(start 106.4514 -44.6786)
					(mid 106.487321 -44.663721)
					(end 106.5022 -44.6278)
				)
			)
		)
		(polygon
			(pts
				(arc
					(start 105.9434 -43.815)
					(mid 105.928521 -43.779079)
					(end 105.8926 -43.7642)
				)
				(arc
					(start 105.6894 -43.7642)
					(mid 105.653479 -43.779079)
					(end 105.6386 -43.815)
				)
				(arc
					(start 105.6386 -44.6278)
					(mid 105.653479 -44.663721)
					(end 105.6894 -44.6786)
				)
				(arc
					(start 105.8926 -44.6786)
					(mid 105.928521 -44.663721)
					(end 105.9434 -44.6278)
				)
			)
		)
		(polygon
			(pts
				(arc
					(start 104.9782 -43.815)
					(mid 104.963321 -43.779079)
					(end 104.9274 -43.7642)
				)
				(arc
					(start 104.7242 -43.7642)
					(mid 104.688279 -43.779079)
					(end 104.6734 -43.815)
				)
				(arc
					(start 104.6734 -44.6278)
					(mid 104.688279 -44.663721)
					(end 104.7242 -44.6786)
				)
				(arc
					(start 104.9274 -44.6786)
					(mid 104.963321 -44.663721)
					(end 104.9782 -44.6278)
				)
			)
		)
		(polygon
			(pts
				(arc
					(start 104.4194 -43.815)
					(mid 104.404521 -43.779079)
					(end 104.3686 -43.7642)
				)
				(arc
					(start 104.1654 -43.7642)
					(mid 104.129479 -43.779079)
					(end 104.1146 -43.815)
				)
				(arc
					(start 104.1146 -44.6278)
					(mid 104.129479 -44.663721)
					(end 104.1654 -44.6786)
				)
				(arc
					(start 104.3686 -44.6786)
					(mid 104.404521 -44.663721)
					(end 104.4194 -44.6278)
				)
			)
		)
		(polygon
			(pts
				(arc
					(start 103.4542 -43.815)
					(mid 103.439321 -43.779079)
					(end 103.4034 -43.7642)
				)
				(arc
					(start 103.2002 -43.7642)
					(mid 103.164279 -43.779079)
					(end 103.1494 -43.815)
				)
				(arc
					(start 103.1494 -44.6278)
					(mid 103.164279 -44.663721)
					(end 103.2002 -44.6786)
				)
				(arc
					(start 103.4034 -44.6786)
					(mid 103.439321 -44.663721)
					(end 103.4542 -44.6278)
				)
			)
		)
		(polygon
			(pts
				(arc
					(start 102.8954 -43.815)
					(mid 102.880521 -43.779079)
					(end 102.8446 -43.7642)
				)
				(arc
					(start 102.6414 -43.7642)
					(mid 102.605479 -43.779079)
					(end 102.5906 -43.815)
				)
				(arc
					(start 102.5906 -44.6278)
					(mid 102.605479 -44.663721)
					(end 102.6414 -44.6786)
				)
				(arc
					(start 102.8446 -44.6786)
					(mid 102.880521 -44.663721)
					(end 102.8954 -44.6278)
				)
			)
		)
		(polygon
			(pts
				(arc
					(start 101.9302 -43.815)
					(mid 101.915321 -43.779079)
					(end 101.8794 -43.7642)
				)
				(arc
					(start 101.6762 -43.7642)
					(mid 101.640279 -43.779079)
					(end 101.6254 -43.815)
				)
				(arc
					(start 101.6254 -44.6278)
					(mid 101.640279 -44.663721)
					(end 101.6762 -44.6786)
				)
				(arc
					(start 101.8794 -44.6786)
					(mid 101.915321 -44.663721)
					(end 101.9302 -44.6278)
				)
			)
		)
		(polygon
			(pts
				(arc
					(start 101.3714 -43.815)
					(mid 101.356521 -43.779079)
					(end 101.3206 -43.7642)
				)
				(arc
					(start 101.1174 -43.7642)
					(mid 101.081479 -43.779079)
					(end 101.0666 -43.815)
				)
				(arc
					(start 101.0666 -44.6278)
					(mid 101.081479 -44.663721)
					(end 101.1174 -44.6786)
				)
				(arc
					(start 101.3206 -44.6786)
					(mid 101.356521 -44.663721)
					(end 101.3714 -44.6278)
				)
			)
		)
		(polygon
			(pts
				(arc
					(start 100.4062 -43.815)
					(mid 100.391321 -43.779079)
					(end 100.3554 -43.7642)
				)
				(arc
					(start 100.1522 -43.7642)
					(mid 100.116279 -43.779079)
					(end 100.1014 -43.815)
				)
				(arc
					(start 100.1014 -44.6278)
					(mid 100.116279 -44.663721)
					(end 100.1522 -44.6786)
				)
				(arc
					(start 100.3554 -44.6786)
					(mid 100.391321 -44.663721)
					(end 100.4062 -44.6278)
				)
			)
		)
		(polygon
			(pts
				(arc
					(start 99.8474 -43.815)
					(mid 99.832521 -43.779079)
					(end 99.7966 -43.7642)
				)
				(arc
					(start 99.5934 -43.7642)
					(mid 99.557479 -43.779079)
					(end 99.5426 -43.815)
				)
				(arc
					(start 99.5426 -44.6278)
					(mid 99.557479 -44.663721)
					(end 99.5934 -44.6786)
				)
				(arc
					(start 99.7966 -44.6786)
					(mid 99.832521 -44.663721)
					(end 99.8474 -44.6278)
				)
			)
		)
		(polygon
			(pts
				(arc
					(start 98.8822 -43.815)
					(mid 98.867321 -43.779079)
					(end 98.8314 -43.7642)
				)
				(arc
					(start 98.6282 -43.7642)
					(mid 98.592279 -43.779079)
					(end 98.5774 -43.815)
				)
				(arc
					(start 98.5774 -44.6278)
					(mid 98.592279 -44.663721)
					(end 98.6282 -44.6786)
				)
				(arc
					(start 98.8314 -44.6786)
					(mid 98.867321 -44.663721)
					(end 98.8822 -44.6278)
				)
			)
		)
		(polygon
			(pts
				(arc
					(start 98.3234 -43.815)
					(mid 98.308521 -43.779079)
					(end 98.2726 -43.7642)
				)
				(arc
					(start 98.0694 -43.7642)
					(mid 98.033479 -43.779079)
					(end 98.0186 -43.815)
				)
				(arc
					(start 98.0186 -44.6278)
					(mid 98.033479 -44.663721)
					(end 98.0694 -44.6786)
				)
				(arc
					(start 98.2726 -44.6786)
					(mid 98.308521 -44.663721)
					(end 98.3234 -44.6278)
				)
			)
		)
		(polygon
			(pts
				(arc
					(start 97.3582 -43.815)
					(mid 97.343321 -43.779079)
					(end 97.3074 -43.7642)
				)
				(arc
					(start 97.1042 -43.7642)
					(mid 97.068279 -43.779079)
					(end 97.0534 -43.815)
				)
				(arc
					(start 97.0534 -44.6278)
					(mid 97.068279 -44.663721)
					(end 97.1042 -44.6786)
				)
				(arc
					(start 97.3074 -44.6786)
					(mid 97.343321 -44.663721)
					(end 97.3582 -44.6278)
				)
			)
		)
		(polygon
			(pts
				(arc
					(start 96.7994 -43.815)
					(mid 96.784521 -43.779079)
					(end 96.7486 -43.7642)
				)
				(arc
					(start 96.5454 -43.7642)
					(mid 96.509479 -43.779079)
					(end 96.4946 -43.815)
				)
				(arc
					(start 96.4946 -44.6278)
					(mid 96.509479 -44.663721)
					(end 96.5454 -44.6786)
				)
				(arc
					(start 96.7486 -44.6786)
					(mid 96.784521 -44.663721)
					(end 96.7994 -44.6278)
				)
			)
		)
		(polygon
			(pts
				(arc
					(start 150.230078 -44.309284)
					(mid 149.885514 -43.757915)
					(end 149.33803 -44.108878)
				)
				(arc
					(start 149.100286 -45.226986)
					(mid 149.452584 -45.769276)
					(end 149.994874 -45.416978)
				)
			)
		)
		(polygon
			(pts
				(arc
					(start 128.9558 -40.4622)
					(mid 128.940921 -40.426279)
					(end 128.905 -40.4114)
				)
				(arc
					(start 128.7018 -40.4114)
					(mid 128.665879 -40.426279)
					(end 128.651 -40.4622)
				)
				(arc
					(start 128.651 -41.275)
					(mid 128.665879 -41.310921)
					(end 128.7018 -41.3258)
				)
				(arc
					(start 128.905 -41.3258)
					(mid 128.940921 -41.310921)
					(end 128.9558 -41.275)
				)
			)
		)
		(polygon
			(pts
				(arc
					(start 128.3716 -40.4622)
					(mid 128.356721 -40.426279)
					(end 128.3208 -40.4114)
				)
				(arc
					(start 128.1176 -40.4114)
					(mid 128.081679 -40.426279)
					(end 128.0668 -40.4622)
				)
				(arc
					(start 128.0668 -41.275)
					(mid 128.081679 -41.310921)
					(end 128.1176 -41.3258)
				)
				(arc
					(start 128.3208 -41.3258)
					(mid 128.356721 -41.310921)
					(end 128.3716 -41.275)
				)
			)
		)
		(polygon
			(pts
				(arc
					(start 149.309328 -40.340788)
					(mid 148.964764 -39.789419)
					(end 148.41728 -40.140382)
				)
				(arc
					(start 148.179536 -41.25849)
					(mid 148.531834 -41.80078)
					(end 149.074124 -41.448482)
				)
			)
		)
		(polygon
			(pts
				(arc
					(start 127.6096 -39.0652)
					(mid 127.594721 -39.029279)
					(end 127.5588 -39.0144)
				)
				(arc
					(start 127.3556 -39.0144)
					(mid 127.319679 -39.029279)
					(end 127.3048 -39.0652)
				)
				(arc
					(start 127.3048 -39.878)
					(mid 127.319679 -39.913921)
					(end 127.3556 -39.9288)
				)
				(arc
					(start 127.5588 -39.9288)
					(mid 127.594721 -39.913921)
					(end 127.6096 -39.878)
				)
			)
		)
		(polygon
			(pts
				(arc
					(start 127.0254 -39.0652)
					(mid 127.010521 -39.029279)
					(end 126.9746 -39.0144)
				)
				(arc
					(start 126.7714 -39.0144)
					(mid 126.735479 -39.029279)
					(end 126.7206 -39.0652)
				)
				(arc
					(start 126.7206 -39.878)
					(mid 126.735479 -39.913921)
					(end 126.7714 -39.9288)
				)
				(arc
					(start 126.9746 -39.9288)
					(mid 127.010521 -39.913921)
					(end 127.0254 -39.878)
				)
			)
		)
		(polygon
			(pts
				(arc
					(start 125.73 -39.0652)
					(mid 125.715121 -39.029279)
					(end 125.6792 -39.0144)
				)
				(arc
					(start 125.476 -39.0144)
					(mid 125.440079 -39.029279)
					(end 125.4252 -39.0652)
				)
				(arc
					(start 125.4252 -39.878)
					(mid 125.440079 -39.913921)
					(end 125.476 -39.9288)
				)
				(arc
					(start 125.6792 -39.9288)
					(mid 125.715121 -39.913921)
					(end 125.73 -39.878)
				)
			)
		)
		(polygon
			(pts
				(arc
					(start 125.1458 -39.0652)
					(mid 125.130921 -39.029279)
					(end 125.095 -39.0144)
				)
				(arc
					(start 124.8918 -39.0144)
					(mid 124.855879 -39.029279)
					(end 124.841 -39.0652)
				)
				(arc
					(start 124.841 -39.878)
					(mid 124.855879 -39.913921)
					(end 124.8918 -39.9288)
				)
				(arc
					(start 125.095 -39.9288)
					(mid 125.130921 -39.913921)
					(end 125.1458 -39.878)
				)
			)
		)
		(polygon
			(pts
				(arc
					(start 123.952 -39.0652)
					(mid 123.937121 -39.029279)
					(end 123.9012 -39.0144)
				)
				(arc
					(start 123.698 -39.0144)
					(mid 123.662079 -39.029279)
					(end 123.6472 -39.0652)
				)
				(arc
					(start 123.6472 -39.878)
					(mid 123.662079 -39.913921)
					(end 123.698 -39.9288)
				)
				(arc
					(start 123.9012 -39.9288)
					(mid 123.937121 -39.913921)
					(end 123.952 -39.878)
				)
			)
		)
		(polygon
			(pts
				(arc
					(start 123.3678 -39.0652)
					(mid 123.352921 -39.029279)
					(end 123.317 -39.0144)
				)
				(arc
					(start 123.1138 -39.0144)
					(mid 123.077879 -39.029279)
					(end 123.063 -39.0652)
				)
				(arc
					(start 123.063 -39.878)
					(mid 123.077879 -39.913921)
					(end 123.1138 -39.9288)
				)
				(arc
					(start 123.317 -39.9288)
					(mid 123.352921 -39.913921)
					(end 123.3678 -39.878)
				)
			)
		)
		(polygon
			(pts
				(arc
					(start 122.174 -39.0652)
					(mid 122.159121 -39.029279)
					(end 122.1232 -39.0144)
				)
				(arc
					(start 121.92 -39.0144)
					(mid 121.884079 -39.029279)
					(end 121.8692 -39.0652)
				)
				(arc
					(start 121.8692 -39.878)
					(mid 121.884079 -39.913921)
					(end 121.92 -39.9288)
				)
				(arc
					(start 122.1232 -39.9288)
					(mid 122.159121 -39.913921)
					(end 122.174 -39.878)
				)
			)
		)
		(polygon
			(pts
				(arc
					(start 121.5898 -39.0652)
					(mid 121.574921 -39.029279)
					(end 121.539 -39.0144)
				)
				(arc
					(start 121.3358 -39.0144)
					(mid 121.299879 -39.029279)
					(end 121.285 -39.0652)
				)
				(arc
					(start 121.285 -39.878)
					(mid 121.299879 -39.913921)
					(end 121.3358 -39.9288)
				)
				(arc
					(start 121.539 -39.9288)
					(mid 121.574921 -39.913921)
					(end 121.5898 -39.878)
				)
			)
		)
		(polygon
			(pts
				(arc
					(start 151.676862 -38.098476)
					(mid 151.332298 -37.547107)
					(end 150.784814 -37.89807)
				)
				(arc
					(start 150.54707 -39.016178)
					(mid 150.899368 -39.558468)
					(end 151.441658 -39.20617)
				)
			)
		)
		(polygon
			(pts
				(arc
					(start 166.58336 -37.59962)
					(mid 166.199693 -37.216334)
					(end 165.81628 -37.599874)
				)
				(arc
					(start 165.81628 -38.399974)
					(mid 166.19982 -38.783514)
					(end 166.58336 -38.399974)
				)
			)
		)
		(polygon
			(pts
				(arc
					(start 166.200074 -37.183568)
					(mid 166.58336 -36.799901)
					(end 166.19982 -36.416488)
				)
				(arc
					(start 165.399974 -36.416488)
					(mid 165.016434 -36.800028)
					(end 165.399974 -37.183568)
				)
			)
		)
		(polygon
			(pts
				(arc
					(start 166.58336 -35.199574)
					(mid 166.199693 -34.816288)
					(end 165.81628 -35.199828)
				)
				(arc
					(start 165.81628 -35.999928)
					(mid 166.19982 -36.383468)
					(end 166.58336 -35.999928)
				)
			)
		)
		(polygon
			(pts
				(arc
					(start 149.814534 -35.21329)
					(mid 149.46997 -34.661921)
					(end 148.922486 -35.012884)
				)
				(arc
					(start 148.684742 -36.130992)
					(mid 149.03704 -36.673282)
					(end 149.57933 -36.320984)
				)
			)
		)
		(polygon
			(pts
				(arc
					(start 166.200074 -34.783522)
					(mid 166.58336 -34.399855)
					(end 166.19982 -34.016442)
				)
				(arc
					(start 165.399974 -34.016442)
					(mid 165.016434 -34.399982)
					(end 165.399974 -34.783522)
				)
			)
		)
		(polygon
			(pts
				(arc
					(start 166.58336 -32.799782)
					(mid 166.199693 -32.416496)
					(end 165.81628 -32.800036)
				)
				(arc
					(start 165.81628 -33.599882)
					(mid 166.19982 -33.983422)
					(end 166.58336 -33.599882)
				)
			)
		)
		(polygon
			(pts
				(arc
					(start 146.969226 -32.460184)
					(mid 146.624662 -31.908815)
					(end 146.077178 -32.259778)
				)
				(arc
					(start 145.839434 -33.377886)
					(mid 146.191732 -33.920176)
					(end 146.734022 -33.567878)
				)
			)
		)
		(polygon
			(pts
				(arc
					(start 167.000174 -32.383476)
					(mid 167.38346 -31.999809)
					(end 166.99992 -31.616396)
				)
				(arc
					(start 166.200074 -31.616396)
					(mid 165.816534 -31.999936)
					(end 166.200074 -32.383476)
				)
			)
		)
		(polygon
			(pts
				(arc
					(start 176.158144 -30.400244)
					(mid 175.800004 -30.042104)
					(end 175.441864 -30.400244)
				)
				(arc
					(start 175.441864 -31.200344)
					(mid 175.800131 -31.55823)
					(end 176.158144 -31.20009)
				)
			)
		)
		(polygon
			(pts
				(arc
					(start 168.958006 -30.39999)
					(mid 168.599866 -30.04185)
					(end 168.241726 -30.39999)
				)
				(arc
					(start 168.241726 -31.20009)
					(mid 168.599993 -31.557976)
					(end 168.958006 -31.199836)
				)
			)
		)
		(polygon
			(pts
				(arc
					(start 175.358044 -30.39999)
					(mid 174.999777 -30.04185)
					(end 174.641764 -30.400244)
				)
				(arc
					(start 174.642018 -31.199836)
					(mid 175.000158 -31.55823)
					(end 175.358298 -31.199836)
				)
				(xy 175.358044 -30.400244)
			)
		)
		(polygon
			(pts
				(arc
					(start 173.758098 -30.39999)
					(mid 173.399831 -30.04185)
					(end 173.041818 -30.400244)
				)
				(arc
					(start 173.042072 -31.199836)
					(mid 173.400212 -31.55823)
					(end 173.758352 -31.199836)
				)
				(xy 173.758098 -30.400244)
			)
		)
		(polygon
			(pts
				(arc
					(start 172.957998 -30.39999)
					(mid 172.599731 -30.04185)
					(end 172.241718 -30.400244)
				)
				(arc
					(start 172.241972 -31.199836)
					(mid 172.600112 -31.55823)
					(end 172.958252 -31.199836)
				)
				(xy 172.957998 -30.400244)
			)
		)
		(polygon
			(pts
				(arc
					(start 171.358052 -30.39999)
					(mid 170.999785 -30.04185)
					(end 170.641772 -30.400244)
				)
				(arc
					(start 170.642026 -31.199836)
					(mid 171.000166 -31.55823)
					(end 171.358306 -31.199836)
				)
				(xy 171.358052 -30.400244)
			)
		)
		(polygon
			(pts
				(arc
					(start 170.557952 -30.39999)
					(mid 170.199685 -30.04185)
					(end 169.841672 -30.400244)
				)
				(arc
					(start 169.841926 -31.199836)
					(mid 170.200066 -31.55823)
					(end 170.558206 -31.199836)
				)
				(xy 170.557952 -30.400244)
			)
		)
		(polygon
			(pts
				(arc
					(start 168.157906 -30.39999)
					(mid 167.799639 -30.04185)
					(end 167.441626 -30.400244)
				)
				(arc
					(start 167.44188 -31.199582)
					(mid 167.80002 -31.557976)
					(end 168.15816 -31.199582)
				)
				(xy 168.157906 -30.400244)
			)
		)
		(polygon
			(pts
				(arc
					(start 166.58336 -30.399736)
					(mid 166.199693 -30.01645)
					(end 165.81628 -30.39999)
				)
				(arc
					(start 165.81628 -31.199836)
					(mid 166.19982 -31.583376)
					(end 166.58336 -31.199836)
				)
			)
		)
		(polygon
			(pts
				(arc
					(start 166.200074 -29.21635)
					(mid 165.81628 -29.599763)
					(end 166.19982 -29.98343)
				)
				(arc
					(start 166.999412 -29.983684)
					(mid 167.383206 -29.600271)
					(end 166.999666 -29.216604)
				)
			)
		)
		(polygon
			(pts
				(arc
					(start 180.819552 -23.596346)
					(mid 180.436012 -23.212806)
					(end 180.052472 -23.596346)
				)
				(arc
					(start 180.052472 -24.4856)
					(mid 180.436139 -24.868886)
					(end 180.819552 -24.485346)
				)
			)
		)
		(polygon
			(pts
				(arc
					(start 166.508938 -23.166832)
					(mid 166.125398 -22.783292)
					(end 165.741858 -23.166832)
				)
				(arc
					(start 165.741858 -24.056086)
					(mid 166.125525 -24.439372)
					(end 166.508938 -24.055832)
				)
			)
		)
		(polygon
			(pts
				(arc
					(start 168.543478 -23.123906)
					(mid 168.159938 -22.740366)
					(end 167.776398 -23.123906)
				)
				(arc
					(start 167.776398 -24.01316)
					(mid 168.160065 -24.396446)
					(end 168.543478 -24.012906)
				)
			)
		)
		(polygon
			(pts
				(arc
					(start 178.790854 -23.11654)
					(mid 178.407314 -22.733)
					(end 178.023774 -23.11654)
				)
				(arc
					(start 178.023774 -24.005794)
					(mid 178.407441 -24.38908)
					(end 178.790854 -24.00554)
				)
			)
		)
		(polygon
			(pts
				(arc
					(start 170.600624 -23.11527)
					(mid 170.217084 -22.73173)
					(end 169.833544 -23.11527)
				)
				(arc
					(start 169.833544 -24.004524)
					(mid 170.217211 -24.38781)
					(end 170.600624 -24.00427)
				)
			)
		)
		(polygon
			(pts
				(arc
					(start 172.65269 -23.112984)
					(mid 172.26915 -22.729444)
					(end 171.88561 -23.112984)
				)
				(arc
					(start 171.88561 -24.002238)
					(mid 172.269277 -24.385524)
					(end 172.65269 -24.001984)
				)
			)
		)
		(polygon
			(pts
				(arc
					(start 174.698406 -23.112476)
					(mid 174.314866 -22.728936)
					(end 173.931326 -23.112476)
				)
				(arc
					(start 173.931326 -24.00173)
					(mid 174.314993 -24.385016)
					(end 174.698406 -24.001476)
				)
			)
		)
		(polygon
			(pts
				(arc
					(start 176.75225 -23.103332)
					(mid 176.36871 -22.719792)
					(end 175.98517 -23.103332)
				)
				(arc
					(start 175.98517 -23.992586)
					(mid 176.368837 -24.375872)
					(end 176.75225 -23.992332)
				)
			)
		)
		(polygon
			(pts
				(arc
					(start 181.726586 -21.740368)
					(mid 181.711707 -21.704447)
					(end 181.675786 -21.689568)
				)
				(arc
					(start 180.862986 -21.689568)
					(mid 180.827065 -21.704447)
					(end 180.812186 -21.740368)
				)
				(arc
					(start 180.812186 -21.943568)
					(mid 180.827065 -21.979489)
					(end 180.862986 -21.994368)
				)
				(arc
					(start 181.675786 -21.994368)
					(mid 181.711707 -21.979489)
					(end 181.726586 -21.943568)
				)
			)
		)
		(polygon
			(pts
				(arc
					(start 181.72684 -21.17344)
					(mid 181.711961 -21.137519)
					(end 181.67604 -21.12264)
				)
				(arc
					(start 180.86324 -21.12264)
					(mid 180.827319 -21.137519)
					(end 180.81244 -21.17344)
				)
				(arc
					(start 180.81244 -21.37664)
					(mid 180.827319 -21.412561)
					(end 180.86324 -21.42744)
				)
				(arc
					(start 181.67604 -21.42744)
					(mid 181.711961 -21.412561)
					(end 181.72684 -21.37664)
				)
			)
		)
		(polygon
			(pts
				(arc
					(start 178.877976 -21.04898)
					(mid 178.863097 -21.013059)
					(end 178.827176 -20.99818)
				)
				(arc
					(start 178.014376 -20.99818)
					(mid 177.978455 -21.013059)
					(end 177.963576 -21.04898)
				)
				(arc
					(start 177.963576 -21.25218)
					(mid 177.978455 -21.288101)
					(end 178.014376 -21.30298)
				)
				(arc
					(start 178.827176 -21.30298)
					(mid 178.863097 -21.288101)
					(end 178.877976 -21.25218)
				)
			)
		)
		(polygon
			(pts
				(arc
					(start 169.13479 -20.600416)
					(mid 169.119911 -20.564495)
					(end 169.08399 -20.549616)
				)
				(arc
					(start 168.88079 -20.549616)
					(mid 168.844869 -20.564495)
					(end 168.82999 -20.600416)
				)
				(arc
					(start 168.82999 -21.413216)
					(mid 168.844869 -21.449137)
					(end 168.88079 -21.464016)
				)
				(arc
					(start 169.08399 -21.464016)
					(mid 169.119911 -21.449137)
					(end 169.13479 -21.413216)
				)
			)
		)
		(polygon
			(pts
				(arc
					(start 169.7101 -20.597876)
					(mid 169.695221 -20.561955)
					(end 169.6593 -20.547076)
				)
				(arc
					(start 169.4561 -20.547076)
					(mid 169.420179 -20.561955)
					(end 169.4053 -20.597876)
				)
				(arc
					(start 169.4053 -21.410676)
					(mid 169.420179 -21.446597)
					(end 169.4561 -21.461476)
				)
				(arc
					(start 169.6593 -21.461476)
					(mid 169.695221 -21.446597)
					(end 169.7101 -21.410676)
				)
			)
		)
		(polygon
			(pts
				(arc
					(start 175.763428 -20.548346)
					(mid 175.748549 -20.512425)
					(end 175.712628 -20.497546)
				)
				(arc
					(start 175.509428 -20.497546)
					(mid 175.473507 -20.512425)
					(end 175.458628 -20.548346)
				)
				(arc
					(start 175.458628 -21.361146)
					(mid 175.473507 -21.397067)
					(end 175.509428 -21.411946)
				)
				(arc
					(start 175.712628 -21.411946)
					(mid 175.748549 -21.397067)
					(end 175.763428 -21.361146)
				)
			)
		)
		(polygon
			(pts
				(arc
					(start 175.196246 -20.548092)
					(mid 175.181367 -20.512171)
					(end 175.145446 -20.497292)
				)
				(arc
					(start 174.942246 -20.497292)
					(mid 174.906325 -20.512171)
					(end 174.891446 -20.548092)
				)
				(arc
					(start 174.891446 -21.360892)
					(mid 174.906325 -21.396813)
					(end 174.942246 -21.411692)
				)
				(arc
					(start 175.145446 -21.411692)
					(mid 175.181367 -21.396813)
					(end 175.196246 -21.360892)
				)
			)
		)
		(polygon
			(pts
				(arc
					(start 173.777402 -20.48002)
					(mid 173.762523 -20.444099)
					(end 173.726602 -20.42922)
				)
				(arc
					(start 173.523402 -20.42922)
					(mid 173.487481 -20.444099)
					(end 173.472602 -20.48002)
				)
				(arc
					(start 173.472602 -21.29282)
					(mid 173.487481 -21.328741)
					(end 173.523402 -21.34362)
				)
				(arc
					(start 173.726602 -21.34362)
					(mid 173.762523 -21.328741)
					(end 173.777402 -21.29282)
				)
			)
		)
		(polygon
			(pts
				(arc
					(start 171.685204 -20.48002)
					(mid 171.670325 -20.444099)
					(end 171.634404 -20.42922)
				)
				(arc
					(start 171.431204 -20.42922)
					(mid 171.395283 -20.444099)
					(end 171.380404 -20.48002)
				)
				(arc
					(start 171.380404 -21.29282)
					(mid 171.395283 -21.328741)
					(end 171.431204 -21.34362)
				)
				(arc
					(start 171.634404 -21.34362)
					(mid 171.670325 -21.328741)
					(end 171.685204 -21.29282)
				)
			)
		)
		(polygon
			(pts
				(arc
					(start 171.075604 -20.48002)
					(mid 171.060725 -20.444099)
					(end 171.024804 -20.42922)
				)
				(arc
					(start 170.821604 -20.42922)
					(mid 170.785683 -20.444099)
					(end 170.770804 -20.48002)
				)
				(arc
					(start 170.770804 -21.29282)
					(mid 170.785683 -21.328741)
					(end 170.821604 -21.34362)
				)
				(arc
					(start 171.024804 -21.34362)
					(mid 171.060725 -21.328741)
					(end 171.075604 -21.29282)
				)
			)
		)
		(polygon
			(pts
				(arc
					(start 173.198282 -20.479766)
					(mid 173.183403 -20.443845)
					(end 173.147482 -20.428966)
				)
				(arc
					(start 172.944282 -20.428966)
					(mid 172.908361 -20.443845)
					(end 172.893482 -20.479766)
				)
				(arc
					(start 172.893482 -21.292566)
					(mid 172.908361 -21.328487)
					(end 172.944282 -21.343366)
				)
				(arc
					(start 173.147482 -21.343366)
					(mid 173.183403 -21.328487)
					(end 173.198282 -21.292566)
				)
			)
		)
		(polygon
			(pts
				(arc
					(start 178.877214 -20.478242)
					(mid 178.862335 -20.442321)
					(end 178.826414 -20.427442)
				)
				(arc
					(start 178.013614 -20.427442)
					(mid 177.977693 -20.442321)
					(end 177.962814 -20.478242)
				)
				(arc
					(start 177.962814 -20.681442)
					(mid 177.977693 -20.717363)
					(end 178.013614 -20.732242)
				)
				(arc
					(start 178.826414 -20.732242)
					(mid 178.862335 -20.717363)
					(end 178.877214 -20.681442)
				)
			)
		)
		(polygon
			(pts
				(arc
					(start 165.711378 -20.176744)
					(mid 165.696499 -20.140823)
					(end 165.660578 -20.125944)
				)
				(arc
					(start 165.457378 -20.125944)
					(mid 165.421457 -20.140823)
					(end 165.406578 -20.176744)
				)
				(arc
					(start 165.406578 -20.989544)
					(mid 165.421457 -21.025465)
					(end 165.457378 -21.040344)
				)
				(arc
					(start 165.660578 -21.040344)
					(mid 165.696499 -21.025465)
					(end 165.711378 -20.989544)
				)
			)
		)
		(polygon
			(pts
				(arc
					(start 165.076378 -20.176744)
					(mid 165.061499 -20.140823)
					(end 165.025578 -20.125944)
				)
				(arc
					(start 164.822378 -20.125944)
					(mid 164.786457 -20.140823)
					(end 164.771578 -20.176744)
				)
				(arc
					(start 164.771578 -20.989544)
					(mid 164.786457 -21.025465)
					(end 164.822378 -21.040344)
				)
				(arc
					(start 165.025578 -21.040344)
					(mid 165.061499 -21.025465)
					(end 165.076378 -20.989544)
				)
			)
		)
		(polygon
			(pts
				(arc
					(start 167.43172 -20.166584)
					(mid 167.416841 -20.130663)
					(end 167.38092 -20.115784)
				)
				(arc
					(start 167.17772 -20.115784)
					(mid 167.141799 -20.130663)
					(end 167.12692 -20.166584)
				)
				(arc
					(start 167.12692 -20.979384)
					(mid 167.141799 -21.015305)
					(end 167.17772 -21.030184)
				)
				(arc
					(start 167.38092 -21.030184)
					(mid 167.416841 -21.015305)
					(end 167.43172 -20.979384)
				)
			)
		)
		(polygon
			(pts
				(arc
					(start 166.79672 -20.166584)
					(mid 166.781841 -20.130663)
					(end 166.74592 -20.115784)
				)
				(arc
					(start 166.54272 -20.115784)
					(mid 166.506799 -20.130663)
					(end 166.49192 -20.166584)
				)
				(arc
					(start 166.49192 -20.979384)
					(mid 166.506799 -21.015305)
					(end 166.54272 -21.030184)
				)
				(arc
					(start 166.74592 -21.030184)
					(mid 166.781841 -21.015305)
					(end 166.79672 -20.979384)
				)
			)
		)
		(polygon
			(pts
				(arc
					(start 191.361314 -10.999978)
					(mid 190.799974 -10.438638)
					(end 190.238634 -10.999978)
				)
				(arc
					(start 190.238634 -12.40028)
					(mid 190.800101 -12.961366)
					(end 191.361314 -12.400026)
				)
			)
		)
		(polygon
			(pts
				(arc
					(start 187.761118 -10.999978)
					(mid 187.199778 -10.438638)
					(end 186.638438 -10.999978)
				)
				(arc
					(start 186.638438 -12.40028)
					(mid 187.199905 -12.961366)
					(end 187.761118 -12.400026)
				)
			)
		)
		(polygon
			(pts
				(arc
					(start 184.161176 -10.999978)
					(mid 183.599836 -10.438638)
					(end 183.038496 -10.999978)
				)
				(arc
					(start 183.038496 -12.40028)
					(mid 183.599963 -12.961366)
					(end 184.161176 -12.400026)
				)
			)
		)
		(polygon
			(pts
				(arc
					(start 180.561234 -10.999978)
					(mid 179.999894 -10.438638)
					(end 179.438554 -10.999978)
				)
				(arc
					(start 179.438554 -12.40028)
					(mid 180.000021 -12.961366)
					(end 180.561234 -12.400026)
				)
			)
		)
		(polygon
			(pts
				(arc
					(start 147.761452 -10.999978)
					(mid 147.200112 -10.438638)
					(end 146.638772 -10.999978)
				)
				(arc
					(start 146.638772 -12.40028)
					(mid 147.200239 -12.961366)
					(end 147.761452 -12.400026)
				)
			)
		)
		(polygon
			(pts
				(arc
					(start 144.16151 -10.999978)
					(mid 143.60017 -10.438638)
					(end 143.03883 -10.999978)
				)
				(arc
					(start 143.03883 -12.40028)
					(mid 143.600297 -12.961366)
					(end 144.16151 -12.400026)
				)
			)
		)
		(polygon
			(pts
				(arc
					(start 140.561314 -10.999978)
					(mid 139.999974 -10.438638)
					(end 139.438634 -10.999978)
				)
				(arc
					(start 139.438634 -12.40028)
					(mid 140.000101 -12.961366)
					(end 140.561314 -12.400026)
				)
			)
		)
		(polygon
			(pts
				(arc
					(start 136.961372 -10.999978)
					(mid 136.400032 -10.438638)
					(end 135.838692 -10.999978)
				)
				(arc
					(start 135.838692 -12.40028)
					(mid 136.400159 -12.961366)
					(end 136.961372 -12.400026)
				)
			)
		)
		(polygon
			(pts
				(arc
					(start 133.36143 -10.999978)
					(mid 132.80009 -10.438638)
					(end 132.23875 -10.999978)
				)
				(arc
					(start 132.23875 -12.40028)
					(mid 132.800217 -12.961366)
					(end 133.36143 -12.400026)
				)
			)
		)
		(polygon
			(pts
				(arc
					(start 129.761488 -10.999978)
					(mid 129.200148 -10.438638)
					(end 128.638808 -10.999978)
				)
				(arc
					(start 128.638808 -12.40028)
					(mid 129.200275 -12.961366)
					(end 129.761488 -12.400026)
				)
			)
		)
		(polygon
			(pts
				(arc
					(start 126.161546 -10.999978)
					(mid 125.600206 -10.438638)
					(end 125.038866 -10.999978)
				)
				(arc
					(start 125.038866 -12.40028)
					(mid 125.600333 -12.961366)
					(end 126.161546 -12.400026)
				)
			)
		)
		(polygon
			(pts
				(arc
					(start 122.56135 -10.999978)
					(mid 122.00001 -10.438638)
					(end 121.43867 -10.999978)
				)
				(arc
					(start 121.43867 -12.40028)
					(mid 122.000137 -12.961366)
					(end 122.56135 -12.400026)
				)
			)
		)
		(polygon
			(pts
				(arc
					(start 118.961408 -10.999978)
					(mid 118.400068 -10.438638)
					(end 117.838728 -10.999978)
				)
				(arc
					(start 117.838728 -12.40028)
					(mid 118.400195 -12.961366)
					(end 118.961408 -12.400026)
				)
			)
		)
		(polygon
			(pts
				(arc
					(start 115.361466 -10.999978)
					(mid 114.800126 -10.438638)
					(end 114.238786 -10.999978)
				)
				(arc
					(start 114.238786 -12.40028)
					(mid 114.800253 -12.961366)
					(end 115.361466 -12.400026)
				)
			)
		)
		(polygon
			(pts
				(arc
					(start 111.761524 -10.999978)
					(mid 111.200184 -10.438638)
					(end 110.638844 -10.999978)
				)
				(arc
					(start 110.638844 -12.40028)
					(mid 111.200311 -12.961366)
					(end 111.761524 -12.400026)
				)
			)
		)
		(polygon
			(pts
				(arc
					(start 108.161328 -10.999978)
					(mid 107.599988 -10.438638)
					(end 107.038648 -10.999978)
				)
				(arc
					(start 107.038648 -12.40028)
					(mid 107.600115 -12.961366)
					(end 108.161328 -12.400026)
				)
			)
		)
		(polygon
			(pts
				(arc
					(start 104.561386 -10.999978)
					(mid 104.000046 -10.438638)
					(end 103.438706 -10.999978)
				)
				(arc
					(start 103.438706 -12.40028)
					(mid 104.000173 -12.961366)
					(end 104.561386 -12.400026)
				)
			)
		)
		(polygon
			(pts
				(arc
					(start 100.961444 -10.999978)
					(mid 100.400104 -10.438638)
					(end 99.838764 -10.999978)
				)
				(arc
					(start 99.838764 -12.40028)
					(mid 100.400231 -12.961366)
					(end 100.961444 -12.400026)
				)
			)
		)
		(polygon
			(pts
				(arc
					(start 97.361502 -10.999978)
					(mid 96.800162 -10.438638)
					(end 96.238822 -10.999978)
				)
				(arc
					(start 96.238822 -12.40028)
					(mid 96.800289 -12.961366)
					(end 97.361502 -12.400026)
				)
			)
		)
		(polygon
			(pts
				(arc
					(start 93.761306 -10.999978)
					(mid 93.199966 -10.438638)
					(end 92.638626 -10.999978)
				)
				(arc
					(start 92.638626 -12.40028)
					(mid 93.200093 -12.961366)
					(end 93.761306 -12.400026)
				)
			)
		)
		(polygon
			(pts
				(arc
					(start 90.161364 -10.999978)
					(mid 89.600024 -10.438638)
					(end 89.038684 -10.999978)
				)
				(arc
					(start 89.038684 -12.40028)
					(mid 89.600151 -12.961366)
					(end 90.161364 -12.400026)
				)
			)
		)
		(polygon
			(pts
				(arc
					(start 86.561422 -10.999978)
					(mid 86.000082 -10.438638)
					(end 85.438742 -10.999978)
				)
				(arc
					(start 85.438742 -12.40028)
					(mid 86.000209 -12.961366)
					(end 86.561422 -12.400026)
				)
			)
		)
		(polygon
			(pts
				(arc
					(start 193.161158 -9.800082)
					(mid 192.599818 -9.238742)
					(end 192.038478 -9.800082)
				)
				(arc
					(start 192.038478 -11.200384)
					(mid 192.599945 -11.76147)
					(end 193.161158 -11.20013)
				)
			)
		)
		(polygon
			(pts
				(arc
					(start 189.561216 -9.800082)
					(mid 188.999876 -9.238742)
					(end 188.438536 -9.800082)
				)
				(arc
					(start 188.438536 -11.200384)
					(mid 189.000003 -11.76147)
					(end 189.561216 -11.20013)
				)
			)
		)
		(polygon
			(pts
				(arc
					(start 185.961274 -9.800082)
					(mid 185.399934 -9.238742)
					(end 184.838594 -9.800082)
				)
				(arc
					(start 184.838594 -11.200384)
					(mid 185.400061 -11.76147)
					(end 185.961274 -11.20013)
				)
			)
		)
		(polygon
			(pts
				(arc
					(start 182.361332 -9.800082)
					(mid 181.799992 -9.238742)
					(end 181.238652 -9.800082)
				)
				(arc
					(start 181.238652 -11.200384)
					(mid 181.800119 -11.76147)
					(end 182.361332 -11.20013)
				)
			)
		)
		(polygon
			(pts
				(arc
					(start 149.561296 -9.800082)
					(mid 148.999956 -9.238742)
					(end 148.438616 -9.800082)
				)
				(arc
					(start 148.438616 -11.200384)
					(mid 149.000083 -11.76147)
					(end 149.561296 -11.20013)
				)
			)
		)
		(polygon
			(pts
				(arc
					(start 145.961354 -9.800082)
					(mid 145.400014 -9.238742)
					(end 144.838674 -9.800082)
				)
				(arc
					(start 144.838674 -11.200384)
					(mid 145.400141 -11.76147)
					(end 145.961354 -11.20013)
				)
			)
		)
		(polygon
			(pts
				(arc
					(start 142.361412 -9.800082)
					(mid 141.800072 -9.238742)
					(end 141.238732 -9.800082)
				)
				(arc
					(start 141.238732 -11.200384)
					(mid 141.800199 -11.76147)
					(end 142.361412 -11.20013)
				)
			)
		)
		(polygon
			(pts
				(arc
					(start 138.76147 -9.800082)
					(mid 138.20013 -9.238742)
					(end 137.63879 -9.800082)
				)
				(arc
					(start 137.63879 -11.200384)
					(mid 138.200257 -11.76147)
					(end 138.76147 -11.20013)
				)
			)
		)
		(polygon
			(pts
				(arc
					(start 135.161528 -9.800082)
					(mid 134.600188 -9.238742)
					(end 134.038848 -9.800082)
				)
				(arc
					(start 134.038848 -11.200384)
					(mid 134.600315 -11.76147)
					(end 135.161528 -11.20013)
				)
			)
		)
		(polygon
			(pts
				(arc
					(start 131.561332 -9.800082)
					(mid 130.999992 -9.238742)
					(end 130.438652 -9.800082)
				)
				(arc
					(start 130.438652 -11.200384)
					(mid 131.000119 -11.76147)
					(end 131.561332 -11.20013)
				)
			)
		)
		(polygon
			(pts
				(arc
					(start 127.96139 -9.800082)
					(mid 127.40005 -9.238742)
					(end 126.83871 -9.800082)
				)
				(arc
					(start 126.83871 -11.200384)
					(mid 127.400177 -11.76147)
					(end 127.96139 -11.20013)
				)
			)
		)
		(polygon
			(pts
				(arc
					(start 124.361448 -9.800082)
					(mid 123.800108 -9.238742)
					(end 123.238768 -9.800082)
				)
				(arc
					(start 123.238768 -11.200384)
					(mid 123.800235 -11.76147)
					(end 124.361448 -11.20013)
				)
			)
		)
		(polygon
			(pts
				(arc
					(start 120.761506 -9.800082)
					(mid 120.200166 -9.238742)
					(end 119.638826 -9.800082)
				)
				(arc
					(start 119.638826 -11.200384)
					(mid 120.200293 -11.76147)
					(end 120.761506 -11.20013)
				)
			)
		)
		(polygon
			(pts
				(arc
					(start 117.16131 -9.800082)
					(mid 116.59997 -9.238742)
					(end 116.03863 -9.800082)
				)
				(arc
					(start 116.03863 -11.200384)
					(mid 116.600097 -11.76147)
					(end 117.16131 -11.20013)
				)
			)
		)
		(polygon
			(pts
				(arc
					(start 113.561368 -9.800082)
					(mid 113.000028 -9.238742)
					(end 112.438688 -9.800082)
				)
				(arc
					(start 112.438688 -11.200384)
					(mid 113.000155 -11.76147)
					(end 113.561368 -11.20013)
				)
			)
		)
		(polygon
			(pts
				(arc
					(start 109.961426 -9.800082)
					(mid 109.400086 -9.238742)
					(end 108.838746 -9.800082)
				)
				(arc
					(start 108.838746 -11.200384)
					(mid 109.400213 -11.76147)
					(end 109.961426 -11.20013)
				)
			)
		)
		(polygon
			(pts
				(arc
					(start 106.361484 -9.800082)
					(mid 105.800144 -9.238742)
					(end 105.238804 -9.800082)
				)
				(arc
					(start 105.238804 -11.200384)
					(mid 105.800271 -11.76147)
					(end 106.361484 -11.20013)
				)
			)
		)
		(polygon
			(pts
				(arc
					(start 102.761542 -9.800082)
					(mid 102.200202 -9.238742)
					(end 101.638862 -9.800082)
				)
				(arc
					(start 101.638862 -11.200384)
					(mid 102.200329 -11.76147)
					(end 102.761542 -11.20013)
				)
			)
		)
		(polygon
			(pts
				(arc
					(start 99.161346 -9.800082)
					(mid 98.600006 -9.238742)
					(end 98.038666 -9.800082)
				)
				(arc
					(start 98.038666 -11.200384)
					(mid 98.600133 -11.76147)
					(end 99.161346 -11.20013)
				)
			)
		)
		(polygon
			(pts
				(arc
					(start 95.561404 -9.800082)
					(mid 95.000064 -9.238742)
					(end 94.438724 -9.800082)
				)
				(arc
					(start 94.438724 -11.200384)
					(mid 95.000191 -11.76147)
					(end 95.561404 -11.20013)
				)
			)
		)
		(polygon
			(pts
				(arc
					(start 91.961462 -9.800082)
					(mid 91.400122 -9.238742)
					(end 90.838782 -9.800082)
				)
				(arc
					(start 90.838782 -11.200384)
					(mid 91.400249 -11.76147)
					(end 91.961462 -11.20013)
				)
			)
		)
		(polygon
			(pts
				(arc
					(start 88.36152 -9.800082)
					(mid 87.80018 -9.238742)
					(end 87.23884 -9.800082)
				)
				(arc
					(start 87.23884 -11.200384)
					(mid 87.800307 -11.76147)
					(end 88.36152 -11.20013)
				)
			)
		)
		(polygon
			(pts
				(arc
					(start 180.561234 -7.400036)
					(mid 179.999894 -6.838696)
					(end 179.438554 -7.400036)
				)
				(arc
					(start 179.438554 -8.800338)
					(mid 180.000021 -9.361424)
					(end 180.561234 -8.800084)
				)
			)
		)
		(polygon
			(pts
				(arc
					(start 191.361314 -3.800094)
					(mid 190.799974 -3.238754)
					(end 190.238634 -3.800094)
				)
				(arc
					(start 190.238634 -5.200396)
					(mid 190.800101 -5.761482)
					(end 191.361314 -5.200142)
				)
			)
		)
		(polygon
			(pts
				(arc
					(start 187.761118 -3.800094)
					(mid 187.199778 -3.238754)
					(end 186.638438 -3.800094)
				)
				(arc
					(start 186.638438 -5.200396)
					(mid 187.199905 -5.761482)
					(end 187.761118 -5.200142)
				)
			)
		)
		(polygon
			(pts
				(arc
					(start 184.161176 -3.800094)
					(mid 183.599836 -3.238754)
					(end 183.038496 -3.800094)
				)
				(arc
					(start 183.038496 -5.200396)
					(mid 183.599963 -5.761482)
					(end 184.161176 -5.200142)
				)
			)
		)
		(polygon
			(pts
				(arc
					(start 180.561234 -3.800094)
					(mid 179.999894 -3.238754)
					(end 179.438554 -3.800094)
				)
				(arc
					(start 179.438554 -5.200396)
					(mid 180.000021 -5.761482)
					(end 180.561234 -5.200142)
				)
			)
		)
		(polygon
			(pts
				(arc
					(start 147.761452 -3.800094)
					(mid 147.200112 -3.238754)
					(end 146.638772 -3.800094)
				)
				(arc
					(start 146.638772 -5.200396)
					(mid 147.200239 -5.761482)
					(end 147.761452 -5.200142)
				)
			)
		)
		(polygon
			(pts
				(arc
					(start 144.16151 -3.800094)
					(mid 143.60017 -3.238754)
					(end 143.03883 -3.800094)
				)
				(arc
					(start 143.03883 -5.200396)
					(mid 143.600297 -5.761482)
					(end 144.16151 -5.200142)
				)
			)
		)
		(polygon
			(pts
				(arc
					(start 140.561314 -3.800094)
					(mid 139.999974 -3.238754)
					(end 139.438634 -3.800094)
				)
				(arc
					(start 139.438634 -5.200396)
					(mid 140.000101 -5.761482)
					(end 140.561314 -5.200142)
				)
			)
		)
		(polygon
			(pts
				(arc
					(start 136.961372 -3.800094)
					(mid 136.400032 -3.238754)
					(end 135.838692 -3.800094)
				)
				(arc
					(start 135.838692 -5.200396)
					(mid 136.400159 -5.761482)
					(end 136.961372 -5.200142)
				)
			)
		)
		(polygon
			(pts
				(arc
					(start 133.36143 -3.800094)
					(mid 132.80009 -3.238754)
					(end 132.23875 -3.800094)
				)
				(arc
					(start 132.23875 -5.200396)
					(mid 132.800217 -5.761482)
					(end 133.36143 -5.200142)
				)
			)
		)
		(polygon
			(pts
				(arc
					(start 129.761488 -3.800094)
					(mid 129.200148 -3.238754)
					(end 128.638808 -3.800094)
				)
				(arc
					(start 128.638808 -5.200396)
					(mid 129.200275 -5.761482)
					(end 129.761488 -5.200142)
				)
			)
		)
		(polygon
			(pts
				(arc
					(start 126.161546 -3.800094)
					(mid 125.600206 -3.238754)
					(end 125.038866 -3.800094)
				)
				(arc
					(start 125.038866 -5.200396)
					(mid 125.600333 -5.761482)
					(end 126.161546 -5.200142)
				)
			)
		)
		(polygon
			(pts
				(arc
					(start 122.56135 -3.800094)
					(mid 122.00001 -3.238754)
					(end 121.43867 -3.800094)
				)
				(arc
					(start 121.43867 -5.200396)
					(mid 122.000137 -5.761482)
					(end 122.56135 -5.200142)
				)
			)
		)
		(polygon
			(pts
				(arc
					(start 118.961408 -3.800094)
					(mid 118.400068 -3.238754)
					(end 117.838728 -3.800094)
				)
				(arc
					(start 117.838728 -5.200396)
					(mid 118.400195 -5.761482)
					(end 118.961408 -5.200142)
				)
			)
		)
		(polygon
			(pts
				(arc
					(start 115.361466 -3.800094)
					(mid 114.800126 -3.238754)
					(end 114.238786 -3.800094)
				)
				(arc
					(start 114.238786 -5.200396)
					(mid 114.800253 -5.761482)
					(end 115.361466 -5.200142)
				)
			)
		)
		(polygon
			(pts
				(arc
					(start 111.761524 -3.800094)
					(mid 111.200184 -3.238754)
					(end 110.638844 -3.800094)
				)
				(arc
					(start 110.638844 -5.200396)
					(mid 111.200311 -5.761482)
					(end 111.761524 -5.200142)
				)
			)
		)
		(polygon
			(pts
				(arc
					(start 108.161328 -3.800094)
					(mid 107.599988 -3.238754)
					(end 107.038648 -3.800094)
				)
				(arc
					(start 107.038648 -5.200396)
					(mid 107.600115 -5.761482)
					(end 108.161328 -5.200142)
				)
			)
		)
		(polygon
			(pts
				(arc
					(start 104.561386 -3.800094)
					(mid 104.000046 -3.238754)
					(end 103.438706 -3.800094)
				)
				(arc
					(start 103.438706 -5.200396)
					(mid 104.000173 -5.761482)
					(end 104.561386 -5.200142)
				)
			)
		)
		(polygon
			(pts
				(arc
					(start 100.961444 -3.800094)
					(mid 100.400104 -3.238754)
					(end 99.838764 -3.800094)
				)
				(arc
					(start 99.838764 -5.200396)
					(mid 100.400231 -5.761482)
					(end 100.961444 -5.200142)
				)
			)
		)
		(polygon
			(pts
				(arc
					(start 97.361502 -3.800094)
					(mid 96.800162 -3.238754)
					(end 96.238822 -3.800094)
				)
				(arc
					(start 96.238822 -5.200396)
					(mid 96.800289 -5.761482)
					(end 97.361502 -5.200142)
				)
			)
		)
		(polygon
			(pts
				(arc
					(start 93.761306 -3.800094)
					(mid 93.199966 -3.238754)
					(end 92.638626 -3.800094)
				)
				(arc
					(start 92.638626 -5.200396)
					(mid 93.200093 -5.761482)
					(end 93.761306 -5.200142)
				)
			)
		)
		(polygon
			(pts
				(arc
					(start 90.161364 -3.800094)
					(mid 89.600024 -3.238754)
					(end 89.038684 -3.800094)
				)
				(arc
					(start 89.038684 -5.200396)
					(mid 89.600151 -5.761482)
					(end 90.161364 -5.200142)
				)
			)
		)
		(polygon
			(pts
				(arc
					(start 86.561422 -3.800094)
					(mid 86.000082 -3.238754)
					(end 85.438742 -3.800094)
				)
				(arc
					(start 85.438742 -5.200396)
					(mid 86.000209 -5.761482)
					(end 86.561422 -5.200142)
				)
			)
		)
		(polygon
			(pts
				(arc
					(start 193.161158 -2.600198)
					(mid 192.599818 -2.038858)
					(end 192.038478 -2.600198)
				)
				(arc
					(start 192.038478 -4.000246)
					(mid 192.599945 -4.561332)
					(end 193.161158 -3.999992)
				)
			)
		)
		(polygon
			(pts
				(arc
					(start 189.561216 -2.600198)
					(mid 188.999876 -2.038858)
					(end 188.438536 -2.600198)
				)
				(arc
					(start 188.438536 -4.000246)
					(mid 189.000003 -4.561332)
					(end 189.561216 -3.999992)
				)
			)
		)
		(polygon
			(pts
				(arc
					(start 185.961274 -2.600198)
					(mid 185.399934 -2.038858)
					(end 184.838594 -2.600198)
				)
				(arc
					(start 184.838594 -4.000246)
					(mid 185.400061 -4.561332)
					(end 185.961274 -3.999992)
				)
			)
		)
		(polygon
			(pts
				(arc
					(start 182.361332 -2.600198)
					(mid 181.799992 -2.038858)
					(end 181.238652 -2.600198)
				)
				(arc
					(start 181.238652 -4.000246)
					(mid 181.800119 -4.561332)
					(end 182.361332 -3.999992)
				)
			)
		)
		(polygon
			(pts
				(arc
					(start 149.561296 -2.600198)
					(mid 148.999956 -2.038858)
					(end 148.438616 -2.600198)
				)
				(arc
					(start 148.438616 -4.000246)
					(mid 149.000083 -4.561332)
					(end 149.561296 -3.999992)
				)
			)
		)
		(polygon
			(pts
				(arc
					(start 145.961354 -2.600198)
					(mid 145.400014 -2.038858)
					(end 144.838674 -2.600198)
				)
				(arc
					(start 144.838674 -4.000246)
					(mid 145.400141 -4.561332)
					(end 145.961354 -3.999992)
				)
			)
		)
		(polygon
			(pts
				(arc
					(start 142.361412 -2.600198)
					(mid 141.800072 -2.038858)
					(end 141.238732 -2.600198)
				)
				(arc
					(start 141.238732 -4.000246)
					(mid 141.800199 -4.561332)
					(end 142.361412 -3.999992)
				)
			)
		)
		(polygon
			(pts
				(arc
					(start 138.76147 -2.600198)
					(mid 138.20013 -2.038858)
					(end 137.63879 -2.600198)
				)
				(arc
					(start 137.63879 -4.000246)
					(mid 138.200257 -4.561332)
					(end 138.76147 -3.999992)
				)
			)
		)
		(polygon
			(pts
				(arc
					(start 135.161528 -2.600198)
					(mid 134.600188 -2.038858)
					(end 134.038848 -2.600198)
				)
				(arc
					(start 134.038848 -4.000246)
					(mid 134.600315 -4.561332)
					(end 135.161528 -3.999992)
				)
			)
		)
		(polygon
			(pts
				(arc
					(start 131.561332 -2.600198)
					(mid 130.999992 -2.038858)
					(end 130.438652 -2.600198)
				)
				(arc
					(start 130.438652 -4.000246)
					(mid 131.000119 -4.561332)
					(end 131.561332 -3.999992)
				)
			)
		)
		(polygon
			(pts
				(arc
					(start 127.96139 -2.600198)
					(mid 127.40005 -2.038858)
					(end 126.83871 -2.600198)
				)
				(arc
					(start 126.83871 -4.000246)
					(mid 127.400177 -4.561332)
					(end 127.96139 -3.999992)
				)
			)
		)
		(polygon
			(pts
				(arc
					(start 124.361448 -2.600198)
					(mid 123.800108 -2.038858)
					(end 123.238768 -2.600198)
				)
				(arc
					(start 123.238768 -4.000246)
					(mid 123.800235 -4.561332)
					(end 124.361448 -3.999992)
				)
			)
		)
		(polygon
			(pts
				(arc
					(start 120.761506 -2.600198)
					(mid 120.200166 -2.038858)
					(end 119.638826 -2.600198)
				)
				(arc
					(start 119.638826 -4.000246)
					(mid 120.200293 -4.561332)
					(end 120.761506 -3.999992)
				)
			)
		)
		(polygon
			(pts
				(arc
					(start 117.16131 -2.600198)
					(mid 116.59997 -2.038858)
					(end 116.03863 -2.600198)
				)
				(arc
					(start 116.03863 -4.000246)
					(mid 116.600097 -4.561332)
					(end 117.16131 -3.999992)
				)
			)
		)
		(polygon
			(pts
				(arc
					(start 113.561368 -2.600198)
					(mid 113.000028 -2.038858)
					(end 112.438688 -2.600198)
				)
				(arc
					(start 112.438688 -4.000246)
					(mid 113.000155 -4.561332)
					(end 113.561368 -3.999992)
				)
			)
		)
		(polygon
			(pts
				(arc
					(start 109.961426 -2.600198)
					(mid 109.400086 -2.038858)
					(end 108.838746 -2.600198)
				)
				(arc
					(start 108.838746 -4.000246)
					(mid 109.400213 -4.561332)
					(end 109.961426 -3.999992)
				)
			)
		)
		(polygon
			(pts
				(arc
					(start 106.361484 -2.600198)
					(mid 105.800144 -2.038858)
					(end 105.238804 -2.600198)
				)
				(arc
					(start 105.238804 -4.000246)
					(mid 105.800271 -4.561332)
					(end 106.361484 -3.999992)
				)
			)
		)
		(polygon
			(pts
				(arc
					(start 102.761542 -2.600198)
					(mid 102.200202 -2.038858)
					(end 101.638862 -2.600198)
				)
				(arc
					(start 101.638862 -4.000246)
					(mid 102.200329 -4.561332)
					(end 102.761542 -3.999992)
				)
			)
		)
		(polygon
			(pts
				(arc
					(start 99.161346 -2.600198)
					(mid 98.600006 -2.038858)
					(end 98.038666 -2.600198)
				)
				(arc
					(start 98.038666 -4.000246)
					(mid 98.600133 -4.561332)
					(end 99.161346 -3.999992)
				)
			)
		)
		(polygon
			(pts
				(arc
					(start 95.561404 -2.600198)
					(mid 95.000064 -2.038858)
					(end 94.438724 -2.600198)
				)
				(arc
					(start 94.438724 -4.000246)
					(mid 95.000191 -4.561332)
					(end 95.561404 -3.999992)
				)
			)
		)
		(polygon
			(pts
				(arc
					(start 91.961462 -2.600198)
					(mid 91.400122 -2.038858)
					(end 90.838782 -2.600198)
				)
				(arc
					(start 90.838782 -4.000246)
					(mid 91.400249 -4.561332)
					(end 91.961462 -3.999992)
				)
			)
		)
		(polygon
			(pts
				(arc
					(start 88.36152 -2.600198)
					(mid 87.80018 -2.038858)
					(end 87.23884 -2.600198)
				)
				(arc
					(start 87.23884 -4.000246)
					(mid 87.800307 -4.561332)
					(end 88.36152 -3.999992)
				)
			)
		)
	)
	(zone
		(layer "Cmts.User")
		(hatch none 0.5)
		(connect_pads
			(clearance 0)
		)
		(min_thickness 0.25)
		(keepout
			(tracks allowed)
			(vias allowed)
			(pads allowed)
			(copperpour allowed)
			(footprints allowed)
		)
		(placement
			(enabled no)
			(sheetname "")
		)
		(fill
			(thermal_gap 0.5)
			(thermal_bridge_width 0.5)
			(island_removal_mode 0)
		)
		(polygon
			(pts
				(xy 173.942502 -24.38527) (xy 173.942502 -22.709124) (xy 174.712376 -22.709124) (xy 174.712376 -24.38527)
			)
		)
	)
	(zone
		(layer "Cmts.User")
		(hatch none 0.5)
		(connect_pads
			(clearance 0)
		)
		(min_thickness 0.25)
		(keepout
			(tracks allowed)
			(vias allowed)
			(pads allowed)
			(copperpour allowed)
			(footprints allowed)
		)
		(placement
			(enabled no)
			(sheetname "")
		)
		(fill
			(thermal_gap 0.5)
			(thermal_bridge_width 0.5)
			(island_removal_mode 0)
		)
		(polygon
			(pts
				(xy 180.046122 -24.87549) (xy 180.046122 -23.199344) (xy 180.815996 -23.199344) (xy 180.815996 -24.87549)
			)
		)
	)
	(zone
		(layer "Cmts.User")
		(hatch none 0.5)
		(connect_pads
			(clearance 0)
		)
		(min_thickness 0.25)
		(keepout
			(tracks allowed)
			(vias allowed)
			(pads allowed)
			(copperpour allowed)
			(footprints allowed)
		)
		(placement
			(enabled no)
			(sheetname "")
		)
		(fill
			(thermal_gap 0.5)
			(thermal_bridge_width 0.5)
			(island_removal_mode 0)
		)
		(polygon
			(pts
				(xy 129.19964 -47.44847) (xy 129.19964 -45.350684) (xy 130.113786 -45.350684) (xy 130.113786 -47.44847)
			)
		)
	)
	(zone
		(layer "Cmts.User")
		(hatch none 0.5)
		(connect_pads
			(clearance 0)
		)
		(min_thickness 0.25)
		(keepout
			(tracks allowed)
			(vias allowed)
			(pads allowed)
			(copperpour allowed)
			(footprints allowed)
		)
		(placement
			(enabled no)
			(sheetname "")
		)
		(fill
			(thermal_gap 0.5)
			(thermal_bridge_width 0.5)
			(island_removal_mode 0)
		)
		(polygon
			(pts
				(xy 178.023774 -24.409908) (xy 178.023774 -22.733762) (xy 178.793648 -22.733762) (xy 178.793648 -24.409908)
			)
		)
	)
	(zone
		(layer "Cmts.User")
		(hatch none 0.5)
		(connect_pads
			(clearance 0)
		)
		(min_thickness 0.25)
		(keepout
			(tracks allowed)
			(vias allowed)
			(pads allowed)
			(copperpour allowed)
			(footprints allowed)
		)
		(placement
			(enabled no)
			(sheetname "")
		)
		(fill
			(thermal_gap 0.5)
			(thermal_bridge_width 0.5)
			(island_removal_mode 0)
		)
		(polygon
			(pts
				(xy 138.103864 -79.78648) (xy 140.04671 -79.78648) (xy 140.04671 -80.556354) (xy 138.103864 -80.556354)
			)
		)
	)
	(zone
		(layer "Cmts.User")
		(hatch none 0.5)
		(connect_pads
			(clearance 0)
		)
		(min_thickness 0.25)
		(keepout
			(tracks allowed)
			(vias allowed)
			(pads allowed)
			(copperpour allowed)
			(footprints allowed)
		)
		(placement
			(enabled no)
			(sheetname "")
		)
		(fill
			(thermal_gap 0.5)
			(thermal_bridge_width 0.5)
			(island_removal_mode 0)
		)
		(polygon
			(pts
				(xy 98.141282 -50.322226) (xy 131.877308 -50.322226) (xy 131.877308 -77.462634) (xy 125.540516 -77.462634)
				(xy 125.540516 -56.735472) (xy 98.141282 -56.735472)
			)
		)
	)
	(zone
		(layer "Cmts.User")
		(hatch none 0.5)
		(connect_pads
			(clearance 0)
		)
		(min_thickness 0.25)
		(keepout
			(tracks allowed)
			(vias allowed)
			(pads allowed)
			(copperpour allowed)
			(footprints allowed)
		)
		(placement
			(enabled no)
			(sheetname "")
		)
		(fill
			(thermal_gap 0.5)
			(thermal_bridge_width 0.5)
			(island_removal_mode 0)
		)
		(polygon
			(pts
				(xy 131.769104 -47.433484) (xy 131.769104 -45.335698) (xy 132.68325 -45.335698) (xy 132.68325 -47.433484)
			)
		)
	)
	(zone
		(layer "Cmts.User")
		(hatch none 0.5)
		(connect_pads
			(clearance 0)
		)
		(min_thickness 0.25)
		(keepout
			(tracks allowed)
			(vias allowed)
			(pads allowed)
			(copperpour allowed)
			(footprints allowed)
		)
		(placement
			(enabled no)
			(sheetname "")
		)
		(fill
			(thermal_gap 0.5)
			(thermal_bridge_width 0.5)
			(island_removal_mode 0)
		)
		(polygon
			(pts
				(xy 150.321772 -43.874182) (xy 149.885654 -45.926248) (xy 148.991574 -45.736256) (xy 149.427692 -43.68419)
			)
		)
	)
	(zone
		(layer "Cmts.User")
		(hatch none 0.5)
		(connect_pads
			(clearance 0)
		)
		(min_thickness 0.25)
		(keepout
			(tracks allowed)
			(vias allowed)
			(pads allowed)
			(copperpour allowed)
			(footprints allowed)
		)
		(placement
			(enabled no)
			(sheetname "")
		)
		(fill
			(thermal_gap 0.5)
			(thermal_bridge_width 0.5)
			(island_removal_mode 0)
		)
		(polygon
			(pts
				(xy 138.519154 -60.66409) (xy 140.61694 -60.66409) (xy 140.61694 -61.578236) (xy 138.519154 -61.578236)
			)
		)
	)
	(zone
		(layer "Cmts.User")
		(hatch none 0.5)
		(connect_pads
			(clearance 0)
		)
		(min_thickness 0.25)
		(keepout
			(tracks allowed)
			(vias allowed)
			(pads allowed)
			(copperpour allowed)
			(footprints allowed)
		)
		(placement
			(enabled no)
			(sheetname "")
		)
		(fill
			(thermal_gap 0.5)
			(thermal_bridge_width 0.5)
			(island_removal_mode 0)
		)
		(polygon
			(pts
				(xy 85.31098 -1.710436) (xy 149.622764 -1.710436) (xy 149.622764 -13.193268) (xy 85.31098 -13.193268)
			)
		)
	)
	(zone
		(layer "Cmts.User")
		(hatch none 0.5)
		(connect_pads
			(clearance 0)
		)
		(min_thickness 0.25)
		(keepout
			(tracks allowed)
			(vias allowed)
			(pads allowed)
			(copperpour allowed)
			(footprints allowed)
		)
		(placement
			(enabled no)
			(sheetname "")
		)
		(fill
			(thermal_gap 0.5)
			(thermal_bridge_width 0.5)
			(island_removal_mode 0)
		)
		(polygon
			(pts
				(xy 149.421342 -39.80307) (xy 148.98497 -41.854882) (xy 148.09089 -41.66489) (xy 148.527008 -39.613078)
			)
		)
	)
	(zone
		(layer "Cmts.User")
		(hatch none 0.5)
		(connect_pads
			(clearance 0)
		)
		(min_thickness 0.25)
		(keepout
			(tracks allowed)
			(vias allowed)
			(pads allowed)
			(copperpour allowed)
			(footprints allowed)
		)
		(placement
			(enabled no)
			(sheetname "")
		)
		(fill
			(thermal_gap 0.5)
			(thermal_bridge_width 0.5)
			(island_removal_mode 0)
		)
		(polygon
			(pts
				(xy 126.611634 -47.463202) (xy 126.611634 -45.365416) (xy 127.52578 -45.365416) (xy 127.52578 -47.463202)
			)
		)
	)
	(zone
		(layer "Cmts.User")
		(hatch none 0.5)
		(connect_pads
			(clearance 0)
		)
		(min_thickness 0.25)
		(keepout
			(tracks allowed)
			(vias allowed)
			(pads allowed)
			(copperpour allowed)
			(footprints allowed)
		)
		(placement
			(enabled no)
			(sheetname "")
		)
		(fill
			(thermal_gap 0.5)
			(thermal_bridge_width 0.5)
			(island_removal_mode 0)
		)
		(polygon
			(pts
				(xy 138.091418 -78.118208) (xy 140.034264 -78.118208) (xy 140.034264 -78.888082) (xy 138.091418 -78.888082)
			)
		)
	)
	(zone
		(layer "Cmts.User")
		(hatch none 0.5)
		(connect_pads
			(clearance 0)
		)
		(min_thickness 0.25)
		(keepout
			(tracks allowed)
			(vias allowed)
			(pads allowed)
			(copperpour allowed)
			(footprints allowed)
		)
		(placement
			(enabled no)
			(sheetname "")
		)
		(fill
			(thermal_gap 0.5)
			(thermal_bridge_width 0.5)
			(island_removal_mode 0)
		)
		(polygon
			(pts
				(xy 148.103336 -46.00702) (xy 147.667218 -48.059086) (xy 146.772884 -47.869094) (xy 147.209002 -45.817028)
			)
		)
	)
	(zone
		(layer "Cmts.User")
		(hatch none 0.5)
		(connect_pads
			(clearance 0)
		)
		(min_thickness 0.25)
		(keepout
			(tracks allowed)
			(vias allowed)
			(pads allowed)
			(copperpour allowed)
			(footprints allowed)
		)
		(placement
			(enabled no)
			(sheetname "")
		)
		(fill
			(thermal_gap 0.5)
			(thermal_bridge_width 0.5)
			(island_removal_mode 0)
		)
		(polygon
			(pts
				(xy 160.528 -54.483) (xy 160.528 -24.858218) (xy 172.614082 -24.858218) (xy 173.103794 -25.34793)
				(xy 174.173134 -25.34793) (xy 174.662846 -24.858218) (xy 179.943506 -24.858218) (xy 180.028088 -24.9428)
				(xy 180.829712 -24.9428) (xy 180.829712 -24.933656) (xy 180.90515 -24.858218) (xy 189.484 -24.858218)
				(xy 189.484 -54.483)
			)
		)
	)
	(zone
		(layer "Cmts.User")
		(hatch none 0.5)
		(connect_pads
			(clearance 0)
		)
		(min_thickness 0.25)
		(keepout
			(tracks allowed)
			(vias allowed)
			(pads allowed)
			(copperpour allowed)
			(footprints allowed)
		)
		(placement
			(enabled no)
			(sheetname "")
		)
		(fill
			(thermal_gap 0.5)
			(thermal_bridge_width 0.5)
			(island_removal_mode 0)
		)
		(polygon
			(pts
				(xy 138.084052 -76.289916) (xy 140.026898 -76.289916) (xy 140.026898 -77.05979) (xy 138.084052 -77.05979)
			)
		)
	)
	(zone
		(layer "Cmts.User")
		(hatch none 0.5)
		(connect_pads
			(clearance 0)
		)
		(min_thickness 0.25)
		(keepout
			(tracks allowed)
			(vias allowed)
			(pads allowed)
			(copperpour allowed)
			(footprints allowed)
		)
		(placement
			(enabled no)
			(sheetname "")
		)
		(fill
			(thermal_gap 0.5)
			(thermal_bridge_width 0.5)
			(island_removal_mode 0)
		)
		(polygon
			(pts
				(xy 175.984154 -24.405336) (xy 175.984154 -22.72919) (xy 176.754028 -22.72919) (xy 176.754028 -24.405336)
			)
		)
	)
	(zone
		(layer "Cmts.User")
		(hatch none 0.5)
		(connect_pads
			(clearance 0)
		)
		(min_thickness 0.25)
		(keepout
			(tracks allowed)
			(vias allowed)
			(pads allowed)
			(copperpour allowed)
			(footprints allowed)
		)
		(placement
			(enabled no)
			(sheetname "")
		)
		(fill
			(thermal_gap 0.5)
			(thermal_bridge_width 0.5)
			(island_removal_mode 0)
		)
		(polygon
			(pts
				(xy 151.802084 -37.4777) (xy 151.365966 -39.529512) (xy 150.471886 -39.33952) (xy 150.908004 -37.287454)
			)
		)
	)
	(zone
		(layer "Cmts.User")
		(hatch none 0.5)
		(connect_pads
			(clearance 0)
		)
		(min_thickness 0.25)
		(keepout
			(tracks allowed)
			(vias allowed)
			(pads allowed)
			(copperpour allowed)
			(footprints allowed)
		)
		(placement
			(enabled no)
			(sheetname "")
		)
		(fill
			(thermal_gap 0.5)
			(thermal_bridge_width 0.5)
			(island_removal_mode 0)
		)
		(polygon
			(pts
				(xy 138.963146 -58.4454) (xy 141.060932 -58.4454) (xy 141.060932 -59.359546) (xy 138.963146 -59.359546)
			)
		)
	)
	(zone
		(layer "Cmts.User")
		(hatch none 0.5)
		(connect_pads
			(clearance 0)
		)
		(min_thickness 0.25)
		(keepout
			(tracks allowed)
			(vias allowed)
			(pads allowed)
			(copperpour allowed)
			(footprints allowed)
		)
		(placement
			(enabled no)
			(sheetname "")
		)
		(fill
			(thermal_gap 0.5)
			(thermal_bridge_width 0.5)
			(island_removal_mode 0)
		)
		(polygon
			(pts
				(xy 169.83583 -24.398224) (xy 169.83583 -22.722078) (xy 170.605704 -22.722078) (xy 170.605704 -24.398224)
			)
		)
	)
	(zone
		(layer "Cmts.User")
		(hatch none 0.5)
		(connect_pads
			(clearance 0)
		)
		(min_thickness 0.25)
		(keepout
			(tracks allowed)
			(vias allowed)
			(pads allowed)
			(copperpour allowed)
			(footprints allowed)
		)
		(placement
			(enabled no)
			(sheetname "")
		)
		(fill
			(thermal_gap 0.5)
			(thermal_bridge_width 0.5)
			(island_removal_mode 0)
		)
		(polygon
			(pts
				(xy 124.211588 -47.44466) (xy 124.211588 -45.346874) (xy 125.125734 -45.346874) (xy 125.125734 -47.44466)
			)
		)
	)
	(zone
		(layer "Cmts.User")
		(hatch none 0.5)
		(connect_pads
			(clearance 0)
		)
		(min_thickness 0.25)
		(keepout
			(tracks allowed)
			(vias allowed)
			(pads allowed)
			(copperpour allowed)
			(footprints allowed)
		)
		(placement
			(enabled no)
			(sheetname "")
		)
		(fill
			(thermal_gap 0.5)
			(thermal_bridge_width 0.5)
			(island_removal_mode 0)
		)
		(polygon
			(pts
				(xy 138.27379 -64.51473) (xy 140.371576 -64.51473) (xy 140.371576 -65.428876) (xy 138.27379 -65.428876)
			)
		)
	)
	(zone
		(layer "Cmts.User")
		(hatch none 0.5)
		(connect_pads
			(clearance 0)
		)
		(min_thickness 0.25)
		(keepout
			(tracks allowed)
			(vias allowed)
			(pads allowed)
			(copperpour allowed)
			(footprints allowed)
		)
		(placement
			(enabled no)
			(sheetname "")
		)
		(fill
			(thermal_gap 0.5)
			(thermal_bridge_width 0.5)
			(island_removal_mode 0)
		)
		(polygon
			(pts
				(xy 96.52 -85.471) (xy 96.52 -48.514) (xy 133.477 -48.514) (xy 133.477 -85.471)
			)
		)
	)
	(zone
		(layer "Cmts.User")
		(hatch none 0.5)
		(connect_pads
			(clearance 0)
		)
		(min_thickness 0.25)
		(keepout
			(tracks allowed)
			(vias allowed)
			(pads allowed)
			(copperpour allowed)
			(footprints allowed)
		)
		(placement
			(enabled no)
			(sheetname "")
		)
		(fill
			(thermal_gap 0.5)
			(thermal_bridge_width 0.5)
			(island_removal_mode 0)
		)
		(polygon
			(pts
				(xy 149.147784 -49.95672) (xy 148.711412 -52.008532) (xy 147.817332 -51.81854) (xy 148.25345 -49.766728)
			)
		)
	)
	(zone
		(layer "Cmts.User")
		(hatch none 0.5)
		(connect_pads
			(clearance 0)
		)
		(min_thickness 0.25)
		(keepout
			(tracks allowed)
			(vias allowed)
			(pads allowed)
			(copperpour allowed)
			(footprints allowed)
		)
		(placement
			(enabled no)
			(sheetname "")
		)
		(fill
			(thermal_gap 0.5)
			(thermal_bridge_width 0.5)
			(island_removal_mode 0)
		)
		(polygon
			(pts
				(xy 138.250168 -62.586362) (xy 140.347954 -62.586362) (xy 140.347954 -63.500508) (xy 138.250168 -63.500508)
			)
		)
	)
	(zone
		(layer "Cmts.User")
		(hatch none 0.5)
		(connect_pads
			(clearance 0)
		)
		(min_thickness 0.25)
		(keepout
			(tracks allowed)
			(vias allowed)
			(pads allowed)
			(copperpour allowed)
			(footprints allowed)
		)
		(placement
			(enabled no)
			(sheetname "")
		)
		(fill
			(thermal_gap 0.5)
			(thermal_bridge_width 0.5)
			(island_removal_mode 0)
		)
		(polygon
			(pts
				(xy 101.310948 -103.274368) (xy 108.37672 -103.274368) (xy 108.37672 -116.343176) (xy 101.310948 -116.343176)
			)
		)
	)
	(zone
		(layer "Cmts.User")
		(hatch none 0.5)
		(connect_pads
			(clearance 0)
		)
		(min_thickness 0.25)
		(keepout
			(tracks allowed)
			(vias allowed)
			(pads allowed)
			(copperpour allowed)
			(footprints allowed)
		)
		(placement
			(enabled no)
			(sheetname "")
		)
		(fill
			(thermal_gap 0.5)
			(thermal_bridge_width 0.5)
			(island_removal_mode 0)
		)
		(polygon
			(pts
				(xy 150.212044 -53.879496) (xy 149.775926 -55.931562) (xy 148.881592 -55.74157) (xy 149.31771 -53.689504)
			)
		)
	)
	(zone
		(layer "Cmts.User")
		(hatch none 0.5)
		(connect_pads
			(clearance 0)
		)
		(min_thickness 0.25)
		(keepout
			(tracks allowed)
			(vias allowed)
			(pads allowed)
			(copperpour allowed)
			(footprints allowed)
		)
		(placement
			(enabled no)
			(sheetname "")
		)
		(fill
			(thermal_gap 0.5)
			(thermal_bridge_width 0.5)
			(island_removal_mode 0)
		)
		(polygon
			(pts
				(xy 179.310792 -1.710436) (xy 193.40703 -1.710436) (xy 193.40703 -13.193268) (xy 179.310792 -13.193268)
			)
		)
	)
	(zone
		(layer "Cmts.User")
		(hatch none 0.5)
		(connect_pads
			(clearance 0)
		)
		(min_thickness 0.25)
		(keepout
			(tracks allowed)
			(vias allowed)
			(pads allowed)
			(copperpour allowed)
			(footprints allowed)
		)
		(placement
			(enabled no)
			(sheetname "")
		)
		(fill
			(thermal_gap 0.5)
			(thermal_bridge_width 0.5)
			(island_removal_mode 0)
		)
		(polygon
			(pts
				(xy 167.75303 -24.40559) (xy 167.75303 -22.729444) (xy 168.522904 -22.729444) (xy 168.522904 -24.40559)
			)
		)
	)
	(zone
		(layer "Cmts.User")
		(hatch none 0.5)
		(connect_pads
			(clearance 0)
		)
		(min_thickness 0.25)
		(keepout
			(tracks allowed)
			(vias allowed)
			(pads allowed)
			(copperpour allowed)
			(footprints allowed)
		)
		(placement
			(enabled no)
			(sheetname "")
		)
		(fill
			(thermal_gap 0.5)
			(thermal_bridge_width 0.5)
			(island_removal_mode 0)
		)
		(polygon
			(pts
				(xy 160.00603 -19.097244) (xy 161.682176 -19.097244) (xy 161.682176 -19.867118) (xy 160.00603 -19.867118)
			)
		)
	)
	(zone
		(layer "Cmts.User")
		(hatch none 0.5)
		(connect_pads
			(clearance 0)
		)
		(min_thickness 0.25)
		(keepout
			(tracks allowed)
			(vias allowed)
			(pads allowed)
			(copperpour allowed)
			(footprints allowed)
		)
		(placement
			(enabled no)
			(sheetname "")
		)
		(fill
			(thermal_gap 0.5)
			(thermal_bridge_width 0.5)
			(island_removal_mode 0)
		)
		(polygon
			(pts
				(xy 171.874688 -24.395176) (xy 171.874688 -22.71903) (xy 172.644562 -22.71903) (xy 172.644562 -24.395176)
			)
		)
	)
	(zone
		(layer "Cmts.User")
		(hatch none 0.5)
		(connect_pads
			(clearance 0)
		)
		(min_thickness 0.25)
		(keepout
			(tracks allowed)
			(vias allowed)
			(pads allowed)
			(copperpour allowed)
			(footprints allowed)
		)
		(placement
			(enabled no)
			(sheetname "")
		)
		(fill
			(thermal_gap 0.5)
			(thermal_bridge_width 0.5)
			(island_removal_mode 0)
		)
		(polygon
			(pts
				(xy 147.084542 -31.916878) (xy 146.648424 -33.968944) (xy 145.754344 -33.778698) (xy 146.190462 -31.726886)
			)
		)
	)
	(zone
		(layer "Cmts.User")
		(hatch none 0.5)
		(connect_pads
			(clearance 0)
		)
		(min_thickness 0.25)
		(keepout
			(tracks allowed)
			(vias allowed)
			(pads allowed)
			(copperpour allowed)
			(footprints allowed)
		)
		(placement
			(enabled no)
			(sheetname "")
		)
		(fill
			(thermal_gap 0.5)
			(thermal_bridge_width 0.5)
			(island_removal_mode 0)
		)
		(polygon
			(pts
				(xy 138.441176 -81.921858) (xy 140.384022 -81.921858) (xy 140.384022 -82.691732) (xy 138.441176 -82.691732)
			)
		)
	)
	(zone
		(layer "Cmts.User")
		(hatch none 0.5)
		(connect_pads
			(clearance 0)
		)
		(min_thickness 0.25)
		(keepout
			(tracks allowed)
			(vias allowed)
			(pads allowed)
			(copperpour allowed)
			(footprints allowed)
		)
		(placement
			(enabled no)
			(sheetname "")
		)
		(fill
			(thermal_gap 0.5)
			(thermal_bridge_width 0.5)
			(island_removal_mode 0)
		)
		(polygon
			(pts
				(xy 165.965886 -24.435816) (xy 165.965886 -22.75967) (xy 166.73576 -22.75967) (xy 166.73576 -24.435816)
			)
		)
	)
	(zone
		(layer "Cmts.User")
		(hatch none 0.5)
		(connect_pads
			(clearance 0)
		)
		(min_thickness 0.25)
		(keepout
			(tracks allowed)
			(vias allowed)
			(pads allowed)
			(copperpour allowed)
			(footprints allowed)
		)
		(placement
			(enabled no)
			(sheetname "")
		)
		(fill
			(thermal_gap 0.5)
			(thermal_bridge_width 0.5)
			(island_removal_mode 0)
		)
		(polygon
			(pts
				(xy 149.916134 -34.747454) (xy 149.480016 -36.79952) (xy 148.585936 -36.609274) (xy 149.022054 -34.557462)
			)
		)
	)
)
